( 
	(global
		("VARIANT_NAME" "ONSEMI")
		("VARIANT_VIEW" "schonsemi_1")
		("VARIANT_DESCRIPTION" "")
	)
	(modules
		"@s9s_mb_2u_lib.s9s_mb_2u(sch_1)"
	)
	(options
		("VARIANT_PROP" "VARIANT")
		("VARIANT_DNI" "DNI")
		("VARIANT_DESIGNATOR" "*")
	)
	(props
		("@s9s_mb_2u_lib.s9s_mb_2u(sch_1):page446_i225@pure_quanta.isl69260irazt(chips)"
			("VARIANT" "*")
			("VALUE" "FD5001")
			("PART_TYPE" "SMLF")
			("MATERIAL" "IC")
			("PART_NUMBER" "AL005001004")
			("STANDARD" "")
			("LIFECYCLE" "")
			("JEDEC_TYPE" "VFQFPN40_TH_0-4_5X5XC")
			("DESCRIPTION" "IC OTHER(40P) FD5001(QFN)")
			("MANUFTR" "ONS")
			("MANUF_PN" "FD5001")
			("RD_CMPLS_LVL" "EP(V1)")
			("CMPLS_LVL" "")
			("FROM_PJ" "S9S-KIMI")
			("CLASS" "IC")
			("DIP_SMD" "")
			("DATA" "ONS_FD5001.pdf")
			("EE_CHECK_LIST" "")
			("FP_ECN" "FD5001.msg")
			("PSL" "")
			("CREATOR" "")
			("STATUS" "")
			("MSD" "NA")
			("ESD_CDM" "NA")
			("ESD_HBM" "NA")
			("ESD_MM" "NA")
			("PIN_LENGTH_SHORT_PIN" "0 MILS")
			("PIN_LENGTH_LONG_PIN" "0 MILS")
			("CREATEDAY" "20200421")
			("LOCATION" "PU32")
		)
		("@s9s_mb_2u_lib.s9s_mb_2u(sch_1):page433_i172@pure_quanta.isl69260irazt(chips)"
			("VARIANT" "*")
			("VALUE" "FD5001")
			("PART_TYPE" "SMLF")
			("MATERIAL" "IC")
			("PART_NUMBER" "AL005001004")
			("STANDARD" "")
			("LIFECYCLE" "")
			("JEDEC_TYPE" "VFQFPN40_TH_0-4_5X5XC")
			("DESCRIPTION" "IC OTHER(40P) FD5001(QFN)")
			("MANUFTR" "ONS")
			("MANUF_PN" "FD5001")
			("RD_CMPLS_LVL" "EP(V1)")
			("CMPLS_LVL" "")
			("FROM_PJ" "S9S-KIMI")
			("CLASS" "IC")
			("DIP_SMD" "")
			("DATA" "ONS_FD5001.pdf")
			("EE_CHECK_LIST" "")
			("FP_ECN" "FD5001.msg")
			("PSL" "")
			("CREATOR" "")
			("STATUS" "")
			("MSD" "NA")
			("ESD_CDM" "NA")
			("ESD_HBM" "NA")
			("ESD_MM" "NA")
			("PIN_LENGTH_SHORT_PIN" "0 MILS")
			("PIN_LENGTH_LONG_PIN" "0 MILS")
			("CREATEDAY" "20200421")
			("LOCATION" "PU29")
		)
		("@s9s_mb_2u_lib.s9s_mb_2u(sch_1):page591_i412@pure_quanta.isl69260irazt(chips)"
			("VARIANT" "*")
			("VALUE" "FD5001")
			("PART_TYPE" "SMLF")
			("MATERIAL" "IC")
			("PART_NUMBER" "AL005001004")
			("STANDARD" "")
			("LIFECYCLE" "")
			("JEDEC_TYPE" "VFQFPN40_TH_0-4_5X5XC")
			("DESCRIPTION" "IC OTHER(40P) FD5001(QFN)")
			("MANUFTR" "ONS")
			("MANUF_PN" "FD5001")
			("RD_CMPLS_LVL" "EP(V1)")
			("CMPLS_LVL" "")
			("FROM_PJ" "S9S-KIMI")
			("CLASS" "IC")
			("DIP_SMD" "")
			("DATA" "ONS_FD5001.pdf")
			("EE_CHECK_LIST" "")
			("FP_ECN" "FD5001.msg")
			("PSL" "")
			("CREATOR" "")
			("STATUS" "")
			("MSD" "NA")
			("ESD_CDM" "NA")
			("ESD_HBM" "NA")
			("ESD_MM" "NA")
			("PIN_LENGTH_SHORT_PIN" "0 MILS")
			("PIN_LENGTH_LONG_PIN" "0 MILS")
			("CREATEDAY" "20200421")
			("LOCATION" "PU22")
		)
		("@s9s_mb_2u_lib.s9s_mb_2u(sch_1):page597_i220@pure_quanta.isl69260irazt(chips)"
			("VARIANT" "*")
			("VALUE" "FD5001")
			("PART_TYPE" "SMLF")
			("MATERIAL" "IC")
			("PART_NUMBER" "AL005001004")
			("STANDARD" "")
			("LIFECYCLE" "")
			("JEDEC_TYPE" "VFQFPN40_TH_0-4_5X5XC")
			("DESCRIPTION" "IC OTHER(40P) FD5001(QFN)")
			("MANUFTR" "ONS")
			("MANUF_PN" "FD5001")
			("RD_CMPLS_LVL" "EP(V1)")
			("CMPLS_LVL" "")
			("FROM_PJ" "S9S-KIMI")
			("CLASS" "IC")
			("DIP_SMD" "")
			("DATA" "ONS_FD5001.pdf")
			("EE_CHECK_LIST" "")
			("FP_ECN" "FD5001.msg")
			("PSL" "")
			("CREATOR" "")
			("STATUS" "")
			("MSD" "NA")
			("ESD_CDM" "NA")
			("ESD_HBM" "NA")
			("ESD_MM" "NA")
			("PIN_LENGTH_SHORT_PIN" "0 MILS")
			("PIN_LENGTH_LONG_PIN" "0 MILS")
			("CREATEDAY" "20200421")
			("LOCATION" "PU21")
		)
		("@s9s_mb_2u_lib.s9s_mb_2u(sch_1):page602_i194@pure_quanta.isl69260irazt(chips)"
			("VARIANT" "*")
			("VALUE" "FD5001")
			("PART_TYPE" "SMLF")
			("MATERIAL" "IC")
			("PART_NUMBER" "AL005001004")
			("STANDARD" "")
			("LIFECYCLE" "")
			("JEDEC_TYPE" "VFQFPN40_TH_0-4_5X5XC")
			("DESCRIPTION" "IC OTHER(40P) FD5001(QFN)")
			("MANUFTR" "ONS")
			("MANUF_PN" "FD5001")
			("RD_CMPLS_LVL" "EP(V1)")
			("CMPLS_LVL" "")
			("FROM_PJ" "S9S-KIMI")
			("CLASS" "IC")
			("DIP_SMD" "")
			("DATA" "ONS_FD5001.pdf")
			("EE_CHECK_LIST" "")
			("FP_ECN" "FD5001.msg")
			("PSL" "")
			("CREATOR" "")
			("STATUS" "")
			("MSD" "NA")
			("ESD_CDM" "NA")
			("ESD_HBM" "NA")
			("ESD_MM" "NA")
			("PIN_LENGTH_SHORT_PIN" "0 MILS")
			("PIN_LENGTH_LONG_PIN" "0 MILS")
			("CREATEDAY" "20200421")
			("LOCATION" "PU18")
		)
		("@s9s_mb_2u_lib.s9s_mb_2u(sch_1):page583_i188@pure_quanta.isl69260irazt(chips)"
			("VARIANT" "*")
			("PART_TYPE" "SMLF")
			("MATERIAL" "IC")
			("VALUE" "FD5001")
			("PART_NUMBER" "AL005001004")
			("PIN_LENGTH_LONG_PIN" "0 MILS")
			("MSD" "NA")
			("DESCRIPTION" "IC OTHER(40P) FD5001(QFN)")
			("EE_CHECK_LIST" "")
			("CLASS" "IC")
			("MANUFTR" "ONS")
			("ESD_MM" "NA")
			("ESD_CDM" "NA")
			("FROM_PJ" "S9S-KIMI")
			("DIP_SMD" "")
			("CREATEDAY" "20200421")
			("STANDARD" "")
			("PIN_LENGTH_SHORT_PIN" "0 MILS")
			("ESD_HBM" "NA")
			("LIFECYCLE" "")
			("STATUS" "")
			("PSL" "")
			("RD_CMPLS_LVL" "EP(V1)")
			("FP_ECN" "FD5001.msg")
			("MANUF_PN" "FD5001")
			("CMPLS_LVL" "")
			("JEDEC_TYPE" "VFQFPN40_TH_0-4_5X5XC")
			("DATA" "ONS_FD5001.pdf")
			("CREATOR" "")
			("LOCATION" "PU14")
		)
		("@s9s_mb_2u_lib.s9s_mb_2u(sch_1):page452_i196@pure_quanta.isl69260irazt(chips)"
			("VARIANT" "*")
			("VALUE" "FD5001")
			("PART_TYPE" "SMLF")
			("MATERIAL" "IC")
			("PART_NUMBER" "AL005001004")
			("STANDARD" "")
			("LIFECYCLE" "")
			("JEDEC_TYPE" "VFQFPN40_TH_0-4_5X5XC")
			("DESCRIPTION" "IC OTHER(40P) FD5001(QFN)")
			("MANUFTR" "ONS")
			("MANUF_PN" "FD5001")
			("RD_CMPLS_LVL" "EP(V1)")
			("CMPLS_LVL" "")
			("FROM_PJ" "S9S-KIMI")
			("CLASS" "IC")
			("DIP_SMD" "")
			("DATA" "ONS_FD5001.pdf")
			("EE_CHECK_LIST" "")
			("FP_ECN" "FD5001.msg")
			("PSL" "")
			("CREATOR" "")
			("STATUS" "")
			("MSD" "NA")
			("ESD_CDM" "NA")
			("ESD_HBM" "NA")
			("ESD_MM" "NA")
			("PIN_LENGTH_SHORT_PIN" "0 MILS")
			("PIN_LENGTH_LONG_PIN" "0 MILS")
			("CREATEDAY" "20200421")
			("LOCATION" "PU35")
		)
		("@s9s_mb_2u_lib.s9s_mb_2u(sch_1):page453_i166@pure_quanta.q_cap(chips)"
			("VARIANT" "*")
			("VALUE" "0.1UF")
			("VOLTAGE" "25V")
			("TOLERANCE" "10%")
			("PACK_TYPE" "0402")
			("MATERIAL" "EMPTY")
			("PART_NUMBER" "CH4104K1B00")
			("STANDARD" "")
			("LIFECYCLE" "")
			("ASS_PART" "")
			("JEDEC_TYPE" "C0402")
			("ALT_SYMBOLS" "(C0402_OCTAGONXA,C0402-0201)")
			("RATED_VOLTAGE" "25V")
			("TOL" "10%")
			("CLASS" "IO")
			("DESCRIPTION" "CAP CHIP 0.1U 25V(+-10%,X7R,0402)")
			("COMPONENT_TYPE" "CHIP0402")
			("LEAD_LENGTH" "")
			("LPID" "")
			("DATE" "20160113")
			("LOCATION" "PC1354")
		)
		("@s9s_mb_2u_lib.s9s_mb_2u(sch_1):page447_i100@pure_quanta.q_cap(chips)"
			("VARIANT" "*")
			("VALUE" "0.1UF")
			("VOLTAGE" "25V")
			("TOLERANCE" "10%")
			("PACK_TYPE" "0402")
			("MATERIAL" "EMPTY")
			("PART_NUMBER" "CH4104K1B00")
			("STANDARD" "")
			("LIFECYCLE" "")
			("ASS_PART" "")
			("JEDEC_TYPE" "C0402")
			("ALT_SYMBOLS" "(C0402_OCTAGONXA,C0402-0201)")
			("RATED_VOLTAGE" "25V")
			("TOL" "10%")
			("CLASS" "IO")
			("DESCRIPTION" "CAP CHIP 0.1U 25V(+-10%,X7R,0402)")
			("COMPONENT_TYPE" "CHIP0402")
			("LEAD_LENGTH" "")
			("LPID" "")
			("DATE" "20160113")
			("LOCATION" "PC1350")
		)
		("@s9s_mb_2u_lib.s9s_mb_2u(sch_1):page447_i98@pure_quanta.q_cap(chips)"
			("VARIANT" "*")
			("VALUE" "0.1UF")
			("VOLTAGE" "25V")
			("TOLERANCE" "10%")
			("PACK_TYPE" "0402")
			("MATERIAL" "EMPTY")
			("PART_NUMBER" "CH4104K1B00")
			("STANDARD" "")
			("LIFECYCLE" "")
			("ASS_PART" "")
			("JEDEC_TYPE" "C0402")
			("ALT_SYMBOLS" "(C0402_OCTAGONXA,C0402-0201)")
			("RATED_VOLTAGE" "25V")
			("TOL" "10%")
			("CLASS" "IO")
			("DESCRIPTION" "CAP CHIP 0.1U 25V(+-10%,X7R,0402)")
			("COMPONENT_TYPE" "CHIP0402")
			("LEAD_LENGTH" "")
			("LPID" "")
			("DATE" "20160113")
			("LOCATION" "PC1349")
		)
		("@s9s_mb_2u_lib.s9s_mb_2u(sch_1):page587_i89@pure_quanta.q_cap(chips)"
			("VARIANT" "*")
			("VALUE" "0.1UF")
			("VOLTAGE" "25V")
			("TOLERANCE" "10%")
			("PACK_TYPE" "0402")
			("MATERIAL" "EMPTY")
			("PART_NUMBER" "CH4104K1B00")
			("STANDARD" "")
			("LIFECYCLE" "")
			("ASS_PART" "")
			("JEDEC_TYPE" "C0402")
			("ALT_SYMBOLS" "(C0402_OCTAGONXA,C0402-0201)")
			("RATED_VOLTAGE" "25V")
			("TOL" "10%")
			("CLASS" "IO")
			("DESCRIPTION" "CAP CHIP 0.1U 25V(+-10%,X7R,0402)")
			("COMPONENT_TYPE" "CHIP0402")
			("LEAD_LENGTH" "")
			("LPID" "")
			("DATE" "20160113")
			("LOCATION" "PC1359")
		)
		("@s9s_mb_2u_lib.s9s_mb_2u(sch_1):page587_i91@pure_quanta.q_cap(chips)"
			("VARIANT" "*")
			("VALUE" "0.1UF")
			("VOLTAGE" "25V")
			("TOLERANCE" "10%")
			("PACK_TYPE" "0402")
			("MATERIAL" "EMPTY")
			("PART_NUMBER" "CH4104K1B00")
			("STANDARD" "")
			("LIFECYCLE" "")
			("ASS_PART" "")
			("JEDEC_TYPE" "C0402")
			("ALT_SYMBOLS" "(C0402_OCTAGONXA,C0402-0201)")
			("RATED_VOLTAGE" "25V")
			("TOL" "10%")
			("CLASS" "IO")
			("DESCRIPTION" "CAP CHIP 0.1U 25V(+-10%,X7R,0402)")
			("COMPONENT_TYPE" "CHIP0402")
			("LEAD_LENGTH" "")
			("LPID" "")
			("DATE" "20160113")
			("LOCATION" "PC1358")
		)
		("@s9s_mb_2u_lib.s9s_mb_2u(sch_1):page588_i76@pure_quanta.q_cap(chips)"
			("VARIANT" "*")
			("VALUE" "0.1UF")
			("VOLTAGE" "25V")
			("TOLERANCE" "10%")
			("PACK_TYPE" "0402")
			("MATERIAL" "EMPTY")
			("PART_NUMBER" "CH4104K1B00")
			("STANDARD" "")
			("LIFECYCLE" "")
			("ASS_PART" "")
			("JEDEC_TYPE" "C0402")
			("ALT_SYMBOLS" "(C0402_OCTAGONXA,C0402-0201)")
			("RATED_VOLTAGE" "25V")
			("TOL" "10%")
			("CLASS" "IO")
			("DESCRIPTION" "CAP CHIP 0.1U 25V(+-10%,X7R,0402)")
			("COMPONENT_TYPE" "CHIP0402")
			("LEAD_LENGTH" "")
			("LPID" "")
			("DATE" "20160113")
			("LOCATION" "PC1361")
		)
		("@s9s_mb_2u_lib.s9s_mb_2u(sch_1):page588_i78@pure_quanta.q_cap(chips)"
			("VARIANT" "*")
			("VALUE" "0.1UF")
			("VOLTAGE" "25V")
			("TOLERANCE" "10%")
			("PACK_TYPE" "0402")
			("MATERIAL" "EMPTY")
			("PART_NUMBER" "CH4104K1B00")
			("STANDARD" "")
			("LIFECYCLE" "")
			("ASS_PART" "")
			("JEDEC_TYPE" "C0402")
			("ALT_SYMBOLS" "(C0402_OCTAGONXA,C0402-0201)")
			("RATED_VOLTAGE" "25V")
			("TOL" "10%")
			("CLASS" "IO")
			("DESCRIPTION" "CAP CHIP 0.1U 25V(+-10%,X7R,0402)")
			("COMPONENT_TYPE" "CHIP0402")
			("LEAD_LENGTH" "")
			("LPID" "")
			("DATE" "20160113")
			("LOCATION" "PC1360")
		)
		("@s9s_mb_2u_lib.s9s_mb_2u(sch_1):page589_i78@pure_quanta.q_cap(chips)"
			("VARIANT" "*")
			("VALUE" "0.1UF")
			("VOLTAGE" "25V")
			("TOLERANCE" "10%")
			("PACK_TYPE" "0402")
			("MATERIAL" "EMPTY")
			("PART_NUMBER" "CH4104K1B00")
			("STANDARD" "")
			("LIFECYCLE" "")
			("ASS_PART" "")
			("JEDEC_TYPE" "C0402")
			("ALT_SYMBOLS" "(C0402_OCTAGONXA,C0402-0201)")
			("RATED_VOLTAGE" "25V")
			("TOL" "10%")
			("CLASS" "IO")
			("DESCRIPTION" "CAP CHIP 0.1U 25V(+-10%,X7R,0402)")
			("COMPONENT_TYPE" "CHIP0402")
			("LEAD_LENGTH" "")
			("LPID" "")
			("DATE" "20160113")
			("LOCATION" "PC1363")
		)
		("@s9s_mb_2u_lib.s9s_mb_2u(sch_1):page589_i76@pure_quanta.q_cap(chips)"
			("VARIANT" "*")
			("VALUE" "0.1UF")
			("VOLTAGE" "25V")
			("TOLERANCE" "10%")
			("PACK_TYPE" "0402")
			("MATERIAL" "EMPTY")
			("PART_NUMBER" "CH4104K1B00")
			("STANDARD" "")
			("LIFECYCLE" "")
			("ASS_PART" "")
			("JEDEC_TYPE" "C0402")
			("ALT_SYMBOLS" "(C0402_OCTAGONXA,C0402-0201)")
			("RATED_VOLTAGE" "25V")
			("TOL" "10%")
			("CLASS" "IO")
			("DESCRIPTION" "CAP CHIP 0.1U 25V(+-10%,X7R,0402)")
			("COMPONENT_TYPE" "CHIP0402")
			("LEAD_LENGTH" "")
			("LPID" "")
			("DATE" "20160113")
			("LOCATION" "PC1362")
		)
		("@s9s_mb_2u_lib.s9s_mb_2u(sch_1):page593_i221@pure_quanta.q_cap(chips)"
			("VARIANT" "*")
			("VALUE" "0.1UF")
			("VOLTAGE" "25V")
			("TOLERANCE" "10%")
			("PACK_TYPE" "0402")
			("MATERIAL" "EMPTY")
			("PART_NUMBER" "CH4104K1B00")
			("STANDARD" "")
			("LIFECYCLE" "")
			("ASS_PART" "")
			("JEDEC_TYPE" "C0402")
			("ALT_SYMBOLS" "(C0402_OCTAGONXA,C0402-0201)")
			("RATED_VOLTAGE" "25V")
			("TOL" "10%")
			("CLASS" "IO")
			("DESCRIPTION" "CAP CHIP 0.1U 25V(+-10%,X7R,0402)")
			("COMPONENT_TYPE" "CHIP0402")
			("LEAD_LENGTH" "")
			("LPID" "")
			("DATE" "20160113")
			("LOCATION" "PC1365")
		)
		("@s9s_mb_2u_lib.s9s_mb_2u(sch_1):page593_i223@pure_quanta.q_cap(chips)"
			("VARIANT" "*")
			("VALUE" "0.1UF")
			("VOLTAGE" "25V")
			("TOLERANCE" "10%")
			("PACK_TYPE" "0402")
			("MATERIAL" "EMPTY")
			("PART_NUMBER" "CH4104K1B00")
			("STANDARD" "")
			("LIFECYCLE" "")
			("ASS_PART" "")
			("JEDEC_TYPE" "C0402")
			("ALT_SYMBOLS" "(C0402_OCTAGONXA,C0402-0201)")
			("RATED_VOLTAGE" "25V")
			("TOL" "10%")
			("CLASS" "IO")
			("DESCRIPTION" "CAP CHIP 0.1U 25V(+-10%,X7R,0402)")
			("COMPONENT_TYPE" "CHIP0402")
			("LEAD_LENGTH" "")
			("LPID" "")
			("DATE" "20160113")
			("LOCATION" "PC1364")
		)
		("@s9s_mb_2u_lib.s9s_mb_2u(sch_1):page595_i52@pure_quanta.q_cap(chips)"
			("VARIANT" "*")
			("VALUE" "0.1UF")
			("VOLTAGE" "25V")
			("TOLERANCE" "10%")
			("PACK_TYPE" "0402")
			("MATERIAL" "EMPTY")
			("PART_NUMBER" "CH4104K1B00")
			("STANDARD" "")
			("LIFECYCLE" "")
			("ASS_PART" "")
			("JEDEC_TYPE" "C0402")
			("ALT_SYMBOLS" "(C0402_OCTAGONXA,C0402-0201)")
			("RATED_VOLTAGE" "25V")
			("TOL" "10%")
			("CLASS" "IO")
			("DESCRIPTION" "CAP CHIP 0.1U 25V(+-10%,X7R,0402)")
			("COMPONENT_TYPE" "CHIP0402")
			("LEAD_LENGTH" "")
			("LPID" "")
			("DATE" "20160113")
			("LOCATION" "PC1366")
		)
		("@s9s_mb_2u_lib.s9s_mb_2u(sch_1):page599_i102@pure_quanta.q_cap(chips)"
			("VARIANT" "*")
			("VALUE" "0.1UF")
			("VOLTAGE" "25V")
			("TOLERANCE" "10%")
			("PACK_TYPE" "0402")
			("MATERIAL" "EMPTY")
			("PART_NUMBER" "CH4104K1B00")
			("STANDARD" "")
			("LIFECYCLE" "")
			("ASS_PART" "")
			("JEDEC_TYPE" "C0402")
			("ALT_SYMBOLS" "(C0402_OCTAGONXA,C0402-0201)")
			("RATED_VOLTAGE" "25V")
			("TOL" "10%")
			("CLASS" "IO")
			("DESCRIPTION" "CAP CHIP 0.1U 25V(+-10%,X7R,0402)")
			("COMPONENT_TYPE" "CHIP0402")
			("LEAD_LENGTH" "")
			("LPID" "")
			("DATE" "20160113")
			("LOCATION" "PC1370")
		)
		("@s9s_mb_2u_lib.s9s_mb_2u(sch_1):page599_i99@pure_quanta.q_cap(chips)"
			("VARIANT" "*")
			("VALUE" "0.1UF")
			("VOLTAGE" "25V")
			("TOLERANCE" "10%")
			("PACK_TYPE" "0402")
			("MATERIAL" "EMPTY")
			("PART_NUMBER" "CH4104K1B00")
			("STANDARD" "")
			("LIFECYCLE" "")
			("ASS_PART" "")
			("JEDEC_TYPE" "C0402")
			("ALT_SYMBOLS" "(C0402_OCTAGONXA,C0402-0201)")
			("RATED_VOLTAGE" "25V")
			("TOL" "10%")
			("CLASS" "IO")
			("DESCRIPTION" "CAP CHIP 0.1U 25V(+-10%,X7R,0402)")
			("COMPONENT_TYPE" "CHIP0402")
			("LEAD_LENGTH" "")
			("LPID" "")
			("DATE" "20160113")
			("LOCATION" "PC1369")
		)
		("@s9s_mb_2u_lib.s9s_mb_2u(sch_1):page598_i96@pure_quanta.q_cap(chips)"
			("VARIANT" "*")
			("VALUE" "0.1UF")
			("VOLTAGE" "25V")
			("TOLERANCE" "10%")
			("PACK_TYPE" "0402")
			("MATERIAL" "EMPTY")
			("PART_NUMBER" "CH4104K1B00")
			("STANDARD" "")
			("LIFECYCLE" "")
			("ASS_PART" "")
			("JEDEC_TYPE" "C0402")
			("ALT_SYMBOLS" "(C0402_OCTAGONXA,C0402-0201)")
			("RATED_VOLTAGE" "25V")
			("TOL" "10%")
			("CLASS" "IO")
			("DESCRIPTION" "CAP CHIP 0.1U 25V(+-10%,X7R,0402)")
			("COMPONENT_TYPE" "CHIP0402")
			("LEAD_LENGTH" "")
			("LPID" "")
			("DATE" "20160113")
			("LOCATION" "PC1368")
		)
		("@s9s_mb_2u_lib.s9s_mb_2u(sch_1):page598_i94@pure_quanta.q_cap(chips)"
			("VARIANT" "*")
			("VALUE" "0.1UF")
			("VOLTAGE" "25V")
			("TOLERANCE" "10%")
			("PACK_TYPE" "0402")
			("MATERIAL" "EMPTY")
			("PART_NUMBER" "CH4104K1B00")
			("STANDARD" "")
			("LIFECYCLE" "")
			("ASS_PART" "")
			("JEDEC_TYPE" "C0402")
			("ALT_SYMBOLS" "(C0402_OCTAGONXA,C0402-0201)")
			("RATED_VOLTAGE" "25V")
			("TOL" "10%")
			("CLASS" "IO")
			("DESCRIPTION" "CAP CHIP 0.1U 25V(+-10%,X7R,0402)")
			("COMPONENT_TYPE" "CHIP0402")
			("LEAD_LENGTH" "")
			("LPID" "")
			("DATE" "20160113")
			("LOCATION" "PC1367")
		)
		("@s9s_mb_2u_lib.s9s_mb_2u(sch_1):page602_i108@pure_quanta.q_cap(chips)"
			("VARIANT" "*")
			("VALUE" "1UF")
			("VOLTAGE" "16V")
			("TOLERANCE" "10%")
			("PACK_TYPE" "C0402")
			("MATERIAL" "X6S")
			("PART_NUMBER" "CH5103KEB01")
			("STANDARD" "")
			("LIFECYCLE" "")
			("ASS_PART" "")
			("JEDEC_TYPE" "C0402")
			("ALT_SYMBOLS" "(C0402-0201)")
			("RATED_VOLTAGE" "16V")
			("TOL" "10%")
			("CLASS" "DISCRETE")
			("DESCRIPTION" "CAP CHIP 1UF 16V(10%,X6S,0402)")
			("COMPONENT_TYPE" "CHIP0402")
			("LEAD_LENGTH" "")
			("LPID" "")
			("DATE" "20140828")
			("LOCATION" "PC390")
		)
		("@s9s_mb_2u_lib.s9s_mb_2u(sch_1):page602_i105@pure_quanta.q_cap(chips)"
			("VARIANT" "*")
			("VALUE" "1UF")
			("VOLTAGE" "16V")
			("TOLERANCE" "10%")
			("PACK_TYPE" "C0402")
			("MATERIAL" "X6S")
			("PART_NUMBER" "CH5103KEB01")
			("STANDARD" "")
			("LIFECYCLE" "")
			("ASS_PART" "")
			("JEDEC_TYPE" "C0402")
			("ALT_SYMBOLS" "(C0402-0201)")
			("RATED_VOLTAGE" "16V")
			("TOL" "10%")
			("CLASS" "DISCRETE")
			("DESCRIPTION" "CAP CHIP 1UF 16V(10%,X6S,0402)")
			("COMPONENT_TYPE" "CHIP0402")
			("LEAD_LENGTH" "")
			("LPID" "")
			("DATE" "20140828")
			("LOCATION" "PC386")
		)
		("@s9s_mb_2u_lib.s9s_mb_2u(sch_1):page603_i166@pure_quanta.q_cap(chips)"
			("VARIANT" "*")
			("VALUE" "0.1UF")
			("VOLTAGE" "25V")
			("TOLERANCE" "10%")
			("PACK_TYPE" "0402")
			("MATERIAL" "EMPTY")
			("PART_NUMBER" "CH4104K1B00")
			("STANDARD" "")
			("LIFECYCLE" "")
			("ASS_PART" "")
			("JEDEC_TYPE" "C0402")
			("ALT_SYMBOLS" "(C0402_OCTAGONXA,C0402-0201)")
			("RATED_VOLTAGE" "25V")
			("TOL" "10%")
			("CLASS" "IO")
			("DESCRIPTION" "CAP CHIP 0.1U 25V(+-10%,X7R,0402)")
			("COMPONENT_TYPE" "CHIP0402")
			("LEAD_LENGTH" "")
			("LPID" "")
			("DATE" "20160113")
			("LOCATION" "PC1371")
		)
		("@s9s_mb_2u_lib.s9s_mb_2u(sch_1):page585_i158@pure_quanta.q_cap(chips)"
			("VARIANT" "*")
			("VALUE" "0.1UF")
			("VOLTAGE" "25V")
			("TOLERANCE" "10%")
			("PACK_TYPE" "0402")
			("MATERIAL" "EMPTY")
			("PART_NUMBER" "CH4104K1B00")
			("STANDARD" "")
			("LIFECYCLE" "")
			("ASS_PART" "")
			("JEDEC_TYPE" "C0402")
			("ALT_SYMBOLS" "(C0402_OCTAGONXA,C0402-0201)")
			("RATED_VOLTAGE" "25V")
			("TOL" "10%")
			("CLASS" "IO")
			("DESCRIPTION" "CAP CHIP 0.1U 25V(+-10%,X7R,0402)")
			("COMPONENT_TYPE" "CHIP0402")
			("LEAD_LENGTH" "")
			("LPID" "")
			("DATE" "20160113")
			("LOCATION" "PC1356")
		)
		("@s9s_mb_2u_lib.s9s_mb_2u(sch_1):page585_i160@pure_quanta.q_cap(chips)"
			("VARIANT" "*")
			("VALUE" "0.1UF")
			("VOLTAGE" "25V")
			("TOLERANCE" "10%")
			("PACK_TYPE" "0402")
			("MATERIAL" "EMPTY")
			("PART_NUMBER" "CH4104K1B00")
			("STANDARD" "")
			("LIFECYCLE" "")
			("ASS_PART" "")
			("JEDEC_TYPE" "C0402")
			("ALT_SYMBOLS" "(C0402_OCTAGONXA,C0402-0201)")
			("RATED_VOLTAGE" "25V")
			("TOL" "10%")
			("CLASS" "IO")
			("DESCRIPTION" "CAP CHIP 0.1U 25V(+-10%,X7R,0402)")
			("COMPONENT_TYPE" "CHIP0402")
			("LEAD_LENGTH" "")
			("LPID" "")
			("DATE" "20160113")
			("LOCATION" "PC1355")
		)
		("@s9s_mb_2u_lib.s9s_mb_2u(sch_1):page436_i89@pure_quanta.q_cap(chips)"
			("VARIANT" "*")
			("VALUE" "0.1UF")
			("VOLTAGE" "25V")
			("TOLERANCE" "10%")
			("PACK_TYPE" "0402")
			("MATERIAL" "EMPTY")
			("PART_NUMBER" "CH4104K1B00")
			("STANDARD" "")
			("LIFECYCLE" "")
			("ASS_PART" "")
			("JEDEC_TYPE" "C0402")
			("ALT_SYMBOLS" "(C0402_OCTAGONXA,C0402-0201)")
			("RATED_VOLTAGE" "25V")
			("TOL" "10%")
			("CLASS" "IO")
			("DESCRIPTION" "CAP CHIP 0.1U 25V(+-10%,X7R,0402)")
			("COMPONENT_TYPE" "CHIP0402")
			("LEAD_LENGTH" "")
			("LPID" "")
			("DATE" "20160113")
			("LOCATION" "PC1341")
		)
		("@s9s_mb_2u_lib.s9s_mb_2u(sch_1):page436_i91@pure_quanta.q_cap(chips)"
			("VARIANT" "*")
			("VALUE" "0.1UF")
			("VOLTAGE" "25V")
			("TOLERANCE" "10%")
			("PACK_TYPE" "0402")
			("MATERIAL" "EMPTY")
			("PART_NUMBER" "CH4104K1B00")
			("STANDARD" "")
			("LIFECYCLE" "")
			("ASS_PART" "")
			("JEDEC_TYPE" "C0402")
			("ALT_SYMBOLS" "(C0402_OCTAGONXA,C0402-0201)")
			("RATED_VOLTAGE" "25V")
			("TOL" "10%")
			("CLASS" "IO")
			("DESCRIPTION" "CAP CHIP 0.1U 25V(+-10%,X7R,0402)")
			("COMPONENT_TYPE" "CHIP0402")
			("LEAD_LENGTH" "")
			("LPID" "")
			("DATE" "20160113")
			("LOCATION" "PC1340")
		)
		("@s9s_mb_2u_lib.s9s_mb_2u(sch_1):page437_i76@pure_quanta.q_cap(chips)"
			("VARIANT" "*")
			("VALUE" "0.1UF")
			("VOLTAGE" "25V")
			("TOLERANCE" "10%")
			("PACK_TYPE" "0402")
			("MATERIAL" "EMPTY")
			("PART_NUMBER" "CH4104K1B00")
			("STANDARD" "")
			("LIFECYCLE" "")
			("ASS_PART" "")
			("JEDEC_TYPE" "C0402")
			("ALT_SYMBOLS" "(C0402_OCTAGONXA,C0402-0201)")
			("RATED_VOLTAGE" "25V")
			("TOL" "10%")
			("CLASS" "IO")
			("DESCRIPTION" "CAP CHIP 0.1U 25V(+-10%,X7R,0402)")
			("COMPONENT_TYPE" "CHIP0402")
			("LEAD_LENGTH" "")
			("LPID" "")
			("DATE" "20160113")
			("LOCATION" "PC1343")
		)
		("@s9s_mb_2u_lib.s9s_mb_2u(sch_1):page437_i78@pure_quanta.q_cap(chips)"
			("VARIANT" "*")
			("VALUE" "0.1UF")
			("VOLTAGE" "25V")
			("TOLERANCE" "10%")
			("PACK_TYPE" "0402")
			("MATERIAL" "EMPTY")
			("PART_NUMBER" "CH4104K1B00")
			("STANDARD" "")
			("LIFECYCLE" "")
			("ASS_PART" "")
			("JEDEC_TYPE" "C0402")
			("ALT_SYMBOLS" "(C0402_OCTAGONXA,C0402-0201)")
			("RATED_VOLTAGE" "25V")
			("TOL" "10%")
			("CLASS" "IO")
			("DESCRIPTION" "CAP CHIP 0.1U 25V(+-10%,X7R,0402)")
			("COMPONENT_TYPE" "CHIP0402")
			("LEAD_LENGTH" "")
			("LPID" "")
			("DATE" "20160113")
			("LOCATION" "PC1342")
		)
		("@s9s_mb_2u_lib.s9s_mb_2u(sch_1):page438_i78@pure_quanta.q_cap(chips)"
			("VARIANT" "*")
			("VALUE" "0.1UF")
			("VOLTAGE" "25V")
			("TOLERANCE" "10%")
			("PACK_TYPE" "0402")
			("MATERIAL" "EMPTY")
			("PART_NUMBER" "CH4104K1B00")
			("STANDARD" "")
			("LIFECYCLE" "")
			("ASS_PART" "")
			("JEDEC_TYPE" "C0402")
			("ALT_SYMBOLS" "(C0402_OCTAGONXA,C0402-0201)")
			("RATED_VOLTAGE" "25V")
			("TOL" "10%")
			("CLASS" "IO")
			("DESCRIPTION" "CAP CHIP 0.1U 25V(+-10%,X7R,0402)")
			("COMPONENT_TYPE" "CHIP0402")
			("LEAD_LENGTH" "")
			("LPID" "")
			("DATE" "20160113")
			("LOCATION" "PC1345")
		)
		("@s9s_mb_2u_lib.s9s_mb_2u(sch_1):page438_i76@pure_quanta.q_cap(chips)"
			("VARIANT" "*")
			("VALUE" "0.1UF")
			("VOLTAGE" "25V")
			("TOLERANCE" "10%")
			("PACK_TYPE" "0402")
			("MATERIAL" "EMPTY")
			("PART_NUMBER" "CH4104K1B00")
			("STANDARD" "")
			("LIFECYCLE" "")
			("ASS_PART" "")
			("JEDEC_TYPE" "C0402")
			("ALT_SYMBOLS" "(C0402_OCTAGONXA,C0402-0201)")
			("RATED_VOLTAGE" "25V")
			("TOL" "10%")
			("CLASS" "IO")
			("DESCRIPTION" "CAP CHIP 0.1U 25V(+-10%,X7R,0402)")
			("COMPONENT_TYPE" "CHIP0402")
			("LEAD_LENGTH" "")
			("LPID" "")
			("DATE" "20160113")
			("LOCATION" "PC1344")
		)
		("@s9s_mb_2u_lib.s9s_mb_2u(sch_1):page435_i159@pure_quanta.q_cap(chips)"
			("VARIANT" "*")
			("VALUE" "0.1UF")
			("VOLTAGE" "25V")
			("TOLERANCE" "10%")
			("PACK_TYPE" "0402")
			("MATERIAL" "EMPTY")
			("PART_NUMBER" "CH4104K1B00")
			("STANDARD" "")
			("LIFECYCLE" "")
			("ASS_PART" "")
			("JEDEC_TYPE" "C0402")
			("ALT_SYMBOLS" "(C0402_OCTAGONXA,C0402-0201)")
			("RATED_VOLTAGE" "25V")
			("TOL" "10%")
			("CLASS" "IO")
			("DESCRIPTION" "CAP CHIP 0.1U 25V(+-10%,X7R,0402)")
			("COMPONENT_TYPE" "CHIP0402")
			("LEAD_LENGTH" "")
			("LPID" "")
			("DATE" "20160113")
			("LOCATION" "PC1339")
		)
		("@s9s_mb_2u_lib.s9s_mb_2u(sch_1):page435_i161@pure_quanta.q_cap(chips)"
			("VARIANT" "*")
			("VALUE" "0.1UF")
			("VOLTAGE" "25V")
			("TOLERANCE" "10%")
			("PACK_TYPE" "0402")
			("MATERIAL" "EMPTY")
			("PART_NUMBER" "CH4104K1B00")
			("STANDARD" "")
			("LIFECYCLE" "")
			("ASS_PART" "")
			("JEDEC_TYPE" "C0402")
			("ALT_SYMBOLS" "(C0402_OCTAGONXA,C0402-0201)")
			("RATED_VOLTAGE" "25V")
			("TOL" "10%")
			("CLASS" "IO")
			("DESCRIPTION" "CAP CHIP 0.1U 25V(+-10%,X7R,0402)")
			("COMPONENT_TYPE" "CHIP0402")
			("LEAD_LENGTH" "")
			("LPID" "")
			("DATE" "20160113")
			("LOCATION" "PC1338")
		)
		("@s9s_mb_2u_lib.s9s_mb_2u(sch_1):page442_i231@pure_quanta.q_cap(chips)"
			("VARIANT" "*")
			("VALUE" "0.1UF")
			("VOLTAGE" "25V")
			("TOLERANCE" "10%")
			("PACK_TYPE" "0402")
			("MATERIAL" "EMPTY")
			("PART_NUMBER" "CH4104K1B00")
			("STANDARD" "")
			("LIFECYCLE" "")
			("ASS_PART" "")
			("JEDEC_TYPE" "C0402")
			("ALT_SYMBOLS" "(C0402_OCTAGONXA,C0402-0201)")
			("RATED_VOLTAGE" "25V")
			("TOL" "10%")
			("CLASS" "IO")
			("DESCRIPTION" "CAP CHIP 0.1U 25V(+-10%,X7R,0402)")
			("COMPONENT_TYPE" "CHIP0402")
			("LEAD_LENGTH" "")
			("LPID" "")
			("DATE" "20160113")
			("LOCATION" "PC1347")
		)
		("@s9s_mb_2u_lib.s9s_mb_2u(sch_1):page442_i233@pure_quanta.q_cap(chips)"
			("VARIANT" "*")
			("VALUE" "0.1UF")
			("VOLTAGE" "25V")
			("TOLERANCE" "10%")
			("PACK_TYPE" "0402")
			("MATERIAL" "EMPTY")
			("PART_NUMBER" "CH4104K1B00")
			("STANDARD" "")
			("LIFECYCLE" "")
			("ASS_PART" "")
			("JEDEC_TYPE" "C0402")
			("ALT_SYMBOLS" "(C0402_OCTAGONXA,C0402-0201)")
			("RATED_VOLTAGE" "25V")
			("TOL" "10%")
			("CLASS" "IO")
			("DESCRIPTION" "CAP CHIP 0.1U 25V(+-10%,X7R,0402)")
			("COMPONENT_TYPE" "CHIP0402")
			("LEAD_LENGTH" "")
			("LPID" "")
			("DATE" "20160113")
			("LOCATION" "PC1346")
		)
		("@s9s_mb_2u_lib.s9s_mb_2u(sch_1):page444_i49@pure_quanta.q_cap(chips)"
			("VARIANT" "*")
			("VALUE" "0.1UF")
			("VOLTAGE" "25V")
			("TOLERANCE" "10%")
			("PACK_TYPE" "0402")
			("MATERIAL" "EMPTY")
			("PART_NUMBER" "CH4104K1B00")
			("STANDARD" "")
			("LIFECYCLE" "")
			("ASS_PART" "")
			("JEDEC_TYPE" "C0402")
			("ALT_SYMBOLS" "(C0402_OCTAGONXA,C0402-0201)")
			("RATED_VOLTAGE" "25V")
			("TOL" "10%")
			("CLASS" "IO")
			("DESCRIPTION" "CAP CHIP 0.1U 25V(+-10%,X7R,0402)")
			("COMPONENT_TYPE" "CHIP0402")
			("LEAD_LENGTH" "")
			("LPID" "")
			("DATE" "20160113")
			("LOCATION" "PC1348")
		)
		("@s9s_mb_2u_lib.s9s_mb_2u(sch_1):page452_i108@pure_quanta.q_cap(chips)"
			("VARIANT" "*")
			("VALUE" "1UF")
			("VOLTAGE" "16V")
			("TOLERANCE" "10%")
			("PACK_TYPE" "C0402")
			("MATERIAL" "X6S")
			("PART_NUMBER" "CH5103KEB01")
			("STANDARD" "")
			("LIFECYCLE" "")
			("ASS_PART" "")
			("JEDEC_TYPE" "C0402")
			("ALT_SYMBOLS" "(C0402-0201)")
			("RATED_VOLTAGE" "16V")
			("TOL" "10%")
			("CLASS" "DISCRETE")
			("DESCRIPTION" "CAP CHIP 1UF 16V(10%,X6S,0402)")
			("COMPONENT_TYPE" "CHIP0402")
			("LEAD_LENGTH" "")
			("LPID" "")
			("DATE" "20140828")
			("LOCATION" "PC628")
		)
		("@s9s_mb_2u_lib.s9s_mb_2u(sch_1):page452_i105@pure_quanta.q_cap(chips)"
			("VARIANT" "*")
			("VALUE" "1UF")
			("VOLTAGE" "16V")
			("TOLERANCE" "10%")
			("PACK_TYPE" "C0402")
			("MATERIAL" "X6S")
			("PART_NUMBER" "CH5103KEB01")
			("STANDARD" "")
			("LIFECYCLE" "")
			("ASS_PART" "")
			("JEDEC_TYPE" "C0402")
			("ALT_SYMBOLS" "(C0402-0201)")
			("RATED_VOLTAGE" "16V")
			("TOL" "10%")
			("CLASS" "DISCRETE")
			("DESCRIPTION" "CAP CHIP 1UF 16V(10%,X6S,0402)")
			("COMPONENT_TYPE" "CHIP0402")
			("LEAD_LENGTH" "")
			("LPID" "")
			("DATE" "20140828")
			("LOCATION" "PC624")
		)
		("@s9s_mb_2u_lib.s9s_mb_2u(sch_1):page446_i123@pure_quanta.q_cap(chips)"
			("VARIANT" "*")
			("VALUE" "1NF")
			("VOLTAGE" "50V")
			("TOLERANCE" "10%")
			("PACK_TYPE" "0402")
			("MATERIAL" "X7R")
			("PART_NUMBER" "CH21006KB16")
			("STANDARD" "")
			("LIFECYCLE" "")
			("ASS_PART" "")
			("JEDEC_TYPE" "C0402")
			("ALT_SYMBOLS" "(C0402-0201)")
			("RATED_VOLTAGE" "50V")
			("TOL" "10%")
			("CLASS" "DISCRETE")
			("DESCRIPTION" "CAP CHIP 1N 50V(+-10%,X7R,0402)EP")
			("COMPONENT_TYPE" "CHIP0402")
			("LEAD_LENGTH" "")
			("LPID" "")
			("DATE" "20100811")
			("LOCATION" "PC594")
		)
		("@s9s_mb_2u_lib.s9s_mb_2u(sch_1):page433_i43@pure_quanta.q_cap(chips)"
			("VARIANT" "*")
			("VALUE" "1NF")
			("VOLTAGE" "50V")
			("TOLERANCE" "10%")
			("PACK_TYPE" "0402")
			("MATERIAL" "X7R")
			("PART_NUMBER" "CH21006KB16")
			("STANDARD" "")
			("LIFECYCLE" "")
			("ASS_PART" "")
			("JEDEC_TYPE" "C0402")
			("ALT_SYMBOLS" "(C0402-0201)")
			("RATED_VOLTAGE" "50V")
			("TOL" "10%")
			("CLASS" "DISCRETE")
			("DESCRIPTION" "CAP CHIP 1N 50V(+-10%,X7R,0402)EP")
			("COMPONENT_TYPE" "CHIP0402")
			("LEAD_LENGTH" "")
			("LPID" "")
			("DATE" "20100811")
			("LOCATION" "PC549")
		)
		("@s9s_mb_2u_lib.s9s_mb_2u(sch_1):page591_i263@pure_quanta.q_cap(chips)"
			("VARIANT" "*")
			("VALUE" "1NF")
			("VOLTAGE" "50V")
			("TOLERANCE" "10%")
			("PACK_TYPE" "0402")
			("MATERIAL" "X7R")
			("PART_NUMBER" "CH21006KB16")
			("STANDARD" "")
			("LIFECYCLE" "")
			("ASS_PART" "")
			("JEDEC_TYPE" "C0402")
			("ALT_SYMBOLS" "(C0402-0201)")
			("RATED_VOLTAGE" "50V")
			("TOL" "10%")
			("CLASS" "DISCRETE")
			("DESCRIPTION" "CAP CHIP 1N 50V(+-10%,X7R,0402)EP")
			("COMPONENT_TYPE" "CHIP0402")
			("LEAD_LENGTH" "")
			("LPID" "")
			("DATE" "20100811")
			("LOCATION" "PC469")
		)
		("@s9s_mb_2u_lib.s9s_mb_2u(sch_1):page591_i254@pure_quanta.q_cap(chips)"
			("VARIANT" "*")
			("VALUE" "1NF")
			("VOLTAGE" "50V")
			("TOLERANCE" "10%")
			("PACK_TYPE" "0402")
			("MATERIAL" "X7R")
			("PART_NUMBER" "CH21006KB16")
			("STANDARD" "")
			("LIFECYCLE" "")
			("ASS_PART" "")
			("JEDEC_TYPE" "C0402")
			("ALT_SYMBOLS" "(C0402-0201)")
			("RATED_VOLTAGE" "50V")
			("TOL" "10%")
			("CLASS" "DISCRETE")
			("DESCRIPTION" "CAP CHIP 1N 50V(+-10%,X7R,0402)EP")
			("COMPONENT_TYPE" "CHIP0402")
			("LEAD_LENGTH" "")
			("LPID" "")
			("DATE" "20100811")
			("LOCATION" "PC468")
		)
		("@s9s_mb_2u_lib.s9s_mb_2u(sch_1):page597_i123@pure_quanta.q_cap(chips)"
			("VARIANT" "*")
			("VALUE" "1NF")
			("VOLTAGE" "50V")
			("TOLERANCE" "10%")
			("PACK_TYPE" "0402")
			("MATERIAL" "X7R")
			("PART_NUMBER" "CH21006KB16")
			("STANDARD" "")
			("LIFECYCLE" "")
			("ASS_PART" "")
			("JEDEC_TYPE" "C0402")
			("ALT_SYMBOLS" "(C0402-0201)")
			("RATED_VOLTAGE" "50V")
			("TOL" "10%")
			("CLASS" "DISCRETE")
			("DESCRIPTION" "CAP CHIP 1N 50V(+-10%,X7R,0402)EP")
			("COMPONENT_TYPE" "CHIP0402")
			("LEAD_LENGTH" "")
			("LPID" "")
			("DATE" "20100811")
			("LOCATION" "PC422")
		)
		("@s9s_mb_2u_lib.s9s_mb_2u(sch_1):page602_i123@pure_quanta.q_cap(chips)"
			("VARIANT" "*")
			("VALUE" "1NF")
			("VOLTAGE" "50V")
			("TOLERANCE" "10%")
			("PACK_TYPE" "0402")
			("MATERIAL" "X7R")
			("PART_NUMBER" "CH21006KB16")
			("STANDARD" "")
			("LIFECYCLE" "")
			("ASS_PART" "")
			("JEDEC_TYPE" "C0402")
			("ALT_SYMBOLS" "(C0402-0201)")
			("RATED_VOLTAGE" "50V")
			("TOL" "10%")
			("CLASS" "DISCRETE")
			("DESCRIPTION" "CAP CHIP 1N 50V(+-10%,X7R,0402)EP")
			("COMPONENT_TYPE" "CHIP0402")
			("LEAD_LENGTH" "")
			("LPID" "")
			("DATE" "20100811")
			("LOCATION" "PC389")
		)
		("@s9s_mb_2u_lib.s9s_mb_2u(sch_1):page583_i43@pure_quanta.q_cap(chips)"
			("VARIANT" "*")
			("VALUE" "1NF")
			("VOLTAGE" "50V")
			("TOLERANCE" "10%")
			("PACK_TYPE" "0402")
			("MATERIAL" "X7R")
			("PART_NUMBER" "CH21006KB16")
			("STANDARD" "")
			("LIFECYCLE" "")
			("ASS_PART" "")
			("JEDEC_TYPE" "C0402")
			("ALT_SYMBOLS" "(C0402-0201)")
			("RATED_VOLTAGE" "50V")
			("TOL" "10%")
			("CLASS" "DISCRETE")
			("DESCRIPTION" "CAP CHIP 1N 50V(+-10%,X7R,0402)EP")
			("COMPONENT_TYPE" "CHIP0402")
			("LEAD_LENGTH" "")
			("LPID" "")
			("DATE" "20100811")
			("LOCATION" "PC331")
		)
		("@s9s_mb_2u_lib.s9s_mb_2u(sch_1):page452_i123@pure_quanta.q_cap(chips)"
			("VARIANT" "*")
			("VALUE" "1NF")
			("VOLTAGE" "50V")
			("TOLERANCE" "10%")
			("PACK_TYPE" "0402")
			("MATERIAL" "X7R")
			("PART_NUMBER" "CH21006KB16")
			("STANDARD" "")
			("LIFECYCLE" "")
			("ASS_PART" "")
			("JEDEC_TYPE" "C0402")
			("ALT_SYMBOLS" "(C0402-0201)")
			("RATED_VOLTAGE" "50V")
			("TOL" "10%")
			("CLASS" "DISCRETE")
			("DESCRIPTION" "CAP CHIP 1N 50V(+-10%,X7R,0402)EP")
			("COMPONENT_TYPE" "CHIP0402")
			("LEAD_LENGTH" "")
			("LPID" "")
			("DATE" "20100811")
			("LOCATION" "PC627")
		)
		("@s9s_mb_2u_lib.s9s_mb_2u(sch_1):page446_i172@pure_quanta.q_cap(chips)"
			("VARIANT" "*")
			("VALUE" "4.7UF")
			("VOLTAGE" "6.3V")
			("TOLERANCE" "20%")
			("PACK_TYPE" "0402")
			("MATERIAL" "EMPTY")
			("PART_NUMBER" "CH5471MEB01")
			("STANDARD" "")
			("LIFECYCLE" "")
			("ASS_PART" "")
			("JEDEC_TYPE" "C0402")
			("ALT_SYMBOLS" "(C0402_OCTAGON,C0402_OCTAGONXA,C0402-0201)")
			("RATED_VOLTAGE" "6.3V")
			("TOL" "20%")
			("CLASS" "IO")
			("DESCRIPTION" "CAP CHIP 4.7UF 6.3V(+-20%,X6S,0402)")
			("COMPONENT_TYPE" "CHIP0402")
			("LEAD_LENGTH" "")
			("LPID" "")
			("DATE" "20151211")
			("LOCATION" "PC597")
		)
		("@s9s_mb_2u_lib.s9s_mb_2u(sch_1):page433_i116@pure_quanta.q_cap(chips)"
			("VARIANT" "*")
			("VALUE" "4.7UF")
			("VOLTAGE" "6.3V")
			("TOLERANCE" "20%")
			("PACK_TYPE" "0402")
			("MATERIAL" "EMPTY")
			("PART_NUMBER" "CH5471MEB01")
			("STANDARD" "")
			("LIFECYCLE" "")
			("ASS_PART" "")
			("JEDEC_TYPE" "C0402")
			("ALT_SYMBOLS" "(C0402_OCTAGON,C0402_OCTAGONXA,C0402-0201)")
			("RATED_VOLTAGE" "6.3V")
			("TOL" "20%")
			("CLASS" "IO")
			("DESCRIPTION" "CAP CHIP 4.7UF 6.3V(+-20%,X6S,0402)")
			("COMPONENT_TYPE" "CHIP0402")
			("LEAD_LENGTH" "")
			("LPID" "")
			("DATE" "20151211")
			("LOCATION" "PC553")
		)
		("@s9s_mb_2u_lib.s9s_mb_2u(sch_1):page591_i340@pure_quanta.q_cap(chips)"
			("VARIANT" "*")
			("VALUE" "4.7UF")
			("VOLTAGE" "6.3V")
			("TOLERANCE" "20%")
			("PACK_TYPE" "0402")
			("MATERIAL" "EMPTY")
			("PART_NUMBER" "CH5471MEB01")
			("STANDARD" "")
			("LIFECYCLE" "")
			("ASS_PART" "")
			("JEDEC_TYPE" "C0402")
			("ALT_SYMBOLS" "(C0402_OCTAGON,C0402_OCTAGONXA,C0402-0201)")
			("RATED_VOLTAGE" "6.3V")
			("TOL" "20%")
			("CLASS" "IO")
			("DESCRIPTION" "CAP CHIP 4.7UF 6.3V(+-20%,X6S,0402)")
			("COMPONENT_TYPE" "CHIP0402")
			("LEAD_LENGTH" "")
			("LPID" "")
			("DATE" "20151211")
			("LOCATION" "PC477")
		)
		("@s9s_mb_2u_lib.s9s_mb_2u(sch_1):page597_i172@pure_quanta.q_cap(chips)"
			("VARIANT" "*")
			("VALUE" "4.7UF")
			("VOLTAGE" "6.3V")
			("TOLERANCE" "20%")
			("PACK_TYPE" "0402")
			("MATERIAL" "EMPTY")
			("PART_NUMBER" "CH5471MEB01")
			("STANDARD" "")
			("LIFECYCLE" "")
			("ASS_PART" "")
			("JEDEC_TYPE" "C0402")
			("ALT_SYMBOLS" "(C0402_OCTAGON,C0402_OCTAGONXA,C0402-0201)")
			("RATED_VOLTAGE" "6.3V")
			("TOL" "20%")
			("CLASS" "IO")
			("DESCRIPTION" "CAP CHIP 4.7UF 6.3V(+-20%,X6S,0402)")
			("COMPONENT_TYPE" "CHIP0402")
			("LEAD_LENGTH" "")
			("LPID" "")
			("DATE" "20151211")
			("LOCATION" "PC425")
		)
		("@s9s_mb_2u_lib.s9s_mb_2u(sch_1):page602_i138@pure_quanta.q_cap(chips)"
			("VARIANT" "*")
			("VALUE" "4.7UF")
			("VOLTAGE" "6.3V")
			("TOLERANCE" "20%")
			("PACK_TYPE" "0402")
			("MATERIAL" "EMPTY")
			("PART_NUMBER" "CH5471MEB01")
			("STANDARD" "")
			("LIFECYCLE" "")
			("ASS_PART" "")
			("JEDEC_TYPE" "C0402")
			("ALT_SYMBOLS" "(C0402_OCTAGON,C0402_OCTAGONXA,C0402-0201)")
			("RATED_VOLTAGE" "6.3V")
			("TOL" "20%")
			("CLASS" "IO")
			("DESCRIPTION" "CAP CHIP 4.7UF 6.3V(+-20%,X6S,0402)")
			("COMPONENT_TYPE" "CHIP0402")
			("LEAD_LENGTH" "")
			("LPID" "")
			("DATE" "20151211")
			("LOCATION" "PC392")
		)
		("@s9s_mb_2u_lib.s9s_mb_2u(sch_1):page583_i116@pure_quanta.q_cap(chips)"
			("VARIANT" "*")
			("VALUE" "4.7UF")
			("VOLTAGE" "6.3V")
			("TOLERANCE" "20%")
			("PACK_TYPE" "0402")
			("MATERIAL" "EMPTY")
			("PART_NUMBER" "CH5471MEB01")
			("STANDARD" "")
			("LIFECYCLE" "")
			("ASS_PART" "")
			("JEDEC_TYPE" "C0402")
			("ALT_SYMBOLS" "(C0402_OCTAGON,C0402_OCTAGONXA,C0402-0201)")
			("RATED_VOLTAGE" "6.3V")
			("TOL" "20%")
			("CLASS" "IO")
			("DESCRIPTION" "CAP CHIP 4.7UF 6.3V(+-20%,X6S,0402)")
			("COMPONENT_TYPE" "CHIP0402")
			("LEAD_LENGTH" "")
			("LPID" "")
			("DATE" "20151211")
			("LOCATION" "PC335")
		)
		("@s9s_mb_2u_lib.s9s_mb_2u(sch_1):page452_i138@pure_quanta.q_cap(chips)"
			("VARIANT" "*")
			("VALUE" "4.7UF")
			("VOLTAGE" "6.3V")
			("TOLERANCE" "20%")
			("PACK_TYPE" "0402")
			("MATERIAL" "EMPTY")
			("PART_NUMBER" "CH5471MEB01")
			("STANDARD" "")
			("LIFECYCLE" "")
			("ASS_PART" "")
			("JEDEC_TYPE" "C0402")
			("ALT_SYMBOLS" "(C0402_OCTAGON,C0402_OCTAGONXA,C0402-0201)")
			("RATED_VOLTAGE" "6.3V")
			("TOL" "20%")
			("CLASS" "IO")
			("DESCRIPTION" "CAP CHIP 4.7UF 6.3V(+-20%,X6S,0402)")
			("COMPONENT_TYPE" "CHIP0402")
			("LEAD_LENGTH" "")
			("LPID" "")
			("DATE" "20151211")
			("LOCATION" "PC630")
		)
		("@s9s_mb_2u_lib.s9s_mb_2u(sch_1):page446_i145@pure_quanta.q_cap(chips)"
			("VARIANT" "*")
			("VALUE" "2200PF")
			("VOLTAGE" "50V")
			("TOLERANCE" "10%")
			("PACK_TYPE" "C0402")
			("MATERIAL" "X7R")
			("PART_NUMBER" "CH2226K1B06")
			("STANDARD" "")
			("LIFECYCLE" "")
			("ASS_PART" "")
			("JEDEC_TYPE" "C0402")
			("ALT_SYMBOLS" "(C0402-0201)")
			("RATED_VOLTAGE" "50V")
			("TOL" "10%")
			("CLASS" "DISCRETE")
			("DESCRIPTION" "CAP CHIP 2200P 50V(+-10%,X7R,0402)MUR")
			("COMPONENT_TYPE" "CHIP0402")
			("LEAD_LENGTH" "")
			("LPID" "")
			("DATE" "20150614")
			("LOCATION" "PC598")
		)
		("@s9s_mb_2u_lib.s9s_mb_2u(sch_1):page433_i61@pure_quanta.q_cap(chips)"
			("VARIANT" "*")
			("VALUE" "2200PF")
			("VOLTAGE" "50V")
			("TOLERANCE" "10%")
			("PACK_TYPE" "C0402")
			("MATERIAL" "X7R")
			("PART_NUMBER" "CH2226K1B06")
			("STANDARD" "")
			("LIFECYCLE" "")
			("ASS_PART" "")
			("JEDEC_TYPE" "C0402")
			("ALT_SYMBOLS" "(C0402-0201)")
			("RATED_VOLTAGE" "50V")
			("TOL" "10%")
			("CLASS" "DISCRETE")
			("DESCRIPTION" "CAP CHIP 2200P 50V(+-10%,X7R,0402)MUR")
			("COMPONENT_TYPE" "CHIP0402")
			("LEAD_LENGTH" "")
			("LPID" "")
			("DATE" "20150614")
			("LOCATION" "PC554")
		)
		("@s9s_mb_2u_lib.s9s_mb_2u(sch_1):page591_i390@pure_quanta.q_cap(chips)"
			("VARIANT" "*")
			("VALUE" "2200PF")
			("VOLTAGE" "50V")
			("TOLERANCE" "10%")
			("PACK_TYPE" "C0402")
			("MATERIAL" "X7R")
			("PART_NUMBER" "CH2226K1B06")
			("STANDARD" "")
			("LIFECYCLE" "")
			("ASS_PART" "")
			("JEDEC_TYPE" "C0402")
			("ALT_SYMBOLS" "(C0402-0201)")
			("RATED_VOLTAGE" "50V")
			("TOL" "10%")
			("CLASS" "DISCRETE")
			("DESCRIPTION" "CAP CHIP 2200P 50V(+-10%,X7R,0402)MUR")
			("COMPONENT_TYPE" "CHIP0402")
			("LEAD_LENGTH" "")
			("LPID" "")
			("DATE" "20150614")
			("LOCATION" "PC1292")
		)
		("@s9s_mb_2u_lib.s9s_mb_2u(sch_1):page591_i368@pure_quanta.q_cap(chips)"
			("VARIANT" "*")
			("VALUE" "2200PF")
			("VOLTAGE" "50V")
			("TOLERANCE" "10%")
			("PACK_TYPE" "C0402")
			("MATERIAL" "X7R")
			("PART_NUMBER" "CH2226K1B06")
			("STANDARD" "")
			("LIFECYCLE" "")
			("ASS_PART" "")
			("JEDEC_TYPE" "C0402")
			("ALT_SYMBOLS" "(C0402-0201)")
			("RATED_VOLTAGE" "50V")
			("TOL" "10%")
			("CLASS" "DISCRETE")
			("DESCRIPTION" "CAP CHIP 2200P 50V(+-10%,X7R,0402)MUR")
			("COMPONENT_TYPE" "CHIP0402")
			("LEAD_LENGTH" "")
			("LPID" "")
			("DATE" "20150614")
			("LOCATION" "PC475")
		)
		("@s9s_mb_2u_lib.s9s_mb_2u(sch_1):page597_i145@pure_quanta.q_cap(chips)"
			("VARIANT" "*")
			("VALUE" "2200PF")
			("VOLTAGE" "50V")
			("TOLERANCE" "10%")
			("PACK_TYPE" "C0402")
			("MATERIAL" "X7R")
			("PART_NUMBER" "CH2226K1B06")
			("STANDARD" "")
			("LIFECYCLE" "")
			("ASS_PART" "")
			("JEDEC_TYPE" "C0402")
			("ALT_SYMBOLS" "(C0402-0201)")
			("RATED_VOLTAGE" "50V")
			("TOL" "10%")
			("CLASS" "DISCRETE")
			("DESCRIPTION" "CAP CHIP 2200P 50V(+-10%,X7R,0402)MUR")
			("COMPONENT_TYPE" "CHIP0402")
			("LEAD_LENGTH" "")
			("LPID" "")
			("DATE" "20150614")
			("LOCATION" "PC426")
		)
		("@s9s_mb_2u_lib.s9s_mb_2u(sch_1):page602_i141@pure_quanta.q_cap(chips)"
			("VARIANT" "*")
			("VALUE" "2200PF")
			("VOLTAGE" "50V")
			("TOLERANCE" "10%")
			("PACK_TYPE" "C0402")
			("MATERIAL" "X7R")
			("PART_NUMBER" "CH2226K1B06")
			("STANDARD" "")
			("LIFECYCLE" "")
			("ASS_PART" "")
			("JEDEC_TYPE" "C0402")
			("ALT_SYMBOLS" "(C0402-0201)")
			("RATED_VOLTAGE" "50V")
			("TOL" "10%")
			("CLASS" "DISCRETE")
			("DESCRIPTION" "CAP CHIP 2200P 50V(+-10%,X7R,0402)MUR")
			("COMPONENT_TYPE" "CHIP0402")
			("LEAD_LENGTH" "")
			("LPID" "")
			("DATE" "20150614")
			("LOCATION" "PC393")
		)
		("@s9s_mb_2u_lib.s9s_mb_2u(sch_1):page583_i61@pure_quanta.q_cap(chips)"
			("VARIANT" "*")
			("VALUE" "2200PF")
			("VOLTAGE" "50V")
			("TOLERANCE" "10%")
			("PACK_TYPE" "C0402")
			("MATERIAL" "X7R")
			("PART_NUMBER" "CH2226K1B06")
			("STANDARD" "")
			("LIFECYCLE" "")
			("ASS_PART" "")
			("JEDEC_TYPE" "C0402")
			("ALT_SYMBOLS" "(C0402-0201)")
			("RATED_VOLTAGE" "50V")
			("TOL" "10%")
			("CLASS" "DISCRETE")
			("DESCRIPTION" "CAP CHIP 2200P 50V(+-10%,X7R,0402)MUR")
			("COMPONENT_TYPE" "CHIP0402")
			("LEAD_LENGTH" "")
			("LPID" "")
			("DATE" "20150614")
			("LOCATION" "PC336")
		)
		("@s9s_mb_2u_lib.s9s_mb_2u(sch_1):page452_i141@pure_quanta.q_cap(chips)"
			("VARIANT" "*")
			("VALUE" "2200PF")
			("VOLTAGE" "50V")
			("TOLERANCE" "10%")
			("PACK_TYPE" "C0402")
			("MATERIAL" "X7R")
			("PART_NUMBER" "CH2226K1B06")
			("STANDARD" "")
			("LIFECYCLE" "")
			("ASS_PART" "")
			("JEDEC_TYPE" "C0402")
			("ALT_SYMBOLS" "(C0402-0201)")
			("RATED_VOLTAGE" "50V")
			("TOL" "10%")
			("CLASS" "DISCRETE")
			("DESCRIPTION" "CAP CHIP 2200P 50V(+-10%,X7R,0402)MUR")
			("COMPONENT_TYPE" "CHIP0402")
			("LEAD_LENGTH" "")
			("LPID" "")
			("DATE" "20150614")
			("LOCATION" "PC631")
		)
		("@s9s_mb_2u_lib.s9s_mb_2u(sch_1):page591_i323@pure_quanta.q_res(chips)"
			("VARIANT" "*")
			("VALUE" "11.3K")
			("TOLERANCE" "0.1%")
			("WATTAGE" "1/16W")
			("PACK_TYPE" "0402LF")
			("MATERIAL" "CHIP")
			("PART_NUMBER" "CS31132BB00")
			("STANDARD" "")
			("LIFECYCLE" "")
			("JEDEC_TYPE" "R0402")
			("ALT_SYMBOLS" "(R0402-0201)")
			("TOL" "0.1%")
			("CLASS" "DISCRETE")
			("DESCRIPTION" "RES CHIP 11.3K 1/16W +-0.1%(0402)")
			("COMPONENT_TYPE" "CHIP0402")
			("LEAD_LENGTH" "")
			("DFM_EXCLUSION" "")
			("DAY" "20140813")
			("LOCATION" "PR259")
		)
		("@s9s_mb_2u_lib.s9s_mb_2u(sch_1):page448_i29@pure_quanta.q_res(chips)"
			("VARIANT" "*")
			("VALUE" "0")
			("TOLERANCE" "5%")
			("WATTAGE" "1/16W")
			("PACK_TYPE" "0402LF")
			("MATERIAL" "EMPTY")
			("PART_NUMBER" "CS00002JB38")
			("STANDARD" "End of Design")
			("LIFECYCLE" "Comp-Approve")
			("JEDEC_TYPE" "R0402")
			("ALT_SYMBOLS" "(R0402-0201)")
			("TOL" "5%")
			("CLASS" "IO")
			("DESCRIPTION" "RESISTOR CHIP 0 1/16W +-5%(0402)")
			("COMPONENT_TYPE" "CHIP0402")
			("LEAD_LENGTH" "")
			("DFM_EXCLUSION" "")
			("DAY" "20100618")
			("LOCATION" "PR1325")
		)
		("@s9s_mb_2u_lib.s9s_mb_2u(sch_1):page448_i36@pure_quanta.q_res(chips)"
			("VARIANT" "*")
			("VALUE" "0")
			("TOLERANCE" "5%")
			("WATTAGE" "1/16W")
			("PACK_TYPE" "0402LF")
			("MATERIAL" "EMPTY")
			("PART_NUMBER" "CS00002JB38")
			("STANDARD" "End of Design")
			("LIFECYCLE" "Comp-Approve")
			("JEDEC_TYPE" "R0402")
			("ALT_SYMBOLS" "(R0402-0201)")
			("TOL" "5%")
			("CLASS" "IO")
			("DESCRIPTION" "RESISTOR CHIP 0 1/16W +-5%(0402)")
			("COMPONENT_TYPE" "CHIP0402")
			("LEAD_LENGTH" "")
			("DFM_EXCLUSION" "")
			("DAY" "20100618")
			("LOCATION" "PR1324")
		)
		("@s9s_mb_2u_lib.s9s_mb_2u(sch_1):page453_i163@pure_quanta.q_res(chips)"
			("VARIANT" "*")
			("VALUE" "0")
			("TOLERANCE" "5%")
			("WATTAGE" "1/16W")
			("PACK_TYPE" "0402LF")
			("MATERIAL" "EMPTY")
			("PART_NUMBER" "CS00002JB38")
			("STANDARD" "End of Design")
			("LIFECYCLE" "Comp-Approve")
			("JEDEC_TYPE" "R0402")
			("ALT_SYMBOLS" "(R0402-0201)")
			("TOL" "5%")
			("CLASS" "IO")
			("DESCRIPTION" "RESISTOR CHIP 0 1/16W +-5%(0402)")
			("COMPONENT_TYPE" "CHIP0402")
			("LEAD_LENGTH" "")
			("DFM_EXCLUSION" "")
			("DAY" "20100618")
			("LOCATION" "PR1785")
		)
		("@s9s_mb_2u_lib.s9s_mb_2u(sch_1):page447_i69@pure_quanta.q_res(chips)"
			("VARIANT" "*")
			("VALUE" "0")
			("TOLERANCE" "5%")
			("WATTAGE" "1/16W")
			("PACK_TYPE" "0402LF")
			("MATERIAL" "EMPTY")
			("PART_NUMBER" "CS00002JB38")
			("STANDARD" "End of Design")
			("LIFECYCLE" "Comp-Approve")
			("JEDEC_TYPE" "R0402")
			("ALT_SYMBOLS" "(R0402-0201)")
			("TOL" "5%")
			("CLASS" "IO")
			("DESCRIPTION" "RESISTOR CHIP 0 1/16W +-5%(0402)")
			("COMPONENT_TYPE" "CHIP0402")
			("LEAD_LENGTH" "")
			("DFM_EXCLUSION" "")
			("DAY" "20100618")
			("LOCATION" "PR1323")
		)
		("@s9s_mb_2u_lib.s9s_mb_2u(sch_1):page447_i66@pure_quanta.q_res(chips)"
			("VARIANT" "*")
			("VALUE" "0")
			("TOLERANCE" "5%")
			("WATTAGE" "1/16W")
			("PACK_TYPE" "0402LF")
			("MATERIAL" "EMPTY")
			("PART_NUMBER" "CS00002JB38")
			("STANDARD" "End of Design")
			("LIFECYCLE" "Comp-Approve")
			("JEDEC_TYPE" "R0402")
			("ALT_SYMBOLS" "(R0402-0201)")
			("TOL" "5%")
			("CLASS" "IO")
			("DESCRIPTION" "RESISTOR CHIP 0 1/16W +-5%(0402)")
			("COMPONENT_TYPE" "CHIP0402")
			("LEAD_LENGTH" "")
			("DFM_EXCLUSION" "")
			("DAY" "20100618")
			("LOCATION" "PR1322")
		)
		("@s9s_mb_2u_lib.s9s_mb_2u(sch_1):page587_i95@pure_quanta.q_res(chips)"
			("VARIANT" "*")
			("VALUE" "0")
			("TOLERANCE" "5%")
			("WATTAGE" "1/16W")
			("PACK_TYPE" "0402LF")
			("MATERIAL" "EMPTY")
			("PART_NUMBER" "CS00002JB38")
			("STANDARD" "End of Design")
			("LIFECYCLE" "Comp-Approve")
			("JEDEC_TYPE" "R0402")
			("ALT_SYMBOLS" "(R0402-0201)")
			("TOL" "5%")
			("CLASS" "IO")
			("DESCRIPTION" "RESISTOR CHIP 0 1/16W +-5%(0402)")
			("COMPONENT_TYPE" "CHIP0402")
			("LEAD_LENGTH" "")
			("DFM_EXCLUSION" "")
			("DAY" "20100618")
			("LOCATION" "PR302")
		)
		("@s9s_mb_2u_lib.s9s_mb_2u(sch_1):page587_i94@pure_quanta.q_res(chips)"
			("VARIANT" "*")
			("VALUE" "0")
			("TOLERANCE" "5%")
			("WATTAGE" "1/16W")
			("PACK_TYPE" "0402LF")
			("MATERIAL" "EMPTY")
			("PART_NUMBER" "CS00002JB38")
			("STANDARD" "End of Design")
			("LIFECYCLE" "Comp-Approve")
			("JEDEC_TYPE" "R0402")
			("ALT_SYMBOLS" "(R0402-0201)")
			("TOL" "5%")
			("CLASS" "IO")
			("DESCRIPTION" "RESISTOR CHIP 0 1/16W +-5%(0402)")
			("COMPONENT_TYPE" "CHIP0402")
			("LEAD_LENGTH" "")
			("DFM_EXCLUSION" "")
			("DAY" "20100618")
			("LOCATION" "PR301")
		)
		("@s9s_mb_2u_lib.s9s_mb_2u(sch_1):page588_i81@pure_quanta.q_res(chips)"
			("VARIANT" "*")
			("VALUE" "0")
			("TOLERANCE" "5%")
			("WATTAGE" "1/16W")
			("PACK_TYPE" "0402LF")
			("MATERIAL" "EMPTY")
			("PART_NUMBER" "CS00002JB38")
			("STANDARD" "End of Design")
			("LIFECYCLE" "Comp-Approve")
			("JEDEC_TYPE" "R0402")
			("ALT_SYMBOLS" "(R0402-0201)")
			("TOL" "5%")
			("CLASS" "IO")
			("DESCRIPTION" "RESISTOR CHIP 0 1/16W +-5%(0402)")
			("COMPONENT_TYPE" "CHIP0402")
			("LEAD_LENGTH" "")
			("DFM_EXCLUSION" "")
			("DAY" "20100618")
			("LOCATION" "PR296")
		)
		("@s9s_mb_2u_lib.s9s_mb_2u(sch_1):page588_i82@pure_quanta.q_res(chips)"
			("VARIANT" "*")
			("VALUE" "0")
			("TOLERANCE" "5%")
			("WATTAGE" "1/16W")
			("PACK_TYPE" "0402LF")
			("MATERIAL" "EMPTY")
			("PART_NUMBER" "CS00002JB38")
			("STANDARD" "End of Design")
			("LIFECYCLE" "Comp-Approve")
			("JEDEC_TYPE" "R0402")
			("ALT_SYMBOLS" "(R0402-0201)")
			("TOL" "5%")
			("CLASS" "IO")
			("DESCRIPTION" "RESISTOR CHIP 0 1/16W +-5%(0402)")
			("COMPONENT_TYPE" "CHIP0402")
			("LEAD_LENGTH" "")
			("DFM_EXCLUSION" "")
			("DAY" "20100618")
			("LOCATION" "PR295")
		)
		("@s9s_mb_2u_lib.s9s_mb_2u(sch_1):page589_i81@pure_quanta.q_res(chips)"
			("VARIANT" "*")
			("VALUE" "0")
			("TOLERANCE" "5%")
			("WATTAGE" "1/16W")
			("PACK_TYPE" "0402LF")
			("MATERIAL" "EMPTY")
			("PART_NUMBER" "CS00002JB38")
			("STANDARD" "End of Design")
			("LIFECYCLE" "Comp-Approve")
			("JEDEC_TYPE" "R0402")
			("ALT_SYMBOLS" "(R0402-0201)")
			("TOL" "5%")
			("CLASS" "IO")
			("DESCRIPTION" "RESISTOR CHIP 0 1/16W +-5%(0402)")
			("COMPONENT_TYPE" "CHIP0402")
			("LEAD_LENGTH" "")
			("DFM_EXCLUSION" "")
			("DAY" "20100618")
			("LOCATION" "PR290")
		)
		("@s9s_mb_2u_lib.s9s_mb_2u(sch_1):page589_i82@pure_quanta.q_res(chips)"
			("VARIANT" "*")
			("VALUE" "0")
			("TOLERANCE" "5%")
			("WATTAGE" "1/16W")
			("PACK_TYPE" "0402LF")
			("MATERIAL" "EMPTY")
			("PART_NUMBER" "CS00002JB38")
			("STANDARD" "End of Design")
			("LIFECYCLE" "Comp-Approve")
			("JEDEC_TYPE" "R0402")
			("ALT_SYMBOLS" "(R0402-0201)")
			("TOL" "5%")
			("CLASS" "IO")
			("DESCRIPTION" "RESISTOR CHIP 0 1/16W +-5%(0402)")
			("COMPONENT_TYPE" "CHIP0402")
			("LEAD_LENGTH" "")
			("DFM_EXCLUSION" "")
			("DAY" "20100618")
			("LOCATION" "PR289")
		)
		("@s9s_mb_2u_lib.s9s_mb_2u(sch_1):page593_i215@pure_quanta.q_res(chips)"
			("VARIANT" "*")
			("VALUE" "0")
			("TOLERANCE" "5%")
			("WATTAGE" "1/16W")
			("PACK_TYPE" "0402LF")
			("MATERIAL" "EMPTY")
			("PART_NUMBER" "CS00002JB38")
			("STANDARD" "End of Design")
			("LIFECYCLE" "Comp-Approve")
			("JEDEC_TYPE" "R0402")
			("ALT_SYMBOLS" "(R0402-0201)")
			("TOL" "5%")
			("CLASS" "IO")
			("DESCRIPTION" "RESISTOR CHIP 0 1/16W +-5%(0402)")
			("COMPONENT_TYPE" "CHIP0402")
			("LEAD_LENGTH" "")
			("DFM_EXCLUSION" "")
			("DAY" "20100618")
			("LOCATION" "PR1797")
		)
		("@s9s_mb_2u_lib.s9s_mb_2u(sch_1):page593_i219@pure_quanta.q_res(chips)"
			("VARIANT" "*")
			("VALUE" "0")
			("TOLERANCE" "5%")
			("WATTAGE" "1/16W")
			("PACK_TYPE" "0402LF")
			("MATERIAL" "EMPTY")
			("PART_NUMBER" "CS00002JB38")
			("STANDARD" "End of Design")
			("LIFECYCLE" "Comp-Approve")
			("JEDEC_TYPE" "R0402")
			("ALT_SYMBOLS" "(R0402-0201)")
			("TOL" "5%")
			("CLASS" "IO")
			("DESCRIPTION" "RESISTOR CHIP 0 1/16W +-5%(0402)")
			("COMPONENT_TYPE" "CHIP0402")
			("LEAD_LENGTH" "")
			("DFM_EXCLUSION" "")
			("DAY" "20100618")
			("LOCATION" "PR1796")
		)
		("@s9s_mb_2u_lib.s9s_mb_2u(sch_1):page595_i49@pure_quanta.q_res(chips)"
			("VARIANT" "*")
			("VALUE" "0")
			("TOLERANCE" "5%")
			("WATTAGE" "1/16W")
			("PACK_TYPE" "0402LF")
			("MATERIAL" "EMPTY")
			("PART_NUMBER" "CS00002JB38")
			("STANDARD" "End of Design")
			("LIFECYCLE" "Comp-Approve")
			("JEDEC_TYPE" "R0402")
			("ALT_SYMBOLS" "(R0402-0201)")
			("TOL" "5%")
			("CLASS" "IO")
			("DESCRIPTION" "RESISTOR CHIP 0 1/16W +-5%(0402)")
			("COMPONENT_TYPE" "CHIP0402")
			("LEAD_LENGTH" "")
			("DFM_EXCLUSION" "")
			("DAY" "20100618")
			("LOCATION" "PR1799")
		)
		("@s9s_mb_2u_lib.s9s_mb_2u(sch_1):page599_i30@pure_quanta.q_res(chips)"
			("VARIANT" "*")
			("VALUE" "0")
			("TOLERANCE" "5%")
			("WATTAGE" "1/16W")
			("PACK_TYPE" "0402LF")
			("MATERIAL" "EMPTY")
			("PART_NUMBER" "CS00002JB38")
			("STANDARD" "End of Design")
			("LIFECYCLE" "Comp-Approve")
			("JEDEC_TYPE" "R0402")
			("ALT_SYMBOLS" "(R0402-0201)")
			("TOL" "5%")
			("CLASS" "IO")
			("DESCRIPTION" "RESISTOR CHIP 0 1/16W +-5%(0402)")
			("COMPONENT_TYPE" "CHIP0402")
			("LEAD_LENGTH" "")
			("DFM_EXCLUSION" "")
			("DAY" "20100618")
			("LOCATION" "PR1334")
		)
		("@s9s_mb_2u_lib.s9s_mb_2u(sch_1):page599_i39@pure_quanta.q_res(chips)"
			("VARIANT" "*")
			("VALUE" "0")
			("TOLERANCE" "5%")
			("WATTAGE" "1/16W")
			("PACK_TYPE" "0402LF")
			("MATERIAL" "EMPTY")
			("PART_NUMBER" "CS00002JB38")
			("STANDARD" "End of Design")
			("LIFECYCLE" "Comp-Approve")
			("JEDEC_TYPE" "R0402")
			("ALT_SYMBOLS" "(R0402-0201)")
			("TOL" "5%")
			("CLASS" "IO")
			("DESCRIPTION" "RESISTOR CHIP 0 1/16W +-5%(0402)")
			("COMPONENT_TYPE" "CHIP0402")
			("LEAD_LENGTH" "")
			("DFM_EXCLUSION" "")
			("DAY" "20100618")
			("LOCATION" "PR1333")
		)
		("@s9s_mb_2u_lib.s9s_mb_2u(sch_1):page598_i42@pure_quanta.q_res(chips)"
			("VARIANT" "*")
			("VALUE" "0")
			("TOLERANCE" "5%")
			("WATTAGE" "1/16W")
			("PACK_TYPE" "0402LF")
			("MATERIAL" "EMPTY")
			("PART_NUMBER" "CS00002JB38")
			("STANDARD" "End of Design")
			("LIFECYCLE" "Comp-Approve")
			("JEDEC_TYPE" "R0402")
			("ALT_SYMBOLS" "(R0402-0201)")
			("TOL" "5%")
			("CLASS" "IO")
			("DESCRIPTION" "RESISTOR CHIP 0 1/16W +-5%(0402)")
			("COMPONENT_TYPE" "CHIP0402")
			("LEAD_LENGTH" "")
			("DFM_EXCLUSION" "")
			("DAY" "20100618")
			("LOCATION" "PR1332")
		)
		("@s9s_mb_2u_lib.s9s_mb_2u(sch_1):page598_i34@pure_quanta.q_res(chips)"
			("VARIANT" "*")
			("VALUE" "0")
			("TOLERANCE" "5%")
			("WATTAGE" "1/16W")
			("PACK_TYPE" "0402LF")
			("MATERIAL" "EMPTY")
			("PART_NUMBER" "CS00002JB38")
			("STANDARD" "End of Design")
			("LIFECYCLE" "Comp-Approve")
			("JEDEC_TYPE" "R0402")
			("ALT_SYMBOLS" "(R0402-0201)")
			("TOL" "5%")
			("CLASS" "IO")
			("DESCRIPTION" "RESISTOR CHIP 0 1/16W +-5%(0402)")
			("COMPONENT_TYPE" "CHIP0402")
			("LEAD_LENGTH" "")
			("DFM_EXCLUSION" "")
			("DAY" "20100618")
			("LOCATION" "PR1331")
		)
		("@s9s_mb_2u_lib.s9s_mb_2u(sch_1):page603_i162@pure_quanta.q_res(chips)"
			("VARIANT" "*")
			("VALUE" "0")
			("TOLERANCE" "5%")
			("WATTAGE" "1/16W")
			("PACK_TYPE" "0402LF")
			("MATERIAL" "EMPTY")
			("PART_NUMBER" "CS00002JB38")
			("STANDARD" "End of Design")
			("LIFECYCLE" "Comp-Approve")
			("JEDEC_TYPE" "R0402")
			("ALT_SYMBOLS" "(R0402-0201)")
			("TOL" "5%")
			("CLASS" "IO")
			("DESCRIPTION" "RESISTOR CHIP 0 1/16W +-5%(0402)")
			("COMPONENT_TYPE" "CHIP0402")
			("LEAD_LENGTH" "")
			("DFM_EXCLUSION" "")
			("DAY" "20100618")
			("LOCATION" "PR1805")
		)
		("@s9s_mb_2u_lib.s9s_mb_2u(sch_1):page585_i165@pure_quanta.q_res(chips)"
			("VARIANT" "*")
			("VALUE" "0")
			("TOLERANCE" "5%")
			("WATTAGE" "1/16W")
			("PACK_TYPE" "0402LF")
			("MATERIAL" "EMPTY")
			("PART_NUMBER" "CS00002JB38")
			("STANDARD" "End of Design")
			("LIFECYCLE" "Comp-Approve")
			("JEDEC_TYPE" "R0402")
			("ALT_SYMBOLS" "(R0402-0201)")
			("TOL" "5%")
			("CLASS" "IO")
			("DESCRIPTION" "RESISTOR CHIP 0 1/16W +-5%(0402)")
			("COMPONENT_TYPE" "CHIP0402")
			("LEAD_LENGTH" "")
			("DFM_EXCLUSION" "")
			("DAY" "20100618")
			("LOCATION" "PR155")
		)
		("@s9s_mb_2u_lib.s9s_mb_2u(sch_1):page585_i164@pure_quanta.q_res(chips)"
			("VARIANT" "*")
			("VALUE" "0")
			("TOLERANCE" "5%")
			("WATTAGE" "1/16W")
			("PACK_TYPE" "0402LF")
			("MATERIAL" "EMPTY")
			("PART_NUMBER" "CS00002JB38")
			("STANDARD" "End of Design")
			("LIFECYCLE" "Comp-Approve")
			("JEDEC_TYPE" "R0402")
			("ALT_SYMBOLS" "(R0402-0201)")
			("TOL" "5%")
			("CLASS" "IO")
			("DESCRIPTION" "RESISTOR CHIP 0 1/16W +-5%(0402)")
			("COMPONENT_TYPE" "CHIP0402")
			("LEAD_LENGTH" "")
			("DFM_EXCLUSION" "")
			("DAY" "20100618")
			("LOCATION" "PR154")
		)
		("@s9s_mb_2u_lib.s9s_mb_2u(sch_1):page436_i96@pure_quanta.q_res(chips)"
			("VARIANT" "*")
			("VALUE" "0")
			("TOLERANCE" "5%")
			("WATTAGE" "1/16W")
			("PACK_TYPE" "0402LF")
			("MATERIAL" "EMPTY")
			("PART_NUMBER" "CS00002JB38")
			("STANDARD" "End of Design")
			("LIFECYCLE" "Comp-Approve")
			("JEDEC_TYPE" "R0402")
			("ALT_SYMBOLS" "(R0402-0201)")
			("TOL" "5%")
			("CLASS" "IO")
			("DESCRIPTION" "RESISTOR CHIP 0 1/16W +-5%(0402)")
			("COMPONENT_TYPE" "CHIP0402")
			("LEAD_LENGTH" "")
			("DFM_EXCLUSION" "")
			("DAY" "20100618")
			("LOCATION" "PR149")
		)
		("@s9s_mb_2u_lib.s9s_mb_2u(sch_1):page436_i94@pure_quanta.q_res(chips)"
			("VARIANT" "*")
			("VALUE" "0")
			("TOLERANCE" "5%")
			("WATTAGE" "1/16W")
			("PACK_TYPE" "0402LF")
			("MATERIAL" "EMPTY")
			("PART_NUMBER" "CS00002JB38")
			("STANDARD" "End of Design")
			("LIFECYCLE" "Comp-Approve")
			("JEDEC_TYPE" "R0402")
			("ALT_SYMBOLS" "(R0402-0201)")
			("TOL" "5%")
			("CLASS" "IO")
			("DESCRIPTION" "RESISTOR CHIP 0 1/16W +-5%(0402)")
			("COMPONENT_TYPE" "CHIP0402")
			("LEAD_LENGTH" "")
			("DFM_EXCLUSION" "")
			("DAY" "20100618")
			("LOCATION" "PR148")
		)
		("@s9s_mb_2u_lib.s9s_mb_2u(sch_1):page437_i82@pure_quanta.q_res(chips)"
			("VARIANT" "*")
			("VALUE" "0")
			("TOLERANCE" "5%")
			("WATTAGE" "1/16W")
			("PACK_TYPE" "0402LF")
			("MATERIAL" "EMPTY")
			("PART_NUMBER" "CS00002JB38")
			("STANDARD" "End of Design")
			("LIFECYCLE" "Comp-Approve")
			("JEDEC_TYPE" "R0402")
			("ALT_SYMBOLS" "(R0402-0201)")
			("TOL" "5%")
			("CLASS" "IO")
			("DESCRIPTION" "RESISTOR CHIP 0 1/16W +-5%(0402)")
			("COMPONENT_TYPE" "CHIP0402")
			("LEAD_LENGTH" "")
			("DFM_EXCLUSION" "")
			("DAY" "20100618")
			("LOCATION" "PR143")
		)
		("@s9s_mb_2u_lib.s9s_mb_2u(sch_1):page437_i81@pure_quanta.q_res(chips)"
			("VARIANT" "*")
			("VALUE" "0")
			("TOLERANCE" "5%")
			("WATTAGE" "1/16W")
			("PACK_TYPE" "0402LF")
			("MATERIAL" "EMPTY")
			("PART_NUMBER" "CS00002JB38")
			("STANDARD" "End of Design")
			("LIFECYCLE" "Comp-Approve")
			("JEDEC_TYPE" "R0402")
			("ALT_SYMBOLS" "(R0402-0201)")
			("TOL" "5%")
			("CLASS" "IO")
			("DESCRIPTION" "RESISTOR CHIP 0 1/16W +-5%(0402)")
			("COMPONENT_TYPE" "CHIP0402")
			("LEAD_LENGTH" "")
			("DFM_EXCLUSION" "")
			("DAY" "20100618")
			("LOCATION" "PR142")
		)
		("@s9s_mb_2u_lib.s9s_mb_2u(sch_1):page438_i82@pure_quanta.q_res(chips)"
			("VARIANT" "*")
			("VALUE" "0")
			("TOLERANCE" "5%")
			("WATTAGE" "1/16W")
			("PACK_TYPE" "0402LF")
			("MATERIAL" "EMPTY")
			("PART_NUMBER" "CS00002JB38")
			("STANDARD" "End of Design")
			("LIFECYCLE" "Comp-Approve")
			("JEDEC_TYPE" "R0402")
			("ALT_SYMBOLS" "(R0402-0201)")
			("TOL" "5%")
			("CLASS" "IO")
			("DESCRIPTION" "RESISTOR CHIP 0 1/16W +-5%(0402)")
			("COMPONENT_TYPE" "CHIP0402")
			("LEAD_LENGTH" "")
			("DFM_EXCLUSION" "")
			("DAY" "20100618")
			("LOCATION" "PR137")
		)
		("@s9s_mb_2u_lib.s9s_mb_2u(sch_1):page438_i83@pure_quanta.q_res(chips)"
			("VARIANT" "*")
			("VALUE" "0")
			("TOLERANCE" "5%")
			("WATTAGE" "1/16W")
			("PACK_TYPE" "0402LF")
			("MATERIAL" "EMPTY")
			("PART_NUMBER" "CS00002JB38")
			("STANDARD" "End of Design")
			("LIFECYCLE" "Comp-Approve")
			("JEDEC_TYPE" "R0402")
			("ALT_SYMBOLS" "(R0402-0201)")
			("TOL" "5%")
			("CLASS" "IO")
			("DESCRIPTION" "RESISTOR CHIP 0 1/16W +-5%(0402)")
			("COMPONENT_TYPE" "CHIP0402")
			("LEAD_LENGTH" "")
			("DFM_EXCLUSION" "")
			("DAY" "20100618")
			("LOCATION" "PR136")
		)
		("@s9s_mb_2u_lib.s9s_mb_2u(sch_1):page435_i165@pure_quanta.q_res(chips)"
			("VARIANT" "*")
			("VALUE" "0")
			("TOLERANCE" "5%")
			("WATTAGE" "1/16W")
			("PACK_TYPE" "0402LF")
			("MATERIAL" "EMPTY")
			("PART_NUMBER" "CS00002JB38")
			("STANDARD" "End of Design")
			("LIFECYCLE" "Comp-Approve")
			("JEDEC_TYPE" "R0402")
			("ALT_SYMBOLS" "(R0402-0201)")
			("TOL" "5%")
			("CLASS" "IO")
			("DESCRIPTION" "RESISTOR CHIP 0 1/16W +-5%(0402)")
			("COMPONENT_TYPE" "CHIP0402")
			("LEAD_LENGTH" "")
			("DFM_EXCLUSION" "")
			("DAY" "20100618")
			("LOCATION" "PR330")
		)
		("@s9s_mb_2u_lib.s9s_mb_2u(sch_1):page435_i164@pure_quanta.q_res(chips)"
			("VARIANT" "*")
			("VALUE" "0")
			("TOLERANCE" "5%")
			("WATTAGE" "1/16W")
			("PACK_TYPE" "0402LF")
			("MATERIAL" "EMPTY")
			("PART_NUMBER" "CS00002JB38")
			("STANDARD" "End of Design")
			("LIFECYCLE" "Comp-Approve")
			("JEDEC_TYPE" "R0402")
			("ALT_SYMBOLS" "(R0402-0201)")
			("TOL" "5%")
			("CLASS" "IO")
			("DESCRIPTION" "RESISTOR CHIP 0 1/16W +-5%(0402)")
			("COMPONENT_TYPE" "CHIP0402")
			("LEAD_LENGTH" "")
			("DFM_EXCLUSION" "")
			("DAY" "20100618")
			("LOCATION" "PR329")
		)
		("@s9s_mb_2u_lib.s9s_mb_2u(sch_1):page442_i228@pure_quanta.q_res(chips)"
			("VARIANT" "*")
			("VALUE" "0")
			("TOLERANCE" "5%")
			("WATTAGE" "1/16W")
			("PACK_TYPE" "0402LF")
			("MATERIAL" "EMPTY")
			("PART_NUMBER" "CS00002JB38")
			("STANDARD" "End of Design")
			("LIFECYCLE" "Comp-Approve")
			("JEDEC_TYPE" "R0402")
			("ALT_SYMBOLS" "(R0402-0201)")
			("TOL" "5%")
			("CLASS" "IO")
			("DESCRIPTION" "RESISTOR CHIP 0 1/16W +-5%(0402)")
			("COMPONENT_TYPE" "CHIP0402")
			("LEAD_LENGTH" "")
			("DFM_EXCLUSION" "")
			("DAY" "20100618")
			("LOCATION" "PR1777")
		)
		("@s9s_mb_2u_lib.s9s_mb_2u(sch_1):page442_i225@pure_quanta.q_res(chips)"
			("VARIANT" "*")
			("VALUE" "0")
			("TOLERANCE" "5%")
			("WATTAGE" "1/16W")
			("PACK_TYPE" "0402LF")
			("MATERIAL" "EMPTY")
			("PART_NUMBER" "CS00002JB38")
			("STANDARD" "End of Design")
			("LIFECYCLE" "Comp-Approve")
			("JEDEC_TYPE" "R0402")
			("ALT_SYMBOLS" "(R0402-0201)")
			("TOL" "5%")
			("CLASS" "IO")
			("DESCRIPTION" "RESISTOR CHIP 0 1/16W +-5%(0402)")
			("COMPONENT_TYPE" "CHIP0402")
			("LEAD_LENGTH" "")
			("DFM_EXCLUSION" "")
			("DAY" "20100618")
			("LOCATION" "PR1776")
		)
		("@s9s_mb_2u_lib.s9s_mb_2u(sch_1):page444_i46@pure_quanta.q_res(chips)"
			("VARIANT" "*")
			("VALUE" "0")
			("TOLERANCE" "5%")
			("WATTAGE" "1/16W")
			("PACK_TYPE" "0402LF")
			("MATERIAL" "EMPTY")
			("PART_NUMBER" "CS00002JB38")
			("STANDARD" "End of Design")
			("LIFECYCLE" "Comp-Approve")
			("JEDEC_TYPE" "R0402")
			("ALT_SYMBOLS" "(R0402-0201)")
			("TOL" "5%")
			("CLASS" "IO")
			("DESCRIPTION" "RESISTOR CHIP 0 1/16W +-5%(0402)")
			("COMPONENT_TYPE" "CHIP0402")
			("LEAD_LENGTH" "")
			("DFM_EXCLUSION" "")
			("DAY" "20100618")
			("LOCATION" "PR1779")
		)
		("@s9s_mb_2u_lib.s9s_mb_2u(sch_1):page583_i26@pure_quanta.q_res(chips)"
			("VARIANT" "*")
			("VALUE" "1.3K")
			("TOLERANCE" "1%")
			("WATTAGE" "1/16W")
			("PACK_TYPE" "0402LF")
			("MATERIAL" "CHIP")
			("PART_NUMBER" "CS21302FB17")
			("STANDARD" "End of Design")
			("LIFECYCLE" "Comp-Approve")
			("JEDEC_TYPE" "R0402")
			("ALT_SYMBOLS" "(R0402-0201)")
			("TOL" "1%")
			("CLASS" "DISCRETE")
			("DESCRIPTION" "RES CHIP 1.3K 1/16W +-1%(0402) L-F")
			("COMPONENT_TYPE" "CHIP0402")
			("LEAD_LENGTH" "")
			("DFM_EXCLUSION" "")
			("DAY" "20131122")
			("LOCATION" "PR171")
		)
		("@s9s_mb_2u_lib.s9s_mb_2u(sch_1):page597_i197@pure_quanta.q_res(chips)"
			("VARIANT" "*")
			("VALUE" "75K")
			("TOLERANCE" "1%")
			("WATTAGE" "1/16W")
			("PACK_TYPE" "0402LF")
			("MATERIAL" "CHIP")
			("PART_NUMBER" "CS37502FB12")
			("STANDARD" "End of Design")
			("LIFECYCLE" "Comp-Approve")
			("JEDEC_TYPE" "R0402")
			("ALT_SYMBOLS" "(R0402-0201)")
			("TOL" "1%")
			("CLASS" "DISCRETE")
			("DESCRIPTION" "RES CHIP 75K 1/16W +-1%(0402)")
			("COMPONENT_TYPE" "CHIP0402")
			("LEAD_LENGTH" "")
			("DFM_EXCLUSION" "")
			("DAY" "20111130")
			("LOCATION" "PR229")
		)
		("@s9s_mb_2u_lib.s9s_mb_2u(sch_1):page446_i197@pure_quanta.q_res(chips)"
			("VARIANT" "*")
			("VALUE" "45.3K")
			("TOLERANCE" "1%")
			("WATTAGE" "1/16W")
			("PACK_TYPE" "0402LF")
			("MATERIAL" "CHIP")
			("PART_NUMBER" "TMP_QCS34532FB18")
			("STANDARD" "End of Design")
			("LIFECYCLE" "Comp-Approve")
			("JEDEC_TYPE" "R0402")
			("ALT_SYMBOLS" "(R0402-0201)")
			("TOL" "1%")
			("CLASS" "DISCRETE")
			("DESCRIPTION" "45.3Kohm 0402")
			("COMPONENT_TYPE" "CHIP0402")
			("LEAD_LENGTH" "")
			("DFM_EXCLUSION" "")
			("DAY" "")
			("LOCATION" "PR332")
		)
		("@s9s_mb_2u_lib.s9s_mb_2u(sch_1):page448_i104@pure_quanta.q_res(chips)"
			("VARIANT" "*")
			("VALUE" "5.1")
			("TOLERANCE" "5%")
			("WATTAGE" "1/16W")
			("PACK_TYPE" "0402LF")
			("MATERIAL" "CHIP")
			("PART_NUMBER" "CS-5102JB03")
			("STANDARD" "End of Design")
			("LIFECYCLE" "Comp-Approve")
			("JEDEC_TYPE" "R0402")
			("ALT_SYMBOLS" "(R0402-0201)")
			("TOL" "5%")
			("CLASS" "DISCRETE")
			("DESCRIPTION" "RES CHIP 5.1 1/16W +-5%(0402)")
			("COMPONENT_TYPE" "CHIP0402")
			("LEAD_LENGTH" "")
			("DFM_EXCLUSION" "")
			("DAY" "20100827")
			("LOCATION" "PR1783")
		)
		("@s9s_mb_2u_lib.s9s_mb_2u(sch_1):page448_i102@pure_quanta.q_res(chips)"
			("VARIANT" "*")
			("VALUE" "5.1")
			("TOLERANCE" "5%")
			("WATTAGE" "1/16W")
			("PACK_TYPE" "0402LF")
			("MATERIAL" "CHIP")
			("PART_NUMBER" "CS-5102JB03")
			("STANDARD" "End of Design")
			("LIFECYCLE" "Comp-Approve")
			("JEDEC_TYPE" "R0402")
			("ALT_SYMBOLS" "(R0402-0201)")
			("TOL" "5%")
			("CLASS" "DISCRETE")
			("DESCRIPTION" "RES CHIP 5.1 1/16W +-5%(0402)")
			("COMPONENT_TYPE" "CHIP0402")
			("LEAD_LENGTH" "")
			("DFM_EXCLUSION" "")
			("DAY" "20100827")
			("LOCATION" "PR1782")
		)
		("@s9s_mb_2u_lib.s9s_mb_2u(sch_1):page447_i95@pure_quanta.q_res(chips)"
			("VARIANT" "*")
			("VALUE" "5.1")
			("TOLERANCE" "5%")
			("WATTAGE" "1/16W")
			("PACK_TYPE" "0402LF")
			("MATERIAL" "CHIP")
			("PART_NUMBER" "CS-5102JB03")
			("STANDARD" "End of Design")
			("LIFECYCLE" "Comp-Approve")
			("JEDEC_TYPE" "R0402")
			("ALT_SYMBOLS" "(R0402-0201)")
			("TOL" "5%")
			("CLASS" "DISCRETE")
			("DESCRIPTION" "RES CHIP 5.1 1/16W +-5%(0402)")
			("COMPONENT_TYPE" "CHIP0402")
			("LEAD_LENGTH" "")
			("DFM_EXCLUSION" "")
			("DAY" "20100827")
			("LOCATION" "PR1781")
		)
		("@s9s_mb_2u_lib.s9s_mb_2u(sch_1):page447_i94@pure_quanta.q_res(chips)"
			("VARIANT" "*")
			("VALUE" "5.1")
			("TOLERANCE" "5%")
			("WATTAGE" "1/16W")
			("PACK_TYPE" "0402LF")
			("MATERIAL" "CHIP")
			("PART_NUMBER" "CS-5102JB03")
			("STANDARD" "End of Design")
			("LIFECYCLE" "Comp-Approve")
			("JEDEC_TYPE" "R0402")
			("ALT_SYMBOLS" "(R0402-0201)")
			("TOL" "5%")
			("CLASS" "DISCRETE")
			("DESCRIPTION" "RES CHIP 5.1 1/16W +-5%(0402)")
			("COMPONENT_TYPE" "CHIP0402")
			("LEAD_LENGTH" "")
			("DFM_EXCLUSION" "")
			("DAY" "20100827")
			("LOCATION" "PR1780")
		)
		("@s9s_mb_2u_lib.s9s_mb_2u(sch_1):page587_i84@pure_quanta.q_res(chips)"
			("VARIANT" "*")
			("VALUE" "5.1")
			("TOLERANCE" "5%")
			("WATTAGE" "1/16W")
			("PACK_TYPE" "0402LF")
			("MATERIAL" "CHIP")
			("PART_NUMBER" "CS-5102JB03")
			("STANDARD" "End of Design")
			("LIFECYCLE" "Comp-Approve")
			("JEDEC_TYPE" "R0402")
			("ALT_SYMBOLS" "(R0402-0201)")
			("TOL" "5%")
			("CLASS" "DISCRETE")
			("DESCRIPTION" "RES CHIP 5.1 1/16W +-5%(0402)")
			("COMPONENT_TYPE" "CHIP0402")
			("LEAD_LENGTH" "")
			("DFM_EXCLUSION" "")
			("DAY" "20100827")
			("LOCATION" "PR1789")
		)
		("@s9s_mb_2u_lib.s9s_mb_2u(sch_1):page587_i86@pure_quanta.q_res(chips)"
			("VARIANT" "*")
			("VALUE" "5.1")
			("TOLERANCE" "5%")
			("WATTAGE" "1/16W")
			("PACK_TYPE" "0402LF")
			("MATERIAL" "CHIP")
			("PART_NUMBER" "CS-5102JB03")
			("STANDARD" "End of Design")
			("LIFECYCLE" "Comp-Approve")
			("JEDEC_TYPE" "R0402")
			("ALT_SYMBOLS" "(R0402-0201)")
			("TOL" "5%")
			("CLASS" "DISCRETE")
			("DESCRIPTION" "RES CHIP 5.1 1/16W +-5%(0402)")
			("COMPONENT_TYPE" "CHIP0402")
			("LEAD_LENGTH" "")
			("DFM_EXCLUSION" "")
			("DAY" "20100827")
			("LOCATION" "PR1788")
		)
		("@s9s_mb_2u_lib.s9s_mb_2u(sch_1):page588_i71@pure_quanta.q_res(chips)"
			("VARIANT" "*")
			("VALUE" "5.1")
			("TOLERANCE" "5%")
			("WATTAGE" "1/16W")
			("PACK_TYPE" "0402LF")
			("MATERIAL" "CHIP")
			("PART_NUMBER" "CS-5102JB03")
			("STANDARD" "End of Design")
			("LIFECYCLE" "Comp-Approve")
			("JEDEC_TYPE" "R0402")
			("ALT_SYMBOLS" "(R0402-0201)")
			("TOL" "5%")
			("CLASS" "DISCRETE")
			("DESCRIPTION" "RES CHIP 5.1 1/16W +-5%(0402)")
			("COMPONENT_TYPE" "CHIP0402")
			("LEAD_LENGTH" "")
			("DFM_EXCLUSION" "")
			("DAY" "20100827")
			("LOCATION" "PR1791")
		)
		("@s9s_mb_2u_lib.s9s_mb_2u(sch_1):page588_i73@pure_quanta.q_res(chips)"
			("VARIANT" "*")
			("VALUE" "5.1")
			("TOLERANCE" "5%")
			("WATTAGE" "1/16W")
			("PACK_TYPE" "0402LF")
			("MATERIAL" "CHIP")
			("PART_NUMBER" "CS-5102JB03")
			("STANDARD" "End of Design")
			("LIFECYCLE" "Comp-Approve")
			("JEDEC_TYPE" "R0402")
			("ALT_SYMBOLS" "(R0402-0201)")
			("TOL" "5%")
			("CLASS" "DISCRETE")
			("DESCRIPTION" "RES CHIP 5.1 1/16W +-5%(0402)")
			("COMPONENT_TYPE" "CHIP0402")
			("LEAD_LENGTH" "")
			("DFM_EXCLUSION" "")
			("DAY" "20100827")
			("LOCATION" "PR1790")
		)
		("@s9s_mb_2u_lib.s9s_mb_2u(sch_1):page589_i71@pure_quanta.q_res(chips)"
			("VARIANT" "*")
			("VALUE" "5.1")
			("TOLERANCE" "5%")
			("WATTAGE" "1/16W")
			("PACK_TYPE" "0402LF")
			("MATERIAL" "CHIP")
			("PART_NUMBER" "CS-5102JB03")
			("STANDARD" "End of Design")
			("LIFECYCLE" "Comp-Approve")
			("JEDEC_TYPE" "R0402")
			("ALT_SYMBOLS" "(R0402-0201)")
			("TOL" "5%")
			("CLASS" "DISCRETE")
			("DESCRIPTION" "RES CHIP 5.1 1/16W +-5%(0402)")
			("COMPONENT_TYPE" "CHIP0402")
			("LEAD_LENGTH" "")
			("DFM_EXCLUSION" "")
			("DAY" "20100827")
			("LOCATION" "PR1793")
		)
		("@s9s_mb_2u_lib.s9s_mb_2u(sch_1):page589_i73@pure_quanta.q_res(chips)"
			("VARIANT" "*")
			("VALUE" "5.1")
			("TOLERANCE" "5%")
			("WATTAGE" "1/16W")
			("PACK_TYPE" "0402LF")
			("MATERIAL" "CHIP")
			("PART_NUMBER" "CS-5102JB03")
			("STANDARD" "End of Design")
			("LIFECYCLE" "Comp-Approve")
			("JEDEC_TYPE" "R0402")
			("ALT_SYMBOLS" "(R0402-0201)")
			("TOL" "5%")
			("CLASS" "DISCRETE")
			("DESCRIPTION" "RES CHIP 5.1 1/16W +-5%(0402)")
			("COMPONENT_TYPE" "CHIP0402")
			("LEAD_LENGTH" "")
			("DFM_EXCLUSION" "")
			("DAY" "20100827")
			("LOCATION" "PR1792")
		)
		("@s9s_mb_2u_lib.s9s_mb_2u(sch_1):page599_i97@pure_quanta.q_res(chips)"
			("VARIANT" "*")
			("VALUE" "5.1")
			("TOLERANCE" "5%")
			("WATTAGE" "1/16W")
			("PACK_TYPE" "0402LF")
			("MATERIAL" "CHIP")
			("PART_NUMBER" "CS-5102JB03")
			("STANDARD" "End of Design")
			("LIFECYCLE" "Comp-Approve")
			("JEDEC_TYPE" "R0402")
			("ALT_SYMBOLS" "(R0402-0201)")
			("TOL" "5%")
			("CLASS" "DISCRETE")
			("DESCRIPTION" "RES CHIP 5.1 1/16W +-5%(0402)")
			("COMPONENT_TYPE" "CHIP0402")
			("LEAD_LENGTH" "")
			("DFM_EXCLUSION" "")
			("DAY" "20100827")
			("LOCATION" "PR1803")
		)
		("@s9s_mb_2u_lib.s9s_mb_2u(sch_1):page599_i95@pure_quanta.q_res(chips)"
			("VARIANT" "*")
			("VALUE" "5.1")
			("TOLERANCE" "5%")
			("WATTAGE" "1/16W")
			("PACK_TYPE" "0402LF")
			("MATERIAL" "CHIP")
			("PART_NUMBER" "CS-5102JB03")
			("STANDARD" "End of Design")
			("LIFECYCLE" "Comp-Approve")
			("JEDEC_TYPE" "R0402")
			("ALT_SYMBOLS" "(R0402-0201)")
			("TOL" "5%")
			("CLASS" "DISCRETE")
			("DESCRIPTION" "RES CHIP 5.1 1/16W +-5%(0402)")
			("COMPONENT_TYPE" "CHIP0402")
			("LEAD_LENGTH" "")
			("DFM_EXCLUSION" "")
			("DAY" "20100827")
			("LOCATION" "PR1802")
		)
		("@s9s_mb_2u_lib.s9s_mb_2u(sch_1):page598_i91@pure_quanta.q_res(chips)"
			("VARIANT" "*")
			("VALUE" "5.1")
			("TOLERANCE" "5%")
			("WATTAGE" "1/16W")
			("PACK_TYPE" "0402LF")
			("MATERIAL" "CHIP")
			("PART_NUMBER" "CS-5102JB03")
			("STANDARD" "End of Design")
			("LIFECYCLE" "Comp-Approve")
			("JEDEC_TYPE" "R0402")
			("ALT_SYMBOLS" "(R0402-0201)")
			("TOL" "5%")
			("CLASS" "DISCRETE")
			("DESCRIPTION" "RES CHIP 5.1 1/16W +-5%(0402)")
			("COMPONENT_TYPE" "CHIP0402")
			("LEAD_LENGTH" "")
			("DFM_EXCLUSION" "")
			("DAY" "20100827")
			("LOCATION" "PR1801")
		)
		("@s9s_mb_2u_lib.s9s_mb_2u(sch_1):page598_i89@pure_quanta.q_res(chips)"
			("VARIANT" "*")
			("VALUE" "5.1")
			("TOLERANCE" "5%")
			("WATTAGE" "1/16W")
			("PACK_TYPE" "0402LF")
			("MATERIAL" "CHIP")
			("PART_NUMBER" "CS-5102JB03")
			("STANDARD" "End of Design")
			("LIFECYCLE" "Comp-Approve")
			("JEDEC_TYPE" "R0402")
			("ALT_SYMBOLS" "(R0402-0201)")
			("TOL" "5%")
			("CLASS" "DISCRETE")
			("DESCRIPTION" "RES CHIP 5.1 1/16W +-5%(0402)")
			("COMPONENT_TYPE" "CHIP0402")
			("LEAD_LENGTH" "")
			("DFM_EXCLUSION" "")
			("DAY" "20100827")
			("LOCATION" "PR1800")
		)
		("@s9s_mb_2u_lib.s9s_mb_2u(sch_1):page585_i154@pure_quanta.q_res(chips)"
			("VARIANT" "*")
			("VALUE" "5.1")
			("TOLERANCE" "5%")
			("WATTAGE" "1/16W")
			("PACK_TYPE" "0402LF")
			("MATERIAL" "CHIP")
			("PART_NUMBER" "CS-5102JB03")
			("STANDARD" "End of Design")
			("LIFECYCLE" "Comp-Approve")
			("JEDEC_TYPE" "R0402")
			("ALT_SYMBOLS" "(R0402-0201)")
			("TOL" "5%")
			("CLASS" "DISCRETE")
			("DESCRIPTION" "RES CHIP 5.1 1/16W +-5%(0402)")
			("COMPONENT_TYPE" "CHIP0402")
			("LEAD_LENGTH" "")
			("DFM_EXCLUSION" "")
			("DAY" "20100827")
			("LOCATION" "PR1787")
		)
		("@s9s_mb_2u_lib.s9s_mb_2u(sch_1):page585_i155@pure_quanta.q_res(chips)"
			("VARIANT" "*")
			("VALUE" "5.1")
			("TOLERANCE" "5%")
			("WATTAGE" "1/16W")
			("PACK_TYPE" "0402LF")
			("MATERIAL" "CHIP")
			("PART_NUMBER" "CS-5102JB03")
			("STANDARD" "End of Design")
			("LIFECYCLE" "Comp-Approve")
			("JEDEC_TYPE" "R0402")
			("ALT_SYMBOLS" "(R0402-0201)")
			("TOL" "5%")
			("CLASS" "DISCRETE")
			("DESCRIPTION" "RES CHIP 5.1 1/16W +-5%(0402)")
			("COMPONENT_TYPE" "CHIP0402")
			("LEAD_LENGTH" "")
			("DFM_EXCLUSION" "")
			("DAY" "20100827")
			("LOCATION" "PR1786")
		)
		("@s9s_mb_2u_lib.s9s_mb_2u(sch_1):page436_i84@pure_quanta.q_res(chips)"
			("VARIANT" "*")
			("VALUE" "5.1")
			("TOLERANCE" "5%")
			("WATTAGE" "1/16W")
			("PACK_TYPE" "0402LF")
			("MATERIAL" "CHIP")
			("PART_NUMBER" "CS-5102JB03")
			("STANDARD" "End of Design")
			("LIFECYCLE" "Comp-Approve")
			("JEDEC_TYPE" "R0402")
			("ALT_SYMBOLS" "(R0402-0201)")
			("TOL" "5%")
			("CLASS" "DISCRETE")
			("DESCRIPTION" "RES CHIP 5.1 1/16W +-5%(0402)")
			("COMPONENT_TYPE" "CHIP0402")
			("LEAD_LENGTH" "")
			("DFM_EXCLUSION" "")
			("DAY" "20100827")
			("LOCATION" "PR1769")
		)
		("@s9s_mb_2u_lib.s9s_mb_2u(sch_1):page436_i86@pure_quanta.q_res(chips)"
			("VARIANT" "*")
			("VALUE" "5.1")
			("TOLERANCE" "5%")
			("WATTAGE" "1/16W")
			("PACK_TYPE" "0402LF")
			("MATERIAL" "CHIP")
			("PART_NUMBER" "CS-5102JB03")
			("STANDARD" "End of Design")
			("LIFECYCLE" "Comp-Approve")
			("JEDEC_TYPE" "R0402")
			("ALT_SYMBOLS" "(R0402-0201)")
			("TOL" "5%")
			("CLASS" "DISCRETE")
			("DESCRIPTION" "RES CHIP 5.1 1/16W +-5%(0402)")
			("COMPONENT_TYPE" "CHIP0402")
			("LEAD_LENGTH" "")
			("DFM_EXCLUSION" "")
			("DAY" "20100827")
			("LOCATION" "PR1768")
		)
		("@s9s_mb_2u_lib.s9s_mb_2u(sch_1):page437_i71@pure_quanta.q_res(chips)"
			("VARIANT" "*")
			("VALUE" "5.1")
			("TOLERANCE" "5%")
			("WATTAGE" "1/16W")
			("PACK_TYPE" "0402LF")
			("MATERIAL" "CHIP")
			("PART_NUMBER" "CS-5102JB03")
			("STANDARD" "End of Design")
			("LIFECYCLE" "Comp-Approve")
			("JEDEC_TYPE" "R0402")
			("ALT_SYMBOLS" "(R0402-0201)")
			("TOL" "5%")
			("CLASS" "DISCRETE")
			("DESCRIPTION" "RES CHIP 5.1 1/16W +-5%(0402)")
			("COMPONENT_TYPE" "CHIP0402")
			("LEAD_LENGTH" "")
			("DFM_EXCLUSION" "")
			("DAY" "20100827")
			("LOCATION" "PR1771")
		)
		("@s9s_mb_2u_lib.s9s_mb_2u(sch_1):page437_i73@pure_quanta.q_res(chips)"
			("VARIANT" "*")
			("VALUE" "5.1")
			("TOLERANCE" "5%")
			("WATTAGE" "1/16W")
			("PACK_TYPE" "0402LF")
			("MATERIAL" "CHIP")
			("PART_NUMBER" "CS-5102JB03")
			("STANDARD" "End of Design")
			("LIFECYCLE" "Comp-Approve")
			("JEDEC_TYPE" "R0402")
			("ALT_SYMBOLS" "(R0402-0201)")
			("TOL" "5%")
			("CLASS" "DISCRETE")
			("DESCRIPTION" "RES CHIP 5.1 1/16W +-5%(0402)")
			("COMPONENT_TYPE" "CHIP0402")
			("LEAD_LENGTH" "")
			("DFM_EXCLUSION" "")
			("DAY" "20100827")
			("LOCATION" "PR1770")
		)
		("@s9s_mb_2u_lib.s9s_mb_2u(sch_1):page438_i71@pure_quanta.q_res(chips)"
			("VARIANT" "*")
			("VALUE" "5.1")
			("TOLERANCE" "5%")
			("WATTAGE" "1/16W")
			("PACK_TYPE" "0402LF")
			("MATERIAL" "CHIP")
			("PART_NUMBER" "CS-5102JB03")
			("STANDARD" "End of Design")
			("LIFECYCLE" "Comp-Approve")
			("JEDEC_TYPE" "R0402")
			("ALT_SYMBOLS" "(R0402-0201)")
			("TOL" "5%")
			("CLASS" "DISCRETE")
			("DESCRIPTION" "RES CHIP 5.1 1/16W +-5%(0402)")
			("COMPONENT_TYPE" "CHIP0402")
			("LEAD_LENGTH" "")
			("DFM_EXCLUSION" "")
			("DAY" "20100827")
			("LOCATION" "PR1773")
		)
		("@s9s_mb_2u_lib.s9s_mb_2u(sch_1):page438_i73@pure_quanta.q_res(chips)"
			("VARIANT" "*")
			("VALUE" "5.1")
			("TOLERANCE" "5%")
			("WATTAGE" "1/16W")
			("PACK_TYPE" "0402LF")
			("MATERIAL" "CHIP")
			("PART_NUMBER" "CS-5102JB03")
			("STANDARD" "End of Design")
			("LIFECYCLE" "Comp-Approve")
			("JEDEC_TYPE" "R0402")
			("ALT_SYMBOLS" "(R0402-0201)")
			("TOL" "5%")
			("CLASS" "DISCRETE")
			("DESCRIPTION" "RES CHIP 5.1 1/16W +-5%(0402)")
			("COMPONENT_TYPE" "CHIP0402")
			("LEAD_LENGTH" "")
			("DFM_EXCLUSION" "")
			("DAY" "20100827")
			("LOCATION" "PR1772")
		)
		("@s9s_mb_2u_lib.s9s_mb_2u(sch_1):page435_i154@pure_quanta.q_res(chips)"
			("VARIANT" "*")
			("VALUE" "5.1")
			("TOLERANCE" "5%")
			("WATTAGE" "1/16W")
			("PACK_TYPE" "0402LF")
			("MATERIAL" "CHIP")
			("PART_NUMBER" "CS-5102JB03")
			("STANDARD" "End of Design")
			("LIFECYCLE" "Comp-Approve")
			("JEDEC_TYPE" "R0402")
			("ALT_SYMBOLS" "(R0402-0201)")
			("TOL" "5%")
			("CLASS" "DISCRETE")
			("DESCRIPTION" "RES CHIP 5.1 1/16W +-5%(0402)")
			("COMPONENT_TYPE" "CHIP0402")
			("LEAD_LENGTH" "")
			("DFM_EXCLUSION" "")
			("DAY" "20100827")
			("LOCATION" "PR1767")
		)
		("@s9s_mb_2u_lib.s9s_mb_2u(sch_1):page435_i156@pure_quanta.q_res(chips)"
			("VARIANT" "*")
			("VALUE" "5.1")
			("TOLERANCE" "5%")
			("WATTAGE" "1/16W")
			("PACK_TYPE" "0402LF")
			("MATERIAL" "CHIP")
			("PART_NUMBER" "CS-5102JB03")
			("STANDARD" "End of Design")
			("LIFECYCLE" "Comp-Approve")
			("JEDEC_TYPE" "R0402")
			("ALT_SYMBOLS" "(R0402-0201)")
			("TOL" "5%")
			("CLASS" "DISCRETE")
			("DESCRIPTION" "RES CHIP 5.1 1/16W +-5%(0402)")
			("COMPONENT_TYPE" "CHIP0402")
			("LEAD_LENGTH" "")
			("DFM_EXCLUSION" "")
			("DAY" "20100827")
			("LOCATION" "PR1766")
		)
		("@s9s_mb_2u_lib.s9s_mb_2u(sch_1):page641_i23@pure_quanta.q_res(chips)"
			("VARIANT" "*")
			("VALUE" "5.1")
			("TOLERANCE" "5%")
			("WATTAGE" "1/16W")
			("PACK_TYPE" "0402LF")
			("MATERIAL" "EMPTY")
			("PART_NUMBER" "CS-5102JB03")
			("STANDARD" "End of Design")
			("LIFECYCLE" "Comp-Approve")
			("JEDEC_TYPE" "R0402")
			("ALT_SYMBOLS" "(R0402-0201)")
			("TOL" "5%")
			("CLASS" "IO")
			("DESCRIPTION" "RES CHIP 5.1 1/16W +-5%(0402)")
			("COMPONENT_TYPE" "CHIP0402")
			("LEAD_LENGTH" "")
			("DFM_EXCLUSION" "")
			("DAY" "20100827")
			("LOCATION" "PR1889")
		)
		("@s9s_mb_2u_lib.s9s_mb_2u(sch_1):page663_i21@pure_quanta.q_res(chips)"
			("VARIANT" "*")
			("VALUE" "5.1")
			("TOLERANCE" "5%")
			("WATTAGE" "1/16W")
			("PACK_TYPE" "0402LF")
			("MATERIAL" "EMPTY")
			("PART_NUMBER" "CS-5102JB03")
			("STANDARD" "End of Design")
			("LIFECYCLE" "Comp-Approve")
			("JEDEC_TYPE" "R0402")
			("ALT_SYMBOLS" "(R0402-0201)")
			("TOL" "5%")
			("CLASS" "IO")
			("DESCRIPTION" "RES CHIP 5.1 1/16W +-5%(0402)")
			("COMPONENT_TYPE" "CHIP0402")
			("LEAD_LENGTH" "")
			("DFM_EXCLUSION" "")
			("DAY" "20100827")
			("LOCATION" "PR1893")
		)
		("@s9s_mb_2u_lib.s9s_mb_2u(sch_1):page602_i183@pure_quanta.q_res(chips)"
			("VARIANT" "*")
			("VALUE" "59K")
			("TOLERANCE" "1%")
			("WATTAGE" "1/16W ")
			("PACK_TYPE" "0402LF ")
			("MATERIAL" "CHIP")
			("PART_NUMBER" "TMP_QCS35902FB03")
			("STANDARD" "")
			("LIFECYCLE" "")
			("JEDEC_TYPE" "R0402")
			("ALT_SYMBOLS" "(R0402-0201)")
			("TOL" "1%")
			("CLASS" "DISCRETE")
			("DESCRIPTION" "RESISTOR CHIP 59K 1/16W +-1%(0402)")
			("COMPONENT_TYPE" "CHIP0402 ")
			("LEAD_LENGTH" "")
			("DFM_EXCLUSION" "")
			("DAY" "")
			("LOCATION" "PR203")
		)
		("@s9s_mb_2u_lib.s9s_mb_2u(sch_1):page452_i185@pure_quanta.q_res(chips)"
			("VARIANT" "*")
			("VALUE" "102K")
			("TOLERANCE" "1%")
			("WATTAGE" "1/16W")
			("PACK_TYPE" "0402LF")
			("MATERIAL" "CHIP")
			("PART_NUMBER" "CS41022FB19")
			("STANDARD" "End of Design")
			("LIFECYCLE" "Comp-Approve")
			("JEDEC_TYPE" "R0402")
			("ALT_SYMBOLS" "(R0402-0201)")
			("TOL" "1%")
			("CLASS" "DISCRETE")
			("DESCRIPTION" "RES CHIP 102K 1/16W +-1%(0402)")
			("COMPONENT_TYPE" "CHIP0402")
			("LEAD_LENGTH" "")
			("DFM_EXCLUSION" "")
			("DAY" "20110826")
			("LOCATION" "PR358")
		)
		("@s9s_mb_2u_lib.s9s_mb_2u(sch_1):page453_i160@pure_quanta.q_res(chips)"
			("VARIANT" "*")
			("VALUE" "0")
			("TOLERANCE" "5%")
			("WATTAGE" "1/16W")
			("PACK_TYPE" "0402LF")
			("MATERIAL" "CHIP")
			("PART_NUMBER" "CS00002JB38")
			("STANDARD" "End of Design")
			("LIFECYCLE" "Comp-Approve")
			("JEDEC_TYPE" "R0402")
			("ALT_SYMBOLS" "(R0402-0201)")
			("TOL" "5%")
			("CLASS" "DISCRETE")
			("DESCRIPTION" "RESISTOR CHIP 0 1/16W +-5%(0402)")
			("COMPONENT_TYPE" "CHIP0402")
			("LEAD_LENGTH" "")
			("DFM_EXCLUSION" "")
			("DAY" "20100618")
			("LOCATION" "PR1784")
		)
		("@s9s_mb_2u_lib.s9s_mb_2u(sch_1):page593_i213@pure_quanta.q_res(chips)"
			("VARIANT" "*")
			("VALUE" "0")
			("TOLERANCE" "5%")
			("WATTAGE" "1/16W")
			("PACK_TYPE" "0402LF")
			("MATERIAL" "CHIP")
			("PART_NUMBER" "CS00002JB38")
			("STANDARD" "End of Design")
			("LIFECYCLE" "Comp-Approve")
			("JEDEC_TYPE" "R0402")
			("ALT_SYMBOLS" "(R0402-0201)")
			("TOL" "5%")
			("CLASS" "DISCRETE")
			("DESCRIPTION" "RESISTOR CHIP 0 1/16W +-5%(0402)")
			("COMPONENT_TYPE" "CHIP0402")
			("LEAD_LENGTH" "")
			("DFM_EXCLUSION" "")
			("DAY" "20100618")
			("LOCATION" "PR1795")
		)
		("@s9s_mb_2u_lib.s9s_mb_2u(sch_1):page593_i212@pure_quanta.q_res(chips)"
			("VARIANT" "*")
			("VALUE" "0")
			("TOLERANCE" "5%")
			("WATTAGE" "1/16W")
			("PACK_TYPE" "0402LF")
			("MATERIAL" "CHIP")
			("PART_NUMBER" "CS00002JB38")
			("STANDARD" "End of Design")
			("LIFECYCLE" "Comp-Approve")
			("JEDEC_TYPE" "R0402")
			("ALT_SYMBOLS" "(R0402-0201)")
			("TOL" "5%")
			("CLASS" "DISCRETE")
			("DESCRIPTION" "RESISTOR CHIP 0 1/16W +-5%(0402)")
			("COMPONENT_TYPE" "CHIP0402")
			("LEAD_LENGTH" "")
			("DFM_EXCLUSION" "")
			("DAY" "20100618")
			("LOCATION" "PR1794")
		)
		("@s9s_mb_2u_lib.s9s_mb_2u(sch_1):page595_i47@pure_quanta.q_res(chips)"
			("VARIANT" "*")
			("VALUE" "0")
			("TOLERANCE" "5%")
			("WATTAGE" "1/16W")
			("PACK_TYPE" "0402LF")
			("MATERIAL" "CHIP")
			("PART_NUMBER" "CS00002JB38")
			("STANDARD" "End of Design")
			("LIFECYCLE" "Comp-Approve")
			("JEDEC_TYPE" "R0402")
			("ALT_SYMBOLS" "(R0402-0201)")
			("TOL" "5%")
			("CLASS" "DISCRETE")
			("DESCRIPTION" "RESISTOR CHIP 0 1/16W +-5%(0402)")
			("COMPONENT_TYPE" "CHIP0402")
			("LEAD_LENGTH" "")
			("DFM_EXCLUSION" "")
			("DAY" "20100618")
			("LOCATION" "PR1798")
		)
		("@s9s_mb_2u_lib.s9s_mb_2u(sch_1):page603_i161@pure_quanta.q_res(chips)"
			("VARIANT" "*")
			("VALUE" "0")
			("TOLERANCE" "5%")
			("WATTAGE" "1/16W")
			("PACK_TYPE" "0402LF")
			("MATERIAL" "CHIP")
			("PART_NUMBER" "CS00002JB38")
			("STANDARD" "End of Design")
			("LIFECYCLE" "Comp-Approve")
			("JEDEC_TYPE" "R0402")
			("ALT_SYMBOLS" "(R0402-0201)")
			("TOL" "5%")
			("CLASS" "DISCRETE")
			("DESCRIPTION" "RESISTOR CHIP 0 1/16W +-5%(0402)")
			("COMPONENT_TYPE" "CHIP0402")
			("LEAD_LENGTH" "")
			("DFM_EXCLUSION" "")
			("DAY" "20100618")
			("LOCATION" "PR1804")
		)
		("@s9s_mb_2u_lib.s9s_mb_2u(sch_1):page442_i223@pure_quanta.q_res(chips)"
			("VARIANT" "*")
			("VALUE" "0")
			("TOLERANCE" "5%")
			("WATTAGE" "1/16W")
			("PACK_TYPE" "0402LF")
			("MATERIAL" "CHIP")
			("PART_NUMBER" "CS00002JB38")
			("STANDARD" "End of Design")
			("LIFECYCLE" "Comp-Approve")
			("JEDEC_TYPE" "R0402")
			("ALT_SYMBOLS" "(R0402-0201)")
			("TOL" "5%")
			("CLASS" "DISCRETE")
			("DESCRIPTION" "RESISTOR CHIP 0 1/16W +-5%(0402)")
			("COMPONENT_TYPE" "CHIP0402")
			("LEAD_LENGTH" "")
			("DFM_EXCLUSION" "")
			("DAY" "20100618")
			("LOCATION" "PR1775")
		)
		("@s9s_mb_2u_lib.s9s_mb_2u(sch_1):page442_i221@pure_quanta.q_res(chips)"
			("VARIANT" "*")
			("VALUE" "0")
			("TOLERANCE" "5%")
			("WATTAGE" "1/16W")
			("PACK_TYPE" "0402LF")
			("MATERIAL" "CHIP")
			("PART_NUMBER" "CS00002JB38")
			("STANDARD" "End of Design")
			("LIFECYCLE" "Comp-Approve")
			("JEDEC_TYPE" "R0402")
			("ALT_SYMBOLS" "(R0402-0201)")
			("TOL" "5%")
			("CLASS" "DISCRETE")
			("DESCRIPTION" "RESISTOR CHIP 0 1/16W +-5%(0402)")
			("COMPONENT_TYPE" "CHIP0402")
			("LEAD_LENGTH" "")
			("DFM_EXCLUSION" "")
			("DAY" "20100618")
			("LOCATION" "PR1774")
		)
		("@s9s_mb_2u_lib.s9s_mb_2u(sch_1):page444_i44@pure_quanta.q_res(chips)"
			("VARIANT" "*")
			("VALUE" "0")
			("TOLERANCE" "5%")
			("WATTAGE" "1/16W")
			("PACK_TYPE" "0402LF")
			("MATERIAL" "CHIP")
			("PART_NUMBER" "CS00002JB38")
			("STANDARD" "End of Design")
			("LIFECYCLE" "Comp-Approve")
			("JEDEC_TYPE" "R0402")
			("ALT_SYMBOLS" "(R0402-0201)")
			("TOL" "5%")
			("CLASS" "DISCRETE")
			("DESCRIPTION" "RESISTOR CHIP 0 1/16W +-5%(0402)")
			("COMPONENT_TYPE" "CHIP0402")
			("LEAD_LENGTH" "")
			("DFM_EXCLUSION" "")
			("DAY" "20100618")
			("LOCATION" "PR1778")
		)
		("@s9s_mb_2u_lib.s9s_mb_2u(sch_1):page602_i181@pure_quanta.q_res(chips)"
			("VARIANT" "*")
			("VALUE" "0")
			("TOLERANCE" "5%")
			("WATTAGE" "1/16W")
			("PACK_TYPE" "0402LF")
			("MATERIAL" "CHIP")
			("PART_NUMBER" "CS00002JB38")
			("STANDARD" "End of Design")
			("LIFECYCLE" "Comp-Approve")
			("JEDEC_TYPE" "R0402")
			("ALT_SYMBOLS" "(R0402-0201)")
			("TOL" "5%")
			("CLASS" "DISCRETE")
			("DESCRIPTION" "RESISTOR CHIP 0 1/16W +-5%(0402)")
			("COMPONENT_TYPE" "CHIP0402")
			("LEAD_LENGTH" "")
			("DFM_EXCLUSION" "")
			("DAY" "20100618")
			("LOCATION" "PR1410")
		)
		("@s9s_mb_2u_lib.s9s_mb_2u(sch_1):page602_i182@pure_quanta.q_res(chips)"
			("VARIANT" "*")
			("VALUE" "0")
			("TOLERANCE" "5%")
			("WATTAGE" "1/16W")
			("PACK_TYPE" "0402LF")
			("MATERIAL" "CHIP")
			("PART_NUMBER" "CS00002JB38")
			("STANDARD" "End of Design")
			("LIFECYCLE" "Comp-Approve")
			("JEDEC_TYPE" "R0402")
			("ALT_SYMBOLS" "(R0402-0201)")
			("TOL" "5%")
			("CLASS" "DISCRETE")
			("DESCRIPTION" "RESISTOR CHIP 0 1/16W +-5%(0402)")
			("COMPONENT_TYPE" "CHIP0402")
			("LEAD_LENGTH" "")
			("DFM_EXCLUSION" "")
			("DAY" "20100618")
			("LOCATION" "PR1400")
		)
		("@s9s_mb_2u_lib.s9s_mb_2u(sch_1):page452_i180@pure_quanta.q_res(chips)"
			("VARIANT" "*")
			("VALUE" "0")
			("TOLERANCE" "5%")
			("WATTAGE" "1/16W")
			("PACK_TYPE" "0402LF")
			("MATERIAL" "CHIP")
			("PART_NUMBER" "CS00002JB38")
			("STANDARD" "End of Design")
			("LIFECYCLE" "Comp-Approve")
			("JEDEC_TYPE" "R0402")
			("ALT_SYMBOLS" "(R0402-0201)")
			("TOL" "5%")
			("CLASS" "DISCRETE")
			("DESCRIPTION" "RESISTOR CHIP 0 1/16W +-5%(0402)")
			("COMPONENT_TYPE" "CHIP0402")
			("LEAD_LENGTH" "")
			("DFM_EXCLUSION" "")
			("DAY" "20100618")
			("LOCATION" "PR1390")
		)
		("@s9s_mb_2u_lib.s9s_mb_2u(sch_1):page452_i183@pure_quanta.q_res(chips)"
			("VARIANT" "*")
			("VALUE" "0")
			("TOLERANCE" "5%")
			("WATTAGE" "1/16W")
			("PACK_TYPE" "0402LF")
			("MATERIAL" "CHIP")
			("PART_NUMBER" "CS00002JB38")
			("STANDARD" "End of Design")
			("LIFECYCLE" "Comp-Approve")
			("JEDEC_TYPE" "R0402")
			("ALT_SYMBOLS" "(R0402-0201)")
			("TOL" "5%")
			("CLASS" "DISCRETE")
			("DESCRIPTION" "RESISTOR CHIP 0 1/16W +-5%(0402)")
			("COMPONENT_TYPE" "CHIP0402")
			("LEAD_LENGTH" "")
			("DFM_EXCLUSION" "")
			("DAY" "20100618")
			("LOCATION" "PR1380")
		)
		("@s9s_mb_2u_lib.s9s_mb_2u(sch_1):page433_i26@pure_quanta.q_res(chips)"
			("VARIANT" "*")
			("VALUE" "7.32K")
			("TOLERANCE" "1%")
			("WATTAGE" "1/16W")
			("PACK_TYPE" "0402LF")
			("MATERIAL" "CHIP")
			("PART_NUMBER" "TMP_QCS27322FB12")
			("STANDARD" "End of Design")
			("LIFECYCLE" "Comp-Approve")
			("JEDEC_TYPE" "R0402")
			("ALT_SYMBOLS" "(R0402-0201)")
			("TOL" "1%")
			("CLASS" "DISCRETE")
			("DESCRIPTION" "7.32Kohm 0402")
			("COMPONENT_TYPE" "CHIP0402")
			("LEAD_LENGTH" "")
			("DFM_EXCLUSION" "")
			("DAY" "")
			("LOCATION" "PR318")
		)
		("@s9s_mb_2u_lib.s9s_mb_2u(sch_1):page453_i110@pure_quanta.raa2213404gnphb0(chips)"
			("VARIANT" "*")
			("VALUE" "FDMF5076")
			("PART_TYPE" "SMLF")
			("MATERIAL" "IC")
			("PART_NUMBER" "AL005076000")
			("STANDARD" "")
			("LIFECYCLE" "")
			("JEDEC_TYPE" "PQFN17_TH_5X4XA")
			("DESCRIPTION" "IC OTHER(27P)FDMF5076(PQFN)")
			("MANUFTR" "ONS")
			("MANUF_PN" "FDMF5076")
			("RD_CMPLS_LVL" "EP(V1)")
			("CMPLS_LVL" "EP(V1)")
			("FROM_PJ" "S9S-KIMI")
			("CLASS" "IC")
			("DIP_SMD" "")
			("DATA" "ONS_FDMF5076.pdf")
			("EE_CHECK_LIST" "")
			("FP_ECN" "FDMF5076.msg")
			("PSL" "")
			("CREATOR" "")
			("STATUS" "")
			("MSD" "NA")
			("ESD_CDM" "NA")
			("ESD_HBM" "NA")
			("ESD_MM" "NA")
			("PIN_LENGTH_SHORT_PIN" "0 MILS")
			("PIN_LENGTH_LONG_PIN" "0 MILS")
			("CREATEDAY" "20200416")
			("LOCATION" "PU36")
		)
		("@s9s_mb_2u_lib.s9s_mb_2u(sch_1):page593_i183@pure_quanta.raa2213404gnphb0(chips)"
			("VARIANT" "*")
			("VALUE" "FDMF5076")
			("PART_TYPE" "SMLF")
			("MATERIAL" "IC")
			("PART_NUMBER" "AL005076000")
			("STANDARD" "")
			("LIFECYCLE" "")
			("JEDEC_TYPE" "PQFN17_TH_5X4XA")
			("DESCRIPTION" "IC OTHER(27P)FDMF5076(PQFN)")
			("MANUFTR" "ONS")
			("MANUF_PN" "FDMF5076")
			("RD_CMPLS_LVL" "EP(V1)")
			("CMPLS_LVL" "EP(V1)")
			("FROM_PJ" "S9S-KIMI")
			("CLASS" "IC")
			("DIP_SMD" "")
			("DATA" "ONS_FDMF5076.pdf")
			("EE_CHECK_LIST" "")
			("FP_ECN" "FDMF5076.msg")
			("PSL" "")
			("CREATOR" "")
			("STATUS" "")
			("MSD" "NA")
			("ESD_CDM" "NA")
			("ESD_HBM" "NA")
			("ESD_MM" "NA")
			("PIN_LENGTH_SHORT_PIN" "0 MILS")
			("PIN_LENGTH_LONG_PIN" "0 MILS")
			("CREATEDAY" "20200416")
			("LOCATION" "PU51_P1_2")
		)
		("@s9s_mb_2u_lib.s9s_mb_2u(sch_1):page593_i148@pure_quanta.raa2213404gnphb0(chips)"
			("VARIANT" "*")
			("VALUE" "FDMF5076")
			("PART_TYPE" "SMLF")
			("MATERIAL" "IC")
			("PART_NUMBER" "AL005076000")
			("STANDARD" "")
			("LIFECYCLE" "")
			("JEDEC_TYPE" "PQFN17_TH_5X4XA")
			("DESCRIPTION" "IC OTHER(27P)FDMF5076(PQFN)")
			("MANUFTR" "ONS")
			("MANUF_PN" "FDMF5076")
			("RD_CMPLS_LVL" "EP(V1)")
			("CMPLS_LVL" "EP(V1)")
			("FROM_PJ" "S9S-KIMI")
			("CLASS" "IC")
			("DIP_SMD" "")
			("DATA" "ONS_FDMF5076.pdf")
			("EE_CHECK_LIST" "")
			("FP_ECN" "FDMF5076.msg")
			("PSL" "")
			("CREATOR" "")
			("STATUS" "")
			("MSD" "NA")
			("ESD_CDM" "NA")
			("ESD_HBM" "NA")
			("ESD_MM" "NA")
			("PIN_LENGTH_SHORT_PIN" "0 MILS")
			("PIN_LENGTH_LONG_PIN" "0 MILS")
			("CREATEDAY" "20200416")
			("LOCATION" "PU50_P1_1")
		)
		("@s9s_mb_2u_lib.s9s_mb_2u(sch_1):page595_i26@pure_quanta.raa2213404gnphb0(chips)"
			("VARIANT" "*")
			("VALUE" "FDMF5076")
			("PART_TYPE" "SMLF")
			("MATERIAL" "IC")
			("PART_NUMBER" "AL005076000")
			("STANDARD" "")
			("LIFECYCLE" "")
			("JEDEC_TYPE" "PQFN17_TH_5X4XA")
			("DESCRIPTION" "IC OTHER(27P)FDMF5076(PQFN)")
			("MANUFTR" "ONS")
			("MANUF_PN" "FDMF5076")
			("RD_CMPLS_LVL" "EP(V1)")
			("CMPLS_LVL" "EP(V1)")
			("FROM_PJ" "S9S-KIMI")
			("CLASS" "IC")
			("DIP_SMD" "")
			("DATA" "ONS_FDMF5076.pdf")
			("EE_CHECK_LIST" "")
			("FP_ECN" "FDMF5076.msg")
			("PSL" "")
			("CREATOR" "")
			("STATUS" "")
			("MSD" "NA")
			("ESD_CDM" "NA")
			("ESD_HBM" "NA")
			("ESD_MM" "NA")
			("PIN_LENGTH_SHORT_PIN" "0 MILS")
			("PIN_LENGTH_LONG_PIN" "0 MILS")
			("CREATEDAY" "20200416")
			("LOCATION" "PU49")
		)
		("@s9s_mb_2u_lib.s9s_mb_2u(sch_1):page603_i110@pure_quanta.raa2213404gnphb0(chips)"
			("VARIANT" "*")
			("VALUE" "FDMF5076")
			("PART_TYPE" "SMLF")
			("MATERIAL" "IC")
			("PART_NUMBER" "AL005076000")
			("STANDARD" "")
			("LIFECYCLE" "")
			("JEDEC_TYPE" "PQFN17_TH_5X4XA")
			("DESCRIPTION" "IC OTHER(27P)FDMF5076(PQFN)")
			("MANUFTR" "ONS")
			("MANUF_PN" "FDMF5076")
			("RD_CMPLS_LVL" "EP(V1)")
			("CMPLS_LVL" "EP(V1)")
			("FROM_PJ" "S9S-KIMI")
			("CLASS" "IC")
			("DIP_SMD" "")
			("DATA" "ONS_FDMF5076.pdf")
			("EE_CHECK_LIST" "")
			("FP_ECN" "FDMF5076.msg")
			("PSL" "")
			("CREATOR" "")
			("STATUS" "")
			("MSD" "NA")
			("ESD_CDM" "NA")
			("ESD_HBM" "NA")
			("ESD_MM" "NA")
			("PIN_LENGTH_SHORT_PIN" "0 MILS")
			("PIN_LENGTH_LONG_PIN" "0 MILS")
			("CREATEDAY" "20200416")
			("LOCATION" "PU17")
		)
		("@s9s_mb_2u_lib.s9s_mb_2u(sch_1):page442_i183@pure_quanta.raa2213404gnphb0(chips)"
			("VARIANT" "*")
			("VALUE" "FDMF5076")
			("PART_TYPE" "SMLF")
			("MATERIAL" "IC")
			("PART_NUMBER" "AL005076000")
			("STANDARD" "")
			("LIFECYCLE" "")
			("JEDEC_TYPE" "PQFN17_TH_5X4XA")
			("DESCRIPTION" "IC OTHER(27P)FDMF5076(PQFN)")
			("MANUFTR" "ONS")
			("MANUF_PN" "FDMF5076")
			("RD_CMPLS_LVL" "EP(V1)")
			("CMPLS_LVL" "EP(V1)")
			("FROM_PJ" "S9S-KIMI")
			("CLASS" "IC")
			("DIP_SMD" "")
			("DATA" "ONS_FDMF5076.pdf")
			("EE_CHECK_LIST" "")
			("FP_ECN" "FDMF5076.msg")
			("PSL" "")
			("CREATOR" "")
			("STATUS" "")
			("MSD" "NA")
			("ESD_CDM" "NA")
			("ESD_HBM" "NA")
			("ESD_MM" "NA")
			("PIN_LENGTH_SHORT_PIN" "0 MILS")
			("PIN_LENGTH_LONG_PIN" "0 MILS")
			("CREATEDAY" "20200416")
			("LOCATION" "PU44_P0_2")
		)
		("@s9s_mb_2u_lib.s9s_mb_2u(sch_1):page442_i241@pure_quanta.raa2213404gnphb0(chips)"
			("VARIANT" "*")
			("PART_TYPE" "SMLF")
			("MATERIAL" "IC")
			("VALUE" "FDMF5076")
			("PART_NUMBER" "AL005076000")
			("PIN_LENGTH_LONG_PIN" "0 MILS")
			("MSD" "NA")
			("DESCRIPTION" "IC OTHER(27P)FDMF5076(PQFN)")
			("EE_CHECK_LIST" "")
			("CLASS" "IC")
			("MANUFTR" "ONS")
			("ESD_MM" "NA")
			("ESD_CDM" "NA")
			("FROM_PJ" "S9S-KIMI")
			("DIP_SMD" "")
			("CREATEDAY" "20200416")
			("STANDARD" "")
			("PIN_LENGTH_SHORT_PIN" "0 MILS")
			("ESD_HBM" "NA")
			("LIFECYCLE" "")
			("STATUS" "")
			("PSL" "")
			("RD_CMPLS_LVL" "EP(V1)")
			("FP_ECN" "FDMF5076.msg")
			("MANUF_PN" "FDMF5076")
			("CMPLS_LVL" "EP(V1)")
			("JEDEC_TYPE" "PQFN17_TH_5X4XA")
			("DATA" "ONS_FDMF5076.pdf")
			("CREATOR" "")
			("LOCATION" "PU43_P0_1")
		)
		("@s9s_mb_2u_lib.s9s_mb_2u(sch_1):page444_i53@pure_quanta.raa2213404gnphb0(chips)"
			("VARIANT" "*")
			("VALUE" "FDMF5076")
			("PART_TYPE" "SMLF")
			("MATERIAL" "IC")
			("PART_NUMBER" "AL005076000")
			("STANDARD" "")
			("LIFECYCLE" "")
			("JEDEC_TYPE" "PQFN17_TH_5X4XA")
			("DESCRIPTION" "IC OTHER(27P)FDMF5076(PQFN)")
			("MANUFTR" "ONS")
			("MANUF_PN" "FDMF5076")
			("RD_CMPLS_LVL" "EP(V1)")
			("CMPLS_LVL" "EP(V1)")
			("FROM_PJ" "S9S-KIMI")
			("CLASS" "IC")
			("DIP_SMD" "")
			("DATA" "ONS_FDMF5076.pdf")
			("EE_CHECK_LIST" "")
			("FP_ECN" "FDMF5076.msg")
			("PSL" "")
			("CREATOR" "")
			("STATUS" "")
			("MSD" "NA")
			("ESD_CDM" "NA")
			("ESD_HBM" "NA")
			("ESD_MM" "NA")
			("PIN_LENGTH_SHORT_PIN" "0 MILS")
			("PIN_LENGTH_LONG_PIN" "0 MILS")
			("CREATEDAY" "20200416")
			("LOCATION" "PU42")
		)
		("@s9s_mb_2u_lib.s9s_mb_2u(sch_1):page585_i21@pure_quanta.isl99390frztr5935(chips)"
			("VARIANT" "*")
			("PART_TYPE" "SMLF")
			("MATERIAL" "IC")
			("VALUE" "FDMF5085")
			("PART_NUMBER" "AL005085000")
			("PIN_LENGTH_LONG_PIN" "0 MILS")
			("MSD" "NA")
			("DESCRIPTION" "IC OTHER(39P) FDMF5085(PQFN)")
			("EE_CHECK_LIST" "")
			("CLASS" "IC")
			("MANUFTR" "ONS")
			("ESD_MM" "NA")
			("ESD_CDM" "NA")
			("FROM_PJ" "S9S-KIMI")
			("DIP_SMD" "")
			("CREATEDAY" "20200423")
			("STANDARD" "")
			("PIN_LENGTH_SHORT_PIN" "0 MILS")
			("ESD_HBM" "NA")
			("LIFECYCLE" "")
			("STATUS" "")
			("PSL" "")
			("RD_CMPLS_LVL" "EP(V1)")
			("FP_ECN" "")
			("MANUF_PN" "FDMF5085")
			("CMPLS_LVL" "")
			("JEDEC_TYPE" "PQFN21_6X5XB")
			("DATA" "ONS_FDMF5085.pdf")
			("CREATOR" "")
			("LOCATION" "PU13_P0_1")
		)
		("@s9s_mb_2u_lib.s9s_mb_2u(sch_1):page585_i79@pure_quanta.isl99390frztr5935(chips)"
			("VARIANT" "*")
			("VALUE" "FDMF5085")
			("PART_TYPE" "SMLF")
			("MATERIAL" "IC")
			("PART_NUMBER" "AL005085000")
			("STANDARD" "")
			("LIFECYCLE" "")
			("JEDEC_TYPE" "PQFN21_6X5XB")
			("DESCRIPTION" "IC OTHER(39P) FDMF5085(PQFN)")
			("MANUFTR" "ONS")
			("MANUF_PN" "FDMF5085")
			("RD_CMPLS_LVL" "EP(V1)")
			("CMPLS_LVL" "")
			("FROM_PJ" "S9S-KIMI")
			("CLASS" "IC")
			("DIP_SMD" "")
			("DATA" "ONS_FDMF5085.pdf")
			("EE_CHECK_LIST" "")
			("FP_ECN" "")
			("PSL" "")
			("CREATOR" "")
			("STATUS" "")
			("MSD" "NA")
			("ESD_CDM" "NA")
			("ESD_HBM" "NA")
			("ESD_MM" "NA")
			("PIN_LENGTH_SHORT_PIN" "0 MILS")
			("PIN_LENGTH_LONG_PIN" "0 MILS")
			("CREATEDAY" "20200423")
			("LOCATION" "PU12_P0_2")
		)
		("@s9s_mb_2u_lib.s9s_mb_2u(sch_1):page436_i25@pure_quanta.isl99390frztr5935(chips)"
			("VARIANT" "*")
			("VALUE" "FDMF5085")
			("PART_TYPE" "SMLF")
			("MATERIAL" "IC")
			("PART_NUMBER" "AL005085000")
			("STANDARD" "")
			("LIFECYCLE" "")
			("JEDEC_TYPE" "PQFN21_6X5XB")
			("DESCRIPTION" "IC OTHER(39P) FDMF5085(PQFN)")
			("MANUFTR" "ONS")
			("MANUF_PN" "FDMF5085")
			("RD_CMPLS_LVL" "EP(V1)")
			("CMPLS_LVL" "")
			("FROM_PJ" "S9S-KIMI")
			("CLASS" "IC")
			("DIP_SMD" "")
			("DATA" "ONS_FDMF5085.pdf")
			("EE_CHECK_LIST" "")
			("FP_ECN" "")
			("PSL" "")
			("CREATOR" "")
			("STATUS" "")
			("MSD" "NA")
			("ESD_CDM" "NA")
			("ESD_HBM" "NA")
			("ESD_MM" "NA")
			("PIN_LENGTH_SHORT_PIN" "0 MILS")
			("PIN_LENGTH_LONG_PIN" "0 MILS")
			("CREATEDAY" "20200423")
			("LOCATION" "PU11_P0_3")
		)
		("@s9s_mb_2u_lib.s9s_mb_2u(sch_1):page436_i21@pure_quanta.isl99390frztr5935(chips)"
			("VARIANT" "*")
			("VALUE" "FDMF5085")
			("PART_TYPE" "SMLF")
			("MATERIAL" "IC")
			("PART_NUMBER" "AL005085000")
			("STANDARD" "")
			("LIFECYCLE" "")
			("JEDEC_TYPE" "PQFN21_6X5XB")
			("DESCRIPTION" "IC OTHER(39P) FDMF5085(PQFN)")
			("MANUFTR" "ONS")
			("MANUF_PN" "FDMF5085")
			("RD_CMPLS_LVL" "EP(V1)")
			("CMPLS_LVL" "")
			("FROM_PJ" "S9S-KIMI")
			("CLASS" "IC")
			("DIP_SMD" "")
			("DATA" "ONS_FDMF5085.pdf")
			("EE_CHECK_LIST" "")
			("FP_ECN" "")
			("PSL" "")
			("CREATOR" "")
			("STATUS" "")
			("MSD" "NA")
			("ESD_CDM" "NA")
			("ESD_HBM" "NA")
			("ESD_MM" "NA")
			("PIN_LENGTH_SHORT_PIN" "0 MILS")
			("PIN_LENGTH_LONG_PIN" "0 MILS")
			("CREATEDAY" "20200423")
			("LOCATION" "PU10_P0_4")
		)
		("@s9s_mb_2u_lib.s9s_mb_2u(sch_1):page437_i27@pure_quanta.isl99390frztr5935(chips)"
			("VARIANT" "*")
			("VALUE" "FDMF5085")
			("PART_TYPE" "SMLF")
			("MATERIAL" "IC")
			("PART_NUMBER" "AL005085000")
			("STANDARD" "")
			("LIFECYCLE" "")
			("JEDEC_TYPE" "PQFN21_6X5XB")
			("DESCRIPTION" "IC OTHER(39P) FDMF5085(PQFN)")
			("MANUFTR" "ONS")
			("MANUF_PN" "FDMF5085")
			("RD_CMPLS_LVL" "EP(V1)")
			("CMPLS_LVL" "")
			("FROM_PJ" "S9S-KIMI")
			("CLASS" "IC")
			("DIP_SMD" "")
			("DATA" "ONS_FDMF5085.pdf")
			("EE_CHECK_LIST" "")
			("FP_ECN" "")
			("PSL" "")
			("CREATOR" "")
			("STATUS" "")
			("MSD" "NA")
			("ESD_CDM" "NA")
			("ESD_HBM" "NA")
			("ESD_MM" "NA")
			("PIN_LENGTH_SHORT_PIN" "0 MILS")
			("PIN_LENGTH_LONG_PIN" "0 MILS")
			("CREATEDAY" "20200423")
			("LOCATION" "PU9_P0_5")
		)
		("@s9s_mb_2u_lib.s9s_mb_2u(sch_1):page437_i8@pure_quanta.isl99390frztr5935(chips)"
			("VARIANT" "*")
			("VALUE" "FDMF5085")
			("PART_TYPE" "SMLF")
			("MATERIAL" "IC")
			("PART_NUMBER" "AL005085000")
			("STANDARD" "")
			("LIFECYCLE" "")
			("JEDEC_TYPE" "PQFN21_6X5XB")
			("DESCRIPTION" "IC OTHER(39P) FDMF5085(PQFN)")
			("MANUFTR" "ONS")
			("MANUF_PN" "FDMF5085")
			("RD_CMPLS_LVL" "EP(V1)")
			("CMPLS_LVL" "")
			("FROM_PJ" "S9S-KIMI")
			("CLASS" "IC")
			("DIP_SMD" "")
			("DATA" "ONS_FDMF5085.pdf")
			("EE_CHECK_LIST" "")
			("FP_ECN" "")
			("PSL" "")
			("CREATOR" "")
			("STATUS" "")
			("MSD" "NA")
			("ESD_CDM" "NA")
			("ESD_HBM" "NA")
			("ESD_MM" "NA")
			("PIN_LENGTH_SHORT_PIN" "0 MILS")
			("PIN_LENGTH_LONG_PIN" "0 MILS")
			("CREATEDAY" "20200423")
			("LOCATION" "PU8_P0_6")
		)
		("@s9s_mb_2u_lib.s9s_mb_2u(sch_1):page438_i25@pure_quanta.isl99390frztr5935(chips)"
			("VARIANT" "*")
			("VALUE" "FDMF5085")
			("PART_TYPE" "SMLF")
			("MATERIAL" "IC")
			("PART_NUMBER" "AL005085000")
			("STANDARD" "")
			("LIFECYCLE" "")
			("JEDEC_TYPE" "PQFN21_6X5XB")
			("DESCRIPTION" "IC OTHER(39P) FDMF5085(PQFN)")
			("MANUFTR" "ONS")
			("MANUF_PN" "FDMF5085")
			("RD_CMPLS_LVL" "EP(V1)")
			("CMPLS_LVL" "")
			("FROM_PJ" "S9S-KIMI")
			("CLASS" "IC")
			("DIP_SMD" "")
			("DATA" "ONS_FDMF5085.pdf")
			("EE_CHECK_LIST" "")
			("FP_ECN" "")
			("PSL" "")
			("CREATOR" "")
			("STATUS" "")
			("MSD" "NA")
			("ESD_CDM" "NA")
			("ESD_HBM" "NA")
			("ESD_MM" "NA")
			("PIN_LENGTH_SHORT_PIN" "0 MILS")
			("PIN_LENGTH_LONG_PIN" "0 MILS")
			("CREATEDAY" "20200423")
			("LOCATION" "PU7_P0_7")
		)
		("@s9s_mb_2u_lib.s9s_mb_2u(sch_1):page438_i7@pure_quanta.isl99390frztr5935(chips)"
			("VARIANT" "*")
			("VALUE" "FDMF5085")
			("PART_TYPE" "SMLF")
			("MATERIAL" "IC")
			("PART_NUMBER" "AL005085000")
			("STANDARD" "")
			("LIFECYCLE" "")
			("JEDEC_TYPE" "PQFN21_6X5XB")
			("DESCRIPTION" "IC OTHER(39P) FDMF5085(PQFN)")
			("MANUFTR" "ONS")
			("MANUF_PN" "FDMF5085")
			("RD_CMPLS_LVL" "EP(V1)")
			("CMPLS_LVL" "")
			("FROM_PJ" "S9S-KIMI")
			("CLASS" "IC")
			("DIP_SMD" "")
			("DATA" "ONS_FDMF5085.pdf")
			("EE_CHECK_LIST" "")
			("FP_ECN" "")
			("PSL" "")
			("CREATOR" "")
			("STATUS" "")
			("MSD" "NA")
			("ESD_CDM" "NA")
			("ESD_HBM" "NA")
			("ESD_MM" "NA")
			("PIN_LENGTH_SHORT_PIN" "0 MILS")
			("PIN_LENGTH_LONG_PIN" "0 MILS")
			("CREATEDAY" "20200423")
			("LOCATION" "PU6_P0_8")
		)
		("@s9s_mb_2u_lib.s9s_mb_2u(sch_1):page440_i412@pure_quanta.isl69260irazt(chips)"
			("VARIANT" "*")
			("VALUE" "FD5001")
			("PART_TYPE" "SMLF")
			("MATERIAL" "IC")
			("PART_NUMBER" "AL005001004")
			("STANDARD" "")
			("LIFECYCLE" "")
			("JEDEC_TYPE" "VFQFPN40_TH_0-4_5X5XC")
			("DESCRIPTION" "IC OTHER(40P) FD5001(QFN)")
			("MANUFTR" "ONS")
			("MANUF_PN" "FD5001")
			("RD_CMPLS_LVL" "EP(V1)")
			("CMPLS_LVL" "")
			("FROM_PJ" "S9S-KIMI")
			("CLASS" "IC")
			("DIP_SMD" "")
			("DATA" "ONS_FD5001.pdf")
			("EE_CHECK_LIST" "")
			("FP_ECN" "FD5001.msg")
			("PSL" "")
			("CREATOR" "")
			("STATUS" "")
			("MSD" "NA")
			("ESD_CDM" "NA")
			("ESD_HBM" "NA")
			("ESD_MM" "NA")
			("PIN_LENGTH_SHORT_PIN" "0 MILS")
			("PIN_LENGTH_LONG_PIN" "0 MILS")
			("CREATEDAY" "20200421")
			("LOCATION" "PU5")
		)
		("@s9s_mb_2u_lib.s9s_mb_2u(sch_1):page440_i254@pure_quanta.q_cap(chips)"
			("VARIANT" "*")
			("VALUE" "1NF")
			("VOLTAGE" "50V")
			("TOLERANCE" "10%")
			("PACK_TYPE" "0402")
			("MATERIAL" "X7R")
			("PART_NUMBER" "CH21006KB16")
			("STANDARD" "")
			("LIFECYCLE" "")
			("ASS_PART" "")
			("JEDEC_TYPE" "C0402")
			("ALT_SYMBOLS" "(C0402-0201)")
			("RATED_VOLTAGE" "50V")
			("TOL" "10%")
			("CLASS" "DISCRETE")
			("DESCRIPTION" "CAP CHIP 1N 50V(+-10%,X7R,0402)EP")
			("COMPONENT_TYPE" "CHIP0402")
			("LEAD_LENGTH" "")
			("LPID" "")
			("DATE" "20100811")
			("LOCATION" "PC215")
		)
		("@s9s_mb_2u_lib.s9s_mb_2u(sch_1):page440_i263@pure_quanta.q_cap(chips)"
			("VARIANT" "*")
			("VALUE" "1NF")
			("VOLTAGE" "50V")
			("TOLERANCE" "10%")
			("PACK_TYPE" "0402")
			("MATERIAL" "X7R")
			("PART_NUMBER" "CH21006KB16")
			("STANDARD" "")
			("LIFECYCLE" "")
			("ASS_PART" "")
			("JEDEC_TYPE" "C0402")
			("ALT_SYMBOLS" "(C0402-0201)")
			("RATED_VOLTAGE" "50V")
			("TOL" "10%")
			("CLASS" "DISCRETE")
			("DESCRIPTION" "CAP CHIP 1N 50V(+-10%,X7R,0402)EP")
			("COMPONENT_TYPE" "CHIP0402")
			("LEAD_LENGTH" "")
			("LPID" "")
			("DATE" "20100811")
			("LOCATION" "PC216")
		)
		("@s9s_mb_2u_lib.s9s_mb_2u(sch_1):page440_i390@pure_quanta.q_cap(chips)"
			("VARIANT" "*")
			("VALUE" "2200PF")
			("VOLTAGE" "50V")
			("TOLERANCE" "10%")
			("PACK_TYPE" "C0402")
			("MATERIAL" "X7R")
			("PART_NUMBER" "CH2226K1B06")
			("STANDARD" "")
			("LIFECYCLE" "")
			("ASS_PART" "")
			("JEDEC_TYPE" "C0402")
			("ALT_SYMBOLS" "(C0402-0201)")
			("RATED_VOLTAGE" "50V")
			("TOL" "10%")
			("CLASS" "DISCRETE")
			("DESCRIPTION" "CAP CHIP 2200P 50V(+-10%,X7R,0402)MUR")
			("COMPONENT_TYPE" "CHIP0402")
			("LEAD_LENGTH" "")
			("LPID" "")
			("DATE" "20150614")
			("LOCATION" "PC1271")
		)
		("@s9s_mb_2u_lib.s9s_mb_2u(sch_1):page440_i368@pure_quanta.q_cap(chips)"
			("VARIANT" "*")
			("VALUE" "2200PF")
			("VOLTAGE" "50V")
			("TOLERANCE" "10%")
			("PACK_TYPE" "C0402")
			("MATERIAL" "X7R")
			("PART_NUMBER" "CH2226K1B06")
			("STANDARD" "")
			("LIFECYCLE" "")
			("ASS_PART" "")
			("JEDEC_TYPE" "C0402")
			("ALT_SYMBOLS" "(C0402-0201)")
			("RATED_VOLTAGE" "50V")
			("TOL" "10%")
			("CLASS" "DISCRETE")
			("DESCRIPTION" "CAP CHIP 2200P 50V(+-10%,X7R,0402)MUR")
			("COMPONENT_TYPE" "CHIP0402")
			("LEAD_LENGTH" "")
			("LPID" "")
			("DATE" "20150614")
			("LOCATION" "PC222")
		)
		("@s9s_mb_2u_lib.s9s_mb_2u(sch_1):page440_i340@pure_quanta.q_cap(chips)"
			("VARIANT" "*")
			("VALUE" "4.7UF")
			("VOLTAGE" "6.3V")
			("TOLERANCE" "20%")
			("PACK_TYPE" "0402")
			("MATERIAL" "EMPTY")
			("PART_NUMBER" "CH5471MEB01")
			("STANDARD" "")
			("LIFECYCLE" "")
			("ASS_PART" "")
			("JEDEC_TYPE" "C0402")
			("ALT_SYMBOLS" "(C0402_OCTAGON,C0402_OCTAGONXA,C0402-0201)")
			("RATED_VOLTAGE" "6.3V")
			("TOL" "20%")
			("CLASS" "IO")
			("DESCRIPTION" "CAP CHIP 4.7UF 6.3V(+-20%,X6S,0402)")
			("COMPONENT_TYPE" "CHIP0402")
			("LEAD_LENGTH" "")
			("LPID" "")
			("DATE" "20151211")
			("LOCATION" "PC224")
		)
		("@s9s_mb_2u_lib.s9s_mb_2u(sch_1):page440_i323@pure_quanta.q_res(chips)"
			("VARIANT" "*")
			("VALUE" "4.12K")
			("TOLERANCE" "1%")
			("WATTAGE" "1/16W")
			("PACK_TYPE" "0402LF")
			("MATERIAL" "CHIP")
			("PART_NUMBER" "CS24122FB17")
			("STANDARD" "End of Design")
			("LIFECYCLE" "Comp-Approve")
			("JEDEC_TYPE" "R0402")
			("ALT_SYMBOLS" "(R0402-0201)")
			("TOL" "1%")
			("CLASS" "DISCRETE")
			("DESCRIPTION" "RES CHIP 4.12K 1/16W +-1%(0402)")
			("COMPONENT_TYPE" "CHIP0402")
			("LEAD_LENGTH" "")
			("DFM_EXCLUSION" "")
			("DAY" "20110805")
			("LOCATION" "PR106")
		)
		("@s9s_mb_2u_lib.s9s_mb_2u(sch_1):page447_i23@pure_quanta.isl99390frztr5935(chips)"
			("VARIANT" "*")
			("VALUE" "FDMF5085")
			("PART_TYPE" "SMLF")
			("MATERIAL" "IC")
			("PART_NUMBER" "AL005085000")
			("STANDARD" "")
			("LIFECYCLE" "")
			("JEDEC_TYPE" "PQFN21_6X5XB")
			("DESCRIPTION" "IC OTHER(39P) FDMF5085(PQFN)")
			("MANUFTR" "ONS")
			("MANUF_PN" "FDMF5085")
			("RD_CMPLS_LVL" "EP(V1)")
			("CMPLS_LVL" "")
			("FROM_PJ" "S9S-KIMI")
			("CLASS" "IC")
			("DIP_SMD" "")
			("DATA" "ONS_FDMF5085.pdf")
			("EE_CHECK_LIST" "")
			("FP_ECN" "")
			("PSL" "")
			("CREATOR" "")
			("STATUS" "")
			("MSD" "NA")
			("ESD_CDM" "NA")
			("ESD_HBM" "NA")
			("ESD_MM" "NA")
			("PIN_LENGTH_SHORT_PIN" "0 MILS")
			("PIN_LENGTH_LONG_PIN" "0 MILS")
			("CREATEDAY" "20200423")
			("LOCATION" "PU69_P0_1")
		)
		("@s9s_mb_2u_lib.s9s_mb_2u(sch_1):page447_i21@pure_quanta.isl99390frztr5935(chips)"
			("VARIANT" "*")
			("VALUE" "FDMF5085")
			("PART_TYPE" "SMLF")
			("MATERIAL" "IC")
			("PART_NUMBER" "AL005085000")
			("STANDARD" "")
			("LIFECYCLE" "")
			("JEDEC_TYPE" "PQFN21_6X5XB")
			("DESCRIPTION" "IC OTHER(39P) FDMF5085(PQFN)")
			("MANUFTR" "ONS")
			("MANUF_PN" "FDMF5085")
			("RD_CMPLS_LVL" "EP(V1)")
			("CMPLS_LVL" "")
			("FROM_PJ" "S9S-KIMI")
			("CLASS" "IC")
			("DIP_SMD" "")
			("DATA" "ONS_FDMF5085.pdf")
			("EE_CHECK_LIST" "")
			("FP_ECN" "")
			("PSL" "")
			("CREATOR" "")
			("STATUS" "")
			("MSD" "NA")
			("ESD_CDM" "NA")
			("ESD_HBM" "NA")
			("ESD_MM" "NA")
			("PIN_LENGTH_SHORT_PIN" "0 MILS")
			("PIN_LENGTH_LONG_PIN" "0 MILS")
			("CREATEDAY" "20200423")
			("LOCATION" "PU70_P0_2")
		)
		("@s9s_mb_2u_lib.s9s_mb_2u(sch_1):page448_i22@pure_quanta.isl99390frztr5935(chips)"
			("VARIANT" "*")
			("VALUE" "FDMF5085")
			("PART_TYPE" "SMLF")
			("MATERIAL" "IC")
			("PART_NUMBER" "AL005085000")
			("STANDARD" "")
			("LIFECYCLE" "")
			("JEDEC_TYPE" "PQFN21_6X5XB")
			("DESCRIPTION" "IC OTHER(39P) FDMF5085(PQFN)")
			("MANUFTR" "ONS")
			("MANUF_PN" "FDMF5085")
			("RD_CMPLS_LVL" "EP(V1)")
			("CMPLS_LVL" "")
			("FROM_PJ" "S9S-KIMI")
			("CLASS" "IC")
			("DIP_SMD" "")
			("DATA" "ONS_FDMF5085.pdf")
			("EE_CHECK_LIST" "")
			("FP_ECN" "")
			("PSL" "")
			("CREATOR" "")
			("STATUS" "")
			("MSD" "NA")
			("ESD_CDM" "NA")
			("ESD_HBM" "NA")
			("ESD_MM" "NA")
			("PIN_LENGTH_SHORT_PIN" "0 MILS")
			("PIN_LENGTH_LONG_PIN" "0 MILS")
			("CREATEDAY" "20200423")
			("LOCATION" "PU71_P0_3")
		)
		("@s9s_mb_2u_lib.s9s_mb_2u(sch_1):page448_i4@pure_quanta.isl99390frztr5935(chips)"
			("VARIANT" "*")
			("VALUE" "FDMF5085")
			("PART_TYPE" "SMLF")
			("MATERIAL" "IC")
			("PART_NUMBER" "AL005085000")
			("STANDARD" "")
			("LIFECYCLE" "")
			("JEDEC_TYPE" "PQFN21_6X5XB")
			("DESCRIPTION" "IC OTHER(39P) FDMF5085(PQFN)")
			("MANUFTR" "ONS")
			("MANUF_PN" "FDMF5085")
			("RD_CMPLS_LVL" "EP(V1)")
			("CMPLS_LVL" "")
			("FROM_PJ" "S9S-KIMI")
			("CLASS" "IC")
			("DIP_SMD" "")
			("DATA" "ONS_FDMF5085.pdf")
			("EE_CHECK_LIST" "")
			("FP_ECN" "")
			("PSL" "")
			("CREATOR" "")
			("STATUS" "")
			("MSD" "NA")
			("ESD_CDM" "NA")
			("ESD_HBM" "NA")
			("ESD_MM" "NA")
			("PIN_LENGTH_SHORT_PIN" "0 MILS")
			("PIN_LENGTH_LONG_PIN" "0 MILS")
			("CREATEDAY" "20200423")
			("LOCATION" "PU72_P0_4")
		)
		("@s9s_mb_2u_lib.s9s_mb_2u(sch_1):page448_i107@pure_quanta.q_cap(chips)"
			("VARIANT" "*")
			("VALUE" "0.1UF")
			("VOLTAGE" "25V")
			("TOLERANCE" "10%")
			("PACK_TYPE" "0402")
			("MATERIAL" "EMPTY")
			("PART_NUMBER" "CH4104K1B00")
			("STANDARD" "")
			("LIFECYCLE" "")
			("ASS_PART" "")
			("JEDEC_TYPE" "C0402")
			("ALT_SYMBOLS" "(C0402_OCTAGONXA,C0402-0201)")
			("RATED_VOLTAGE" "25V")
			("TOL" "10%")
			("CLASS" "IO")
			("DESCRIPTION" "CAP CHIP 0.1U 25V(+-10%,X7R,0402)")
			("COMPONENT_TYPE" "CHIP0402")
			("LEAD_LENGTH" "")
			("LPID" "")
			("DATE" "20160113")
			("LOCATION" "PC1351")
		)
		("@s9s_mb_2u_lib.s9s_mb_2u(sch_1):page448_i109@pure_quanta.q_cap(chips)"
			("VARIANT" "*")
			("VALUE" "0.1UF")
			("VOLTAGE" "25V")
			("TOLERANCE" "10%")
			("PACK_TYPE" "0402")
			("MATERIAL" "EMPTY")
			("PART_NUMBER" "CH4104K1B00")
			("STANDARD" "")
			("LIFECYCLE" "")
			("ASS_PART" "")
			("JEDEC_TYPE" "C0402")
			("ALT_SYMBOLS" "(C0402_OCTAGONXA,C0402-0201)")
			("RATED_VOLTAGE" "25V")
			("TOL" "10%")
			("CLASS" "IO")
			("DESCRIPTION" "CAP CHIP 0.1U 25V(+-10%,X7R,0402)")
			("COMPONENT_TYPE" "CHIP0402")
			("LEAD_LENGTH" "")
			("LPID" "")
			("DATE" "20160113")
			("LOCATION" "PC1352")
		)
		("@s9s_mb_2u_lib.s9s_mb_2u(sch_1):page435_i21@pure_quanta.isl99390frztr5935(chips)"
			("VARIANT" "*")
			("VALUE" "FDMF5085")
			("PART_TYPE" "SMLF")
			("MATERIAL" "IC")
			("PART_NUMBER" "AL005085000")
			("STANDARD" "")
			("LIFECYCLE" "")
			("JEDEC_TYPE" "PQFN21_6X5XB")
			("DESCRIPTION" "IC OTHER(39P) FDMF5085(PQFN)")
			("MANUFTR" "ONS")
			("MANUF_PN" "FDMF5085")
			("RD_CMPLS_LVL" "EP(V1)")
			("CMPLS_LVL" "")
			("FROM_PJ" "S9S-KIMI")
			("CLASS" "IC")
			("DIP_SMD" "")
			("DATA" "ONS_FDMF5085.pdf")
			("EE_CHECK_LIST" "")
			("FP_ECN" "")
			("PSL" "")
			("CREATOR" "")
			("STATUS" "")
			("MSD" "NA")
			("ESD_CDM" "NA")
			("ESD_HBM" "NA")
			("ESD_MM" "NA")
			("PIN_LENGTH_SHORT_PIN" "0 MILS")
			("PIN_LENGTH_LONG_PIN" "0 MILS")
			("CREATEDAY" "20200423")
			("LOCATION" "PU31_P1_1")
		)
		("@s9s_mb_2u_lib.s9s_mb_2u(sch_1):page435_i79@pure_quanta.isl99390frztr5935(chips)"
			("VARIANT" "*")
			("VALUE" "FDMF5085")
			("PART_TYPE" "SMLF")
			("MATERIAL" "IC")
			("PART_NUMBER" "AL005085000")
			("STANDARD" "")
			("LIFECYCLE" "")
			("JEDEC_TYPE" "PQFN21_6X5XB")
			("DESCRIPTION" "IC OTHER(39P) FDMF5085(PQFN)")
			("MANUFTR" "ONS")
			("MANUF_PN" "FDMF5085")
			("RD_CMPLS_LVL" "EP(V1)")
			("CMPLS_LVL" "")
			("FROM_PJ" "S9S-KIMI")
			("CLASS" "IC")
			("DIP_SMD" "")
			("DATA" "ONS_FDMF5085.pdf")
			("EE_CHECK_LIST" "")
			("FP_ECN" "")
			("PSL" "")
			("CREATOR" "")
			("STATUS" "")
			("MSD" "NA")
			("ESD_CDM" "NA")
			("ESD_HBM" "NA")
			("ESD_MM" "NA")
			("PIN_LENGTH_SHORT_PIN" "0 MILS")
			("PIN_LENGTH_LONG_PIN" "0 MILS")
			("CREATEDAY" "20200423")
			("LOCATION" "PU30_P1_2")
		)
		("@s9s_mb_2u_lib.s9s_mb_2u(sch_1):page587_i96@pure_quanta.isl99390frztr5935(chips)"
			("VARIANT" "*")
			("VALUE" "FDMF5085")
			("PART_TYPE" "SMLF")
			("MATERIAL" "IC")
			("PART_NUMBER" "AL005085000")
			("STANDARD" "")
			("LIFECYCLE" "")
			("JEDEC_TYPE" "PQFN21_6X5XB")
			("DESCRIPTION" "IC OTHER(39P) FDMF5085(PQFN)")
			("MANUFTR" "ONS")
			("MANUF_PN" "FDMF5085")
			("RD_CMPLS_LVL" "EP(V1)")
			("CMPLS_LVL" "")
			("FROM_PJ" "S9S-KIMI")
			("CLASS" "IC")
			("DIP_SMD" "")
			("DATA" "ONS_FDMF5085.pdf")
			("EE_CHECK_LIST" "")
			("FP_ECN" "")
			("PSL" "")
			("CREATOR" "")
			("STATUS" "")
			("MSD" "NA")
			("ESD_CDM" "NA")
			("ESD_HBM" "NA")
			("ESD_MM" "NA")
			("PIN_LENGTH_SHORT_PIN" "0 MILS")
			("PIN_LENGTH_LONG_PIN" "0 MILS")
			("CREATEDAY" "20200423")
			("LOCATION" "PU28_P1_3")
		)
		("@s9s_mb_2u_lib.s9s_mb_2u(sch_1):page587_i21@pure_quanta.isl99390frztr5935(chips)"
			("VARIANT" "*")
			("VALUE" "FDMF5085")
			("PART_TYPE" "SMLF")
			("MATERIAL" "IC")
			("PART_NUMBER" "AL005085000")
			("STANDARD" "")
			("LIFECYCLE" "")
			("JEDEC_TYPE" "PQFN21_6X5XB")
			("DESCRIPTION" "IC OTHER(39P) FDMF5085(PQFN)")
			("MANUFTR" "ONS")
			("MANUF_PN" "FDMF5085")
			("RD_CMPLS_LVL" "EP(V1)")
			("CMPLS_LVL" "")
			("FROM_PJ" "S9S-KIMI")
			("CLASS" "IC")
			("DIP_SMD" "")
			("DATA" "ONS_FDMF5085.pdf")
			("EE_CHECK_LIST" "")
			("FP_ECN" "")
			("PSL" "")
			("CREATOR" "")
			("STATUS" "")
			("MSD" "NA")
			("ESD_CDM" "NA")
			("ESD_HBM" "NA")
			("ESD_MM" "NA")
			("PIN_LENGTH_SHORT_PIN" "0 MILS")
			("PIN_LENGTH_LONG_PIN" "0 MILS")
			("CREATEDAY" "20200423")
			("LOCATION" "PU27_P1_4")
		)
		("@s9s_mb_2u_lib.s9s_mb_2u(sch_1):page588_i27@pure_quanta.isl99390frztr5935(chips)"
			("VARIANT" "*")
			("VALUE" "FDMF5085")
			("PART_TYPE" "SMLF")
			("MATERIAL" "IC")
			("PART_NUMBER" "AL005085000")
			("STANDARD" "")
			("LIFECYCLE" "")
			("JEDEC_TYPE" "PQFN21_6X5XB")
			("DESCRIPTION" "IC OTHER(39P) FDMF5085(PQFN)")
			("MANUFTR" "ONS")
			("MANUF_PN" "FDMF5085")
			("RD_CMPLS_LVL" "EP(V1)")
			("CMPLS_LVL" "")
			("FROM_PJ" "S9S-KIMI")
			("CLASS" "IC")
			("DIP_SMD" "")
			("DATA" "ONS_FDMF5085.pdf")
			("EE_CHECK_LIST" "")
			("FP_ECN" "")
			("PSL" "")
			("CREATOR" "")
			("STATUS" "")
			("MSD" "NA")
			("ESD_CDM" "NA")
			("ESD_HBM" "NA")
			("ESD_MM" "NA")
			("PIN_LENGTH_SHORT_PIN" "0 MILS")
			("PIN_LENGTH_LONG_PIN" "0 MILS")
			("CREATEDAY" "20200423")
			("LOCATION" "PU26_P1_5")
		)
		("@s9s_mb_2u_lib.s9s_mb_2u(sch_1):page588_i8@pure_quanta.isl99390frztr5935(chips)"
			("VARIANT" "*")
			("VALUE" "FDMF5085")
			("PART_TYPE" "SMLF")
			("MATERIAL" "IC")
			("PART_NUMBER" "AL005085000")
			("STANDARD" "")
			("LIFECYCLE" "")
			("JEDEC_TYPE" "PQFN21_6X5XB")
			("DESCRIPTION" "IC OTHER(39P) FDMF5085(PQFN)")
			("MANUFTR" "ONS")
			("MANUF_PN" "FDMF5085")
			("RD_CMPLS_LVL" "EP(V1)")
			("CMPLS_LVL" "")
			("FROM_PJ" "S9S-KIMI")
			("CLASS" "IC")
			("DIP_SMD" "")
			("DATA" "ONS_FDMF5085.pdf")
			("EE_CHECK_LIST" "")
			("FP_ECN" "")
			("PSL" "")
			("CREATOR" "")
			("STATUS" "")
			("MSD" "NA")
			("ESD_CDM" "NA")
			("ESD_HBM" "NA")
			("ESD_MM" "NA")
			("PIN_LENGTH_SHORT_PIN" "0 MILS")
			("PIN_LENGTH_LONG_PIN" "0 MILS")
			("CREATEDAY" "20200423")
			("LOCATION" "PU25_P1_6")
		)
		("@s9s_mb_2u_lib.s9s_mb_2u(sch_1):page589_i25@pure_quanta.isl99390frztr5935(chips)"
			("VARIANT" "*")
			("VALUE" "FDMF5085")
			("PART_TYPE" "SMLF")
			("MATERIAL" "IC")
			("PART_NUMBER" "AL005085000")
			("STANDARD" "")
			("LIFECYCLE" "")
			("JEDEC_TYPE" "PQFN21_6X5XB")
			("DESCRIPTION" "IC OTHER(39P) FDMF5085(PQFN)")
			("MANUFTR" "ONS")
			("MANUF_PN" "FDMF5085")
			("RD_CMPLS_LVL" "EP(V1)")
			("CMPLS_LVL" "")
			("FROM_PJ" "S9S-KIMI")
			("CLASS" "IC")
			("DIP_SMD" "")
			("DATA" "ONS_FDMF5085.pdf")
			("EE_CHECK_LIST" "")
			("FP_ECN" "")
			("PSL" "")
			("CREATOR" "")
			("STATUS" "")
			("MSD" "NA")
			("ESD_CDM" "NA")
			("ESD_HBM" "NA")
			("ESD_MM" "NA")
			("PIN_LENGTH_SHORT_PIN" "0 MILS")
			("PIN_LENGTH_LONG_PIN" "0 MILS")
			("CREATEDAY" "20200423")
			("LOCATION" "PU24_P1_7")
		)
		("@s9s_mb_2u_lib.s9s_mb_2u(sch_1):page589_i7@pure_quanta.isl99390frztr5935(chips)"
			("VARIANT" "*")
			("VALUE" "FDMF5085")
			("PART_TYPE" "SMLF")
			("MATERIAL" "IC")
			("PART_NUMBER" "AL005085000")
			("STANDARD" "")
			("LIFECYCLE" "")
			("JEDEC_TYPE" "PQFN21_6X5XB")
			("DESCRIPTION" "IC OTHER(39P) FDMF5085(PQFN)")
			("MANUFTR" "ONS")
			("MANUF_PN" "FDMF5085")
			("RD_CMPLS_LVL" "EP(V1)")
			("CMPLS_LVL" "")
			("FROM_PJ" "S9S-KIMI")
			("CLASS" "IC")
			("DIP_SMD" "")
			("DATA" "ONS_FDMF5085.pdf")
			("EE_CHECK_LIST" "")
			("FP_ECN" "")
			("PSL" "")
			("CREATOR" "")
			("STATUS" "")
			("MSD" "NA")
			("ESD_CDM" "NA")
			("ESD_HBM" "NA")
			("ESD_MM" "NA")
			("PIN_LENGTH_SHORT_PIN" "0 MILS")
			("PIN_LENGTH_LONG_PIN" "0 MILS")
			("CREATEDAY" "20200423")
			("LOCATION" "PU23_P1_8")
		)
		("@s9s_mb_2u_lib.s9s_mb_2u(sch_1):page598_i44@pure_quanta.isl99390frztr5935(chips)"
			("VARIANT" "*")
			("VALUE" "FDMF5085")
			("PART_TYPE" "SMLF")
			("MATERIAL" "IC")
			("PART_NUMBER" "AL005085000")
			("STANDARD" "")
			("LIFECYCLE" "")
			("JEDEC_TYPE" "PQFN21_6X5XB")
			("DESCRIPTION" "IC OTHER(39P) FDMF5085(PQFN)")
			("MANUFTR" "ONS")
			("MANUF_PN" "FDMF5085")
			("RD_CMPLS_LVL" "EP(V1)")
			("CMPLS_LVL" "")
			("FROM_PJ" "S9S-KIMI")
			("CLASS" "IC")
			("DIP_SMD" "")
			("DATA" "ONS_FDMF5085.pdf")
			("EE_CHECK_LIST" "")
			("FP_ECN" "")
			("PSL" "")
			("CREATOR" "")
			("STATUS" "")
			("MSD" "NA")
			("ESD_CDM" "NA")
			("ESD_HBM" "NA")
			("ESD_MM" "NA")
			("PIN_LENGTH_SHORT_PIN" "0 MILS")
			("PIN_LENGTH_LONG_PIN" "0 MILS")
			("CREATEDAY" "20200423")
			("LOCATION" "PU75_P1_1")
		)
		("@s9s_mb_2u_lib.s9s_mb_2u(sch_1):page598_i48@pure_quanta.isl99390frztr5935(chips)"
			("VARIANT" "*")
			("VALUE" "FDMF5085")
			("PART_TYPE" "SMLF")
			("MATERIAL" "IC")
			("PART_NUMBER" "AL005085000")
			("STANDARD" "")
			("LIFECYCLE" "")
			("JEDEC_TYPE" "PQFN21_6X5XB")
			("DESCRIPTION" "IC OTHER(39P) FDMF5085(PQFN)")
			("MANUFTR" "ONS")
			("MANUF_PN" "FDMF5085")
			("RD_CMPLS_LVL" "EP(V1)")
			("CMPLS_LVL" "")
			("FROM_PJ" "S9S-KIMI")
			("CLASS" "IC")
			("DIP_SMD" "")
			("DATA" "ONS_FDMF5085.pdf")
			("EE_CHECK_LIST" "")
			("FP_ECN" "")
			("PSL" "")
			("CREATOR" "")
			("STATUS" "")
			("MSD" "NA")
			("ESD_CDM" "NA")
			("ESD_HBM" "NA")
			("ESD_MM" "NA")
			("PIN_LENGTH_SHORT_PIN" "0 MILS")
			("PIN_LENGTH_LONG_PIN" "0 MILS")
			("CREATEDAY" "20200423")
			("LOCATION" "PU76_P1_2")
		)
		("@s9s_mb_2u_lib.s9s_mb_2u(sch_1):page599_i28@pure_quanta.isl99390frztr5935(chips)"
			("VARIANT" "*")
			("VALUE" "FDMF5085")
			("PART_TYPE" "SMLF")
			("MATERIAL" "IC")
			("PART_NUMBER" "AL005085000")
			("STANDARD" "")
			("LIFECYCLE" "")
			("JEDEC_TYPE" "PQFN21_6X5XB")
			("DESCRIPTION" "IC OTHER(39P) FDMF5085(PQFN)")
			("MANUFTR" "ONS")
			("MANUF_PN" "FDMF5085")
			("RD_CMPLS_LVL" "EP(V1)")
			("CMPLS_LVL" "")
			("FROM_PJ" "S9S-KIMI")
			("CLASS" "IC")
			("DIP_SMD" "")
			("DATA" "ONS_FDMF5085.pdf")
			("EE_CHECK_LIST" "")
			("FP_ECN" "")
			("PSL" "")
			("CREATOR" "")
			("STATUS" "")
			("MSD" "NA")
			("ESD_CDM" "NA")
			("ESD_HBM" "NA")
			("ESD_MM" "NA")
			("PIN_LENGTH_SHORT_PIN" "0 MILS")
			("PIN_LENGTH_LONG_PIN" "0 MILS")
			("CREATEDAY" "20200423")
			("LOCATION" "PU77_P1_3")
		)
		("@s9s_mb_2u_lib.s9s_mb_2u(sch_1):page599_i25@pure_quanta.isl99390frztr5935(chips)"
			("VARIANT" "*")
			("VALUE" "FDMF5085")
			("PART_TYPE" "SMLF")
			("MATERIAL" "IC")
			("PART_NUMBER" "AL005085000")
			("STANDARD" "")
			("LIFECYCLE" "")
			("JEDEC_TYPE" "PQFN21_6X5XB")
			("DESCRIPTION" "IC OTHER(39P) FDMF5085(PQFN)")
			("MANUFTR" "ONS")
			("MANUF_PN" "FDMF5085")
			("RD_CMPLS_LVL" "EP(V1)")
			("CMPLS_LVL" "")
			("FROM_PJ" "S9S-KIMI")
			("CLASS" "IC")
			("DIP_SMD" "")
			("DATA" "ONS_FDMF5085.pdf")
			("EE_CHECK_LIST" "")
			("FP_ECN" "")
			("PSL" "")
			("CREATOR" "")
			("STATUS" "")
			("MSD" "NA")
			("ESD_CDM" "NA")
			("ESD_HBM" "NA")
			("ESD_MM" "NA")
			("PIN_LENGTH_SHORT_PIN" "0 MILS")
			("PIN_LENGTH_LONG_PIN" "0 MILS")
			("CREATEDAY" "20200423")
			("LOCATION" "PU78_P1_4")
		)
		("@s9s_mb_2u_lib.s9s_mb_2u(sch_1):page663_i1@pure_quanta.isl99390frztr5935(chips)"
			("VARIANT" "*")
			("VALUE" "FDMF5085")
			("PART_TYPE" "SMLF")
			("MATERIAL" "EMPTY")
			("PART_NUMBER" "AL005085000")
			("STANDARD" "")
			("LIFECYCLE" "")
			("JEDEC_TYPE" "PQFN21_6X5XB")
			("DESCRIPTION" "IC OTHER(39P) FDMF5085(PQFN)")
			("MANUFTR" "ONS")
			("MANUF_PN" "FDMF5085")
			("RD_CMPLS_LVL" "EP(V1)")
			("CMPLS_LVL" "")
			("FROM_PJ" "S9S-KIMI")
			("CLASS" "IC")
			("DIP_SMD" "")
			("DATA" "ONS_FDMF5085.pdf")
			("EE_CHECK_LIST" "")
			("FP_ECN" "")
			("PSL" "")
			("CREATOR" "")
			("STATUS" "")
			("MSD" "NA")
			("ESD_CDM" "NA")
			("ESD_HBM" "NA")
			("ESD_MM" "NA")
			("PIN_LENGTH_SHORT_PIN" "0 MILS")
			("PIN_LENGTH_LONG_PIN" "0 MILS")
			("CREATEDAY" "20200423")
			("LOCATION" "PU109_P1_5")
		)
		("@s9s_mb_2u_lib.s9s_mb_2u(sch_1):page641_i1@pure_quanta.isl99390frztr5935(chips)"
			("VARIANT" "*")
			("VALUE" "FDMF5085")
			("PART_TYPE" "SMLF")
			("MATERIAL" "EMPTY")
			("PART_NUMBER" "AL005085000")
			("STANDARD" "")
			("LIFECYCLE" "")
			("JEDEC_TYPE" "PQFN21_6X5XB")
			("DESCRIPTION" "IC OTHER(39P) FDMF5085(PQFN)")
			("MANUFTR" "ONS")
			("MANUF_PN" "FDMF5085")
			("RD_CMPLS_LVL" "EP(V1)")
			("CMPLS_LVL" "")
			("FROM_PJ" "S9S-KIMI")
			("CLASS" "IC")
			("DIP_SMD" "")
			("DATA" "ONS_FDMF5085.pdf")
			("EE_CHECK_LIST" "")
			("FP_ECN" "")
			("PSL" "")
			("CREATOR" "")
			("STATUS" "")
			("MSD" "NA")
			("ESD_CDM" "NA")
			("ESD_HBM" "NA")
			("ESD_MM" "NA")
			("PIN_LENGTH_SHORT_PIN" "0 MILS")
			("PIN_LENGTH_LONG_PIN" "0 MILS")
			("CREATEDAY" "20200423")
			("LOCATION" "PU108_P0_5")
		)
		("@s9s_mb_2u_lib.s9s_mb_2u(sch_1):page521_i63@pure_quanta.conn2_aaabat029k01(chips)"
			("LOCATION" "BT1")
		)
		("@s9s_mb_2u_lib.s9s_mb_2u(sch_1):page521_i68@pure_quanta.q_cap(chips)"
			("LOCATION" "C610")
		)
		("@s9s_mb_2u_lib.s9s_mb_2u(sch_1):page521_i65@pure_quanta.q_cap(chips)"
			("LOCATION" "C611")
		)
		("@s9s_mb_2u_lib.s9s_mb_2u(sch_1):page521_i81@pure_quanta.mosfet_n_gsd(chips)"
			("LOCATION" "Q34")
		)
		("@s9s_mb_2u_lib.s9s_mb_2u(sch_1):page521_i86@pure_quanta.mosfet_n_gsd(chips)"
			("LOCATION" "Q35")
		)
		("@s9s_mb_2u_lib.s9s_mb_2u(sch_1):page521_i24@pure_quanta.q_res(chips)"
			("LOCATION" "R498")
		)
		("@s9s_mb_2u_lib.s9s_mb_2u(sch_1):page521_i70@pure_quanta.q_res(chips)"
			("LOCATION" "R1202")
		)
		("@s9s_mb_2u_lib.s9s_mb_2u(sch_1):page521_i62@pure_quanta.q_res(chips)"
			("LOCATION" "R1203")
		)
		("@s9s_mb_2u_lib.s9s_mb_2u(sch_1):page521_i80@pure_quanta.q_res(chips)"
			("LOCATION" "R1461")
		)
		("@s9s_mb_2u_lib.s9s_mb_2u(sch_1):page521_i85@pure_quanta.q_res(chips)"
			("LOCATION" "R1839")
		)
		("@s9s_mb_2u_lib.s9s_mb_2u(sch_1):page521_i89@pure_quanta.q_res(chips)"
			("LOCATION" "R1840")
		)
		("@s9s_mb_2u_lib.s9s_mb_2u(sch_1):page521_i27@pure_quanta.emmitsburg_rev0p9(chips)"
			("LOCATION" "U4")
		)
		("@s9s_mb_2u_lib.s9s_mb_2u(sch_1):page521_i64@pure_quanta.bas70057f(chips)"
			("LOCATION" "U62")
		)
		("@s9s_mb_2u_lib.s9s_mb_2u(sch_1):page37_i15@pure_quanta.q_cap(chips)"
			("LOCATION" "C1")
		)
		("@s9s_mb_2u_lib.s9s_mb_2u(sch_1):page37_i7@pure_quanta.socket4677_azifs035p001c01(chips)"
			("LOCATION" "U2")
		)
		("@s9s_mb_2u_lib.s9s_mb_2u(sch_1):page37_i8@pure_quanta.socket4677_azifs035p001c01(chips)"
			("LOCATION" "U2")
		)
		("@s9s_mb_2u_lib.s9s_mb_2u(sch_1):page367_i192@pure_quanta.q_cap(chips)"
			("LOCATION" "C2")
		)
		("@s9s_mb_2u_lib.s9s_mb_2u(sch_1):page367_i188@pure_quanta.q_cap(chips)"
			("LOCATION" "C3")
		)
		("@s9s_mb_2u_lib.s9s_mb_2u(sch_1):page367_i190@pure_quanta.q_cap(chips)"
			("LOCATION" "C4")
		)
		("@s9s_mb_2u_lib.s9s_mb_2u(sch_1):page367_i198@pure_quanta.sconn288_adr50001p013c01(chips)"
			("LOCATION" "J1")
		)
		("@s9s_mb_2u_lib.s9s_mb_2u(sch_1):page367_i199@pure_quanta.sconn288_adr50001p013c01(chips)"
			("LOCATION" "J1")
		)
		("@s9s_mb_2u_lib.s9s_mb_2u(sch_1):page367_i200@pure_quanta.sconn288_adr50001p013c01(chips)"
			("LOCATION" "J1")
		)
		("@s9s_mb_2u_lib.s9s_mb_2u(sch_1):page367_i196@pure_quanta.q_res(chips)"
			("LOCATION" "R26")
		)
		("@s9s_mb_2u_lib.s9s_mb_2u(sch_1):page368_i120@pure_quanta.q_cap(chips)"
			("LOCATION" "C5")
		)
		("@s9s_mb_2u_lib.s9s_mb_2u(sch_1):page368_i122@pure_quanta.q_cap(chips)"
			("LOCATION" "C6")
		)
		("@s9s_mb_2u_lib.s9s_mb_2u(sch_1):page368_i144@pure_quanta.q_cap(chips)"
			("LOCATION" "C7")
		)
		("@s9s_mb_2u_lib.s9s_mb_2u(sch_1):page368_i177@pure_quanta.sconn288_adr50001p003c01(chips)"
			("LOCATION" "J2")
		)
		("@s9s_mb_2u_lib.s9s_mb_2u(sch_1):page368_i178@pure_quanta.sconn288_adr50001p003c01(chips)"
			("LOCATION" "J2")
		)
		("@s9s_mb_2u_lib.s9s_mb_2u(sch_1):page368_i179@pure_quanta.sconn288_adr50001p003c01(chips)"
			("LOCATION" "J2")
		)
		("@s9s_mb_2u_lib.s9s_mb_2u(sch_1):page368_i10@pure_quanta.q_res(chips)"
			("LOCATION" "R27")
		)
		("@s9s_mb_2u_lib.s9s_mb_2u(sch_1):page369_i121@pure_quanta.q_cap(chips)"
			("LOCATION" "C8")
		)
		("@s9s_mb_2u_lib.s9s_mb_2u(sch_1):page369_i122@pure_quanta.q_cap(chips)"
			("LOCATION" "C9")
		)
		("@s9s_mb_2u_lib.s9s_mb_2u(sch_1):page369_i144@pure_quanta.q_cap(chips)"
			("LOCATION" "C10")
		)
		("@s9s_mb_2u_lib.s9s_mb_2u(sch_1):page369_i11@pure_quanta.sconn288_adr50001p013c01(chips)"
			("LOCATION" "J3")
		)
		("@s9s_mb_2u_lib.s9s_mb_2u(sch_1):page369_i125@pure_quanta.sconn288_adr50001p013c01(chips)"
			("LOCATION" "J3")
		)
		("@s9s_mb_2u_lib.s9s_mb_2u(sch_1):page369_i146@pure_quanta.sconn288_adr50001p013c01(chips)"
			("LOCATION" "J3")
		)
		("@s9s_mb_2u_lib.s9s_mb_2u(sch_1):page369_i10@pure_quanta.q_res(chips)"
			("LOCATION" "R28")
		)
		("@s9s_mb_2u_lib.s9s_mb_2u(sch_1):page370_i121@pure_quanta.q_cap(chips)"
			("LOCATION" "C11")
		)
		("@s9s_mb_2u_lib.s9s_mb_2u(sch_1):page370_i125@pure_quanta.q_cap(chips)"
			("LOCATION" "C12")
		)
		("@s9s_mb_2u_lib.s9s_mb_2u(sch_1):page370_i127@pure_quanta.q_cap(chips)"
			("LOCATION" "C13")
		)
		("@s9s_mb_2u_lib.s9s_mb_2u(sch_1):page370_i23@pure_quanta.sconn288_adr50001p003c01(chips)"
			("LOCATION" "J4")
		)
		("@s9s_mb_2u_lib.s9s_mb_2u(sch_1):page370_i124@pure_quanta.sconn288_adr50001p003c01(chips)"
			("LOCATION" "J4")
		)
		("@s9s_mb_2u_lib.s9s_mb_2u(sch_1):page370_i174@pure_quanta.sconn288_adr50001p003c01(chips)"
			("LOCATION" "J4")
		)
		("@s9s_mb_2u_lib.s9s_mb_2u(sch_1):page370_i1@pure_quanta.q_res(chips)"
			("LOCATION" "R29")
		)
		("@s9s_mb_2u_lib.s9s_mb_2u(sch_1):page371_i120@pure_quanta.q_cap(chips)"
			("LOCATION" "C14")
		)
		("@s9s_mb_2u_lib.s9s_mb_2u(sch_1):page371_i121@pure_quanta.q_cap(chips)"
			("LOCATION" "C15")
		)
		("@s9s_mb_2u_lib.s9s_mb_2u(sch_1):page371_i123@pure_quanta.q_cap(chips)"
			("LOCATION" "C16")
		)
		("@s9s_mb_2u_lib.s9s_mb_2u(sch_1):page371_i24@pure_quanta.sconn288_adr50001p013c01(chips)"
			("LOCATION" "J5")
		)
		("@s9s_mb_2u_lib.s9s_mb_2u(sch_1):page371_i125@pure_quanta.sconn288_adr50001p013c01(chips)"
			("LOCATION" "J5")
		)
		("@s9s_mb_2u_lib.s9s_mb_2u(sch_1):page371_i174@pure_quanta.sconn288_adr50001p013c01(chips)"
			("LOCATION" "J5")
		)
		("@s9s_mb_2u_lib.s9s_mb_2u(sch_1):page371_i3@pure_quanta.q_res(chips)"
			("LOCATION" "R30")
		)
		("@s9s_mb_2u_lib.s9s_mb_2u(sch_1):page372_i120@pure_quanta.q_cap(chips)"
			("LOCATION" "C17")
		)
		("@s9s_mb_2u_lib.s9s_mb_2u(sch_1):page372_i124@pure_quanta.q_cap(chips)"
			("LOCATION" "C18")
		)
		("@s9s_mb_2u_lib.s9s_mb_2u(sch_1):page372_i127@pure_quanta.q_cap(chips)"
			("LOCATION" "C19")
		)
		("@s9s_mb_2u_lib.s9s_mb_2u(sch_1):page372_i46@pure_quanta.sconn288_adr50001p003c01(chips)"
			("LOCATION" "J6")
		)
		("@s9s_mb_2u_lib.s9s_mb_2u(sch_1):page372_i123@pure_quanta.sconn288_adr50001p003c01(chips)"
			("LOCATION" "J6")
		)
		("@s9s_mb_2u_lib.s9s_mb_2u(sch_1):page372_i175@pure_quanta.sconn288_adr50001p003c01(chips)"
			("LOCATION" "J6")
		)
		("@s9s_mb_2u_lib.s9s_mb_2u(sch_1):page372_i45@pure_quanta.q_res(chips)"
			("LOCATION" "R31")
		)
		("@s9s_mb_2u_lib.s9s_mb_2u(sch_1):page373_i123@pure_quanta.q_cap(chips)"
			("LOCATION" "C20")
		)
		("@s9s_mb_2u_lib.s9s_mb_2u(sch_1):page373_i126@pure_quanta.q_cap(chips)"
			("LOCATION" "C21")
		)
		("@s9s_mb_2u_lib.s9s_mb_2u(sch_1):page373_i166@pure_quanta.q_cap(chips)"
			("LOCATION" "C22")
		)
		("@s9s_mb_2u_lib.s9s_mb_2u(sch_1):page373_i12@pure_quanta.sconn288_adr50001p013c01(chips)"
			("LOCATION" "J7")
		)
		("@s9s_mb_2u_lib.s9s_mb_2u(sch_1):page373_i125@pure_quanta.sconn288_adr50001p013c01(chips)"
			("LOCATION" "J7")
		)
		("@s9s_mb_2u_lib.s9s_mb_2u(sch_1):page373_i168@pure_quanta.sconn288_adr50001p013c01(chips)"
			("LOCATION" "J7")
		)
		("@s9s_mb_2u_lib.s9s_mb_2u(sch_1):page373_i2@pure_quanta.q_res(chips)"
			("LOCATION" "R32")
		)
		("@s9s_mb_2u_lib.s9s_mb_2u(sch_1):page374_i121@pure_quanta.q_cap(chips)"
			("LOCATION" "C23")
		)
		("@s9s_mb_2u_lib.s9s_mb_2u(sch_1):page374_i125@pure_quanta.q_cap(chips)"
			("LOCATION" "C24")
		)
		("@s9s_mb_2u_lib.s9s_mb_2u(sch_1):page374_i127@pure_quanta.q_cap(chips)"
			("LOCATION" "C25")
		)
		("@s9s_mb_2u_lib.s9s_mb_2u(sch_1):page374_i50@pure_quanta.sconn288_adr50001p003c01(chips)"
			("LOCATION" "J8")
		)
		("@s9s_mb_2u_lib.s9s_mb_2u(sch_1):page374_i124@pure_quanta.sconn288_adr50001p003c01(chips)"
			("LOCATION" "J8")
		)
		("@s9s_mb_2u_lib.s9s_mb_2u(sch_1):page374_i175@pure_quanta.sconn288_adr50001p003c01(chips)"
			("LOCATION" "J8")
		)
		("@s9s_mb_2u_lib.s9s_mb_2u(sch_1):page374_i2@pure_quanta.q_res(chips)"
			("LOCATION" "R33")
		)
		("@s9s_mb_2u_lib.s9s_mb_2u(sch_1):page375_i122@pure_quanta.q_cap(chips)"
			("LOCATION" "C26")
		)
		("@s9s_mb_2u_lib.s9s_mb_2u(sch_1):page375_i123@pure_quanta.q_cap(chips)"
			("LOCATION" "C27")
		)
		("@s9s_mb_2u_lib.s9s_mb_2u(sch_1):page375_i145@pure_quanta.q_cap(chips)"
			("LOCATION" "C28")
		)
		("@s9s_mb_2u_lib.s9s_mb_2u(sch_1):page375_i12@pure_quanta.sconn288_adr50001p013c01(chips)"
			("LOCATION" "J9")
		)
		("@s9s_mb_2u_lib.s9s_mb_2u(sch_1):page375_i126@pure_quanta.sconn288_adr50001p013c01(chips)"
			("LOCATION" "J9")
		)
		("@s9s_mb_2u_lib.s9s_mb_2u(sch_1):page375_i147@pure_quanta.sconn288_adr50001p013c01(chips)"
			("LOCATION" "J9")
		)
		("@s9s_mb_2u_lib.s9s_mb_2u(sch_1):page375_i11@pure_quanta.q_res(chips)"
			("LOCATION" "R34")
		)
		("@s9s_mb_2u_lib.s9s_mb_2u(sch_1):page376_i123@pure_quanta.q_cap(chips)"
			("LOCATION" "C29")
		)
		("@s9s_mb_2u_lib.s9s_mb_2u(sch_1):page376_i124@pure_quanta.q_cap(chips)"
			("LOCATION" "C30")
		)
		("@s9s_mb_2u_lib.s9s_mb_2u(sch_1):page376_i146@pure_quanta.q_cap(chips)"
			("LOCATION" "C31")
		)
		("@s9s_mb_2u_lib.s9s_mb_2u(sch_1):page376_i13@pure_quanta.sconn288_adr50001p003c01(chips)"
			("LOCATION" "J10")
		)
		("@s9s_mb_2u_lib.s9s_mb_2u(sch_1):page376_i127@pure_quanta.sconn288_adr50001p003c01(chips)"
			("LOCATION" "J10")
		)
		("@s9s_mb_2u_lib.s9s_mb_2u(sch_1):page376_i148@pure_quanta.sconn288_adr50001p003c01(chips)"
			("LOCATION" "J10")
		)
		("@s9s_mb_2u_lib.s9s_mb_2u(sch_1):page376_i2@pure_quanta.q_res(chips)"
			("LOCATION" "R35")
		)
		("@s9s_mb_2u_lib.s9s_mb_2u(sch_1):page377_i122@pure_quanta.q_cap(chips)"
			("LOCATION" "C32")
		)
		("@s9s_mb_2u_lib.s9s_mb_2u(sch_1):page377_i127@pure_quanta.q_cap(chips)"
			("LOCATION" "C33")
		)
		("@s9s_mb_2u_lib.s9s_mb_2u(sch_1):page377_i130@pure_quanta.q_cap(chips)"
			("LOCATION" "C34")
		)
		("@s9s_mb_2u_lib.s9s_mb_2u(sch_1):page377_i25@pure_quanta.sconn288_adr50001p013c01(chips)"
			("LOCATION" "J11")
		)
		("@s9s_mb_2u_lib.s9s_mb_2u(sch_1):page377_i126@pure_quanta.sconn288_adr50001p013c01(chips)"
			("LOCATION" "J11")
		)
		("@s9s_mb_2u_lib.s9s_mb_2u(sch_1):page377_i175@pure_quanta.sconn288_adr50001p013c01(chips)"
			("LOCATION" "J11")
		)
		("@s9s_mb_2u_lib.s9s_mb_2u(sch_1):page377_i2@pure_quanta.q_res(chips)"
			("LOCATION" "R36")
		)
		("@s9s_mb_2u_lib.s9s_mb_2u(sch_1):page378_i122@pure_quanta.q_cap(chips)"
			("LOCATION" "C35")
		)
		("@s9s_mb_2u_lib.s9s_mb_2u(sch_1):page378_i126@pure_quanta.q_cap(chips)"
			("LOCATION" "C36")
		)
		("@s9s_mb_2u_lib.s9s_mb_2u(sch_1):page378_i128@pure_quanta.q_cap(chips)"
			("LOCATION" "C37")
		)
		("@s9s_mb_2u_lib.s9s_mb_2u(sch_1):page378_i24@pure_quanta.sconn288_adr50001p003c01(chips)"
			("LOCATION" "J12")
		)
		("@s9s_mb_2u_lib.s9s_mb_2u(sch_1):page378_i125@pure_quanta.sconn288_adr50001p003c01(chips)"
			("LOCATION" "J12")
		)
		("@s9s_mb_2u_lib.s9s_mb_2u(sch_1):page378_i175@pure_quanta.sconn288_adr50001p003c01(chips)"
			("LOCATION" "J12")
		)
		("@s9s_mb_2u_lib.s9s_mb_2u(sch_1):page378_i2@pure_quanta.q_res(chips)"
			("LOCATION" "R37")
		)
		("@s9s_mb_2u_lib.s9s_mb_2u(sch_1):page379_i123@pure_quanta.q_cap(chips)"
			("LOCATION" "C38")
		)
		("@s9s_mb_2u_lib.s9s_mb_2u(sch_1):page379_i125@pure_quanta.q_cap(chips)"
			("LOCATION" "C39")
		)
		("@s9s_mb_2u_lib.s9s_mb_2u(sch_1):page379_i162@pure_quanta.q_cap(chips)"
			("LOCATION" "C40")
		)
		("@s9s_mb_2u_lib.s9s_mb_2u(sch_1):page379_i11@pure_quanta.sconn288_adr50001p013c01(chips)"
			("LOCATION" "J13")
		)
		("@s9s_mb_2u_lib.s9s_mb_2u(sch_1):page379_i127@pure_quanta.sconn288_adr50001p013c01(chips)"
			("LOCATION" "J13")
		)
		("@s9s_mb_2u_lib.s9s_mb_2u(sch_1):page379_i164@pure_quanta.sconn288_adr50001p013c01(chips)"
			("LOCATION" "J13")
		)
		("@s9s_mb_2u_lib.s9s_mb_2u(sch_1):page379_i10@pure_quanta.q_res(chips)"
			("LOCATION" "R38")
		)
		("@s9s_mb_2u_lib.s9s_mb_2u(sch_1):page380_i121@pure_quanta.q_cap(chips)"
			("LOCATION" "C41")
		)
		("@s9s_mb_2u_lib.s9s_mb_2u(sch_1):page380_i125@pure_quanta.q_cap(chips)"
			("LOCATION" "C42")
		)
		("@s9s_mb_2u_lib.s9s_mb_2u(sch_1):page380_i128@pure_quanta.q_cap(chips)"
			("LOCATION" "C43")
		)
		("@s9s_mb_2u_lib.s9s_mb_2u(sch_1):page380_i47@pure_quanta.sconn288_adr50001p003c01(chips)"
			("LOCATION" "J14")
		)
		("@s9s_mb_2u_lib.s9s_mb_2u(sch_1):page380_i124@pure_quanta.sconn288_adr50001p003c01(chips)"
			("LOCATION" "J14")
		)
		("@s9s_mb_2u_lib.s9s_mb_2u(sch_1):page380_i176@pure_quanta.sconn288_adr50001p003c01(chips)"
			("LOCATION" "J14")
		)
		("@s9s_mb_2u_lib.s9s_mb_2u(sch_1):page380_i46@pure_quanta.q_res(chips)"
			("LOCATION" "R39")
		)
		("@s9s_mb_2u_lib.s9s_mb_2u(sch_1):page381_i121@pure_quanta.q_cap(chips)"
			("LOCATION" "C44")
		)
		("@s9s_mb_2u_lib.s9s_mb_2u(sch_1):page381_i125@pure_quanta.q_cap(chips)"
			("LOCATION" "C45")
		)
		("@s9s_mb_2u_lib.s9s_mb_2u(sch_1):page381_i127@pure_quanta.q_cap(chips)"
			("LOCATION" "C46")
		)
		("@s9s_mb_2u_lib.s9s_mb_2u(sch_1):page381_i48@pure_quanta.sconn288_adr50001p013c01(chips)"
			("LOCATION" "J15")
		)
		("@s9s_mb_2u_lib.s9s_mb_2u(sch_1):page381_i124@pure_quanta.sconn288_adr50001p013c01(chips)"
			("LOCATION" "J15")
		)
		("@s9s_mb_2u_lib.s9s_mb_2u(sch_1):page381_i176@pure_quanta.sconn288_adr50001p013c01(chips)"
			("LOCATION" "J15")
		)
		("@s9s_mb_2u_lib.s9s_mb_2u(sch_1):page381_i47@pure_quanta.q_res(chips)"
			("LOCATION" "R40")
		)
		("@s9s_mb_2u_lib.s9s_mb_2u(sch_1):page382_i56@pure_quanta.q_cap(chips)"
			("LOCATION" "C47")
		)
		("@s9s_mb_2u_lib.s9s_mb_2u(sch_1):page382_i59@pure_quanta.q_cap(chips)"
			("LOCATION" "C48")
		)
		("@s9s_mb_2u_lib.s9s_mb_2u(sch_1):page382_i62@pure_quanta.q_cap(chips)"
			("LOCATION" "C49")
		)
		("@s9s_mb_2u_lib.s9s_mb_2u(sch_1):page382_i6@pure_quanta.sconn288_adr50001p003c01(chips)"
			("LOCATION" "J16")
		)
		("@s9s_mb_2u_lib.s9s_mb_2u(sch_1):page382_i132@pure_quanta.sconn288_adr50001p003c01(chips)"
			("LOCATION" "J16")
		)
		("@s9s_mb_2u_lib.s9s_mb_2u(sch_1):page382_i64@pure_quanta.sconn288_adr50001p003c01(chips)"
			("LOCATION" "J16")
		)
		("@s9s_mb_2u_lib.s9s_mb_2u(sch_1):page382_i5@pure_quanta.q_res(chips)"
			("LOCATION" "R41")
		)
		("@s9s_mb_2u_lib.s9s_mb_2u(sch_1):page383_i122@pure_quanta.q_cap(chips)"
			("LOCATION" "C50")
		)
		("@s9s_mb_2u_lib.s9s_mb_2u(sch_1):page383_i123@pure_quanta.q_cap(chips)"
			("LOCATION" "C51")
		)
		("@s9s_mb_2u_lib.s9s_mb_2u(sch_1):page383_i145@pure_quanta.q_cap(chips)"
			("LOCATION" "C52")
		)
		("@s9s_mb_2u_lib.s9s_mb_2u(sch_1):page383_i12@pure_quanta.sconn288_adr50001p013c01(chips)"
			("LOCATION" "J17")
		)
		("@s9s_mb_2u_lib.s9s_mb_2u(sch_1):page383_i126@pure_quanta.sconn288_adr50001p013c01(chips)"
			("LOCATION" "J17")
		)
		("@s9s_mb_2u_lib.s9s_mb_2u(sch_1):page383_i147@pure_quanta.sconn288_adr50001p013c01(chips)"
			("LOCATION" "J17")
		)
		("@s9s_mb_2u_lib.s9s_mb_2u(sch_1):page383_i11@pure_quanta.q_res(chips)"
			("LOCATION" "R42")
		)
		("@s9s_mb_2u_lib.s9s_mb_2u(sch_1):page384_i122@pure_quanta.q_cap(chips)"
			("LOCATION" "C53")
		)
		("@s9s_mb_2u_lib.s9s_mb_2u(sch_1):page384_i126@pure_quanta.q_cap(chips)"
			("LOCATION" "C54")
		)
		("@s9s_mb_2u_lib.s9s_mb_2u(sch_1):page384_i128@pure_quanta.q_cap(chips)"
			("LOCATION" "C55")
		)
		("@s9s_mb_2u_lib.s9s_mb_2u(sch_1):page384_i24@pure_quanta.sconn288_adr50001p003c01(chips)"
			("LOCATION" "J18")
		)
		("@s9s_mb_2u_lib.s9s_mb_2u(sch_1):page384_i125@pure_quanta.sconn288_adr50001p003c01(chips)"
			("LOCATION" "J18")
		)
		("@s9s_mb_2u_lib.s9s_mb_2u(sch_1):page384_i175@pure_quanta.sconn288_adr50001p003c01(chips)"
			("LOCATION" "J18")
		)
		("@s9s_mb_2u_lib.s9s_mb_2u(sch_1):page384_i2@pure_quanta.q_res(chips)"
			("LOCATION" "R43")
		)
		("@s9s_mb_2u_lib.s9s_mb_2u(sch_1):page385_i121@pure_quanta.q_cap(chips)"
			("LOCATION" "C56")
		)
		("@s9s_mb_2u_lib.s9s_mb_2u(sch_1):page385_i122@pure_quanta.q_cap(chips)"
			("LOCATION" "C57")
		)
		("@s9s_mb_2u_lib.s9s_mb_2u(sch_1):page385_i124@pure_quanta.q_cap(chips)"
			("LOCATION" "C58")
		)
		("@s9s_mb_2u_lib.s9s_mb_2u(sch_1):page385_i25@pure_quanta.sconn288_adr50001p013c01(chips)"
			("LOCATION" "J19")
		)
		("@s9s_mb_2u_lib.s9s_mb_2u(sch_1):page385_i126@pure_quanta.sconn288_adr50001p013c01(chips)"
			("LOCATION" "J19")
		)
		("@s9s_mb_2u_lib.s9s_mb_2u(sch_1):page385_i175@pure_quanta.sconn288_adr50001p013c01(chips)"
			("LOCATION" "J19")
		)
		("@s9s_mb_2u_lib.s9s_mb_2u(sch_1):page385_i3@pure_quanta.q_res(chips)"
			("LOCATION" "R44")
		)
		("@s9s_mb_2u_lib.s9s_mb_2u(sch_1):page386_i121@pure_quanta.q_cap(chips)"
			("LOCATION" "C59")
		)
		("@s9s_mb_2u_lib.s9s_mb_2u(sch_1):page386_i125@pure_quanta.q_cap(chips)"
			("LOCATION" "C60")
		)
		("@s9s_mb_2u_lib.s9s_mb_2u(sch_1):page386_i127@pure_quanta.q_cap(chips)"
			("LOCATION" "C61")
		)
		("@s9s_mb_2u_lib.s9s_mb_2u(sch_1):page386_i47@pure_quanta.sconn288_adr50001p003c01(chips)"
			("LOCATION" "J20")
		)
		("@s9s_mb_2u_lib.s9s_mb_2u(sch_1):page386_i124@pure_quanta.sconn288_adr50001p003c01(chips)"
			("LOCATION" "J20")
		)
		("@s9s_mb_2u_lib.s9s_mb_2u(sch_1):page386_i176@pure_quanta.sconn288_adr50001p003c01(chips)"
			("LOCATION" "J20")
		)
		("@s9s_mb_2u_lib.s9s_mb_2u(sch_1):page386_i46@pure_quanta.q_res(chips)"
			("LOCATION" "R45")
		)
		("@s9s_mb_2u_lib.s9s_mb_2u(sch_1):page387_i124@pure_quanta.q_cap(chips)"
			("LOCATION" "C62")
		)
		("@s9s_mb_2u_lib.s9s_mb_2u(sch_1):page387_i127@pure_quanta.q_cap(chips)"
			("LOCATION" "C63")
		)
		("@s9s_mb_2u_lib.s9s_mb_2u(sch_1):page387_i167@pure_quanta.q_cap(chips)"
			("LOCATION" "C64")
		)
		("@s9s_mb_2u_lib.s9s_mb_2u(sch_1):page387_i13@pure_quanta.sconn288_adr50001p013c01(chips)"
			("LOCATION" "J21")
		)
		("@s9s_mb_2u_lib.s9s_mb_2u(sch_1):page387_i126@pure_quanta.sconn288_adr50001p013c01(chips)"
			("LOCATION" "J21")
		)
		("@s9s_mb_2u_lib.s9s_mb_2u(sch_1):page387_i169@pure_quanta.sconn288_adr50001p013c01(chips)"
			("LOCATION" "J21")
		)
		("@s9s_mb_2u_lib.s9s_mb_2u(sch_1):page387_i2@pure_quanta.q_res(chips)"
			("LOCATION" "R46")
		)
		("@s9s_mb_2u_lib.s9s_mb_2u(sch_1):page388_i122@pure_quanta.q_cap(chips)"
			("LOCATION" "C65")
		)
		("@s9s_mb_2u_lib.s9s_mb_2u(sch_1):page388_i126@pure_quanta.q_cap(chips)"
			("LOCATION" "C66")
		)
		("@s9s_mb_2u_lib.s9s_mb_2u(sch_1):page388_i128@pure_quanta.q_cap(chips)"
			("LOCATION" "C67")
		)
		("@s9s_mb_2u_lib.s9s_mb_2u(sch_1):page388_i51@pure_quanta.sconn288_adr50001p003c01(chips)"
			("LOCATION" "J22")
		)
		("@s9s_mb_2u_lib.s9s_mb_2u(sch_1):page388_i125@pure_quanta.sconn288_adr50001p003c01(chips)"
			("LOCATION" "J22")
		)
		("@s9s_mb_2u_lib.s9s_mb_2u(sch_1):page388_i176@pure_quanta.sconn288_adr50001p003c01(chips)"
			("LOCATION" "J22")
		)
		("@s9s_mb_2u_lib.s9s_mb_2u(sch_1):page388_i2@pure_quanta.q_res(chips)"
			("LOCATION" "R47")
		)
		("@s9s_mb_2u_lib.s9s_mb_2u(sch_1):page389_i122@pure_quanta.q_cap(chips)"
			("LOCATION" "C68")
		)
		("@s9s_mb_2u_lib.s9s_mb_2u(sch_1):page389_i127@pure_quanta.q_cap(chips)"
			("LOCATION" "C69")
		)
		("@s9s_mb_2u_lib.s9s_mb_2u(sch_1):page389_i129@pure_quanta.q_cap(chips)"
			("LOCATION" "C70")
		)
		("@s9s_mb_2u_lib.s9s_mb_2u(sch_1):page389_i25@pure_quanta.sconn288_adr50001p013c01(chips)"
			("LOCATION" "J23")
		)
		("@s9s_mb_2u_lib.s9s_mb_2u(sch_1):page389_i126@pure_quanta.sconn288_adr50001p013c01(chips)"
			("LOCATION" "J23")
		)
		("@s9s_mb_2u_lib.s9s_mb_2u(sch_1):page389_i175@pure_quanta.sconn288_adr50001p013c01(chips)"
			("LOCATION" "J23")
		)
		("@s9s_mb_2u_lib.s9s_mb_2u(sch_1):page389_i2@pure_quanta.q_res(chips)"
			("LOCATION" "R48")
		)
		("@s9s_mb_2u_lib.s9s_mb_2u(sch_1):page68_i4@pure_quanta.q_cap(chips)"
			("LOCATION" "C71")
		)
		("@s9s_mb_2u_lib.s9s_mb_2u(sch_1):page68_i1@pure_quanta.socket4677_azifs035p001c01(chips)"
			("LOCATION" "U1")
		)
		("@s9s_mb_2u_lib.s9s_mb_2u(sch_1):page68_i8@pure_quanta.socket4677_azifs035p001c01(chips)"
			("LOCATION" "U1")
		)
		("@s9s_mb_2u_lib.s9s_mb_2u(sch_1):page398_i116@pure_quanta.q_cap(chips)"
			("LOCATION" "C72")
		)
		("@s9s_mb_2u_lib.s9s_mb_2u(sch_1):page398_i120@pure_quanta.q_cap(chips)"
			("LOCATION" "C73")
		)
		("@s9s_mb_2u_lib.s9s_mb_2u(sch_1):page398_i122@pure_quanta.q_cap(chips)"
			("LOCATION" "C74")
		)
		("@s9s_mb_2u_lib.s9s_mb_2u(sch_1):page398_i179@pure_quanta.sconn288_adr50001p003c01(chips)"
			("LOCATION" "J32")
		)
		("@s9s_mb_2u_lib.s9s_mb_2u(sch_1):page398_i178@pure_quanta.sconn288_adr50001p003c01(chips)"
			("LOCATION" "J32")
		)
		("@s9s_mb_2u_lib.s9s_mb_2u(sch_1):page398_i177@pure_quanta.sconn288_adr50001p003c01(chips)"
			("LOCATION" "J32")
		)
		("@s9s_mb_2u_lib.s9s_mb_2u(sch_1):page398_i2@pure_quanta.q_res(chips)"
			("LOCATION" "R72")
		)
		("@s9s_mb_2u_lib.s9s_mb_2u(sch_1):page397_i124@pure_quanta.q_cap(chips)"
			("LOCATION" "C75")
		)
		("@s9s_mb_2u_lib.s9s_mb_2u(sch_1):page397_i125@pure_quanta.q_cap(chips)"
			("LOCATION" "C76")
		)
		("@s9s_mb_2u_lib.s9s_mb_2u(sch_1):page397_i126@pure_quanta.q_cap(chips)"
			("LOCATION" "C77")
		)
		("@s9s_mb_2u_lib.s9s_mb_2u(sch_1):page397_i180@pure_quanta.sconn288_adr50001p013c01(chips)"
			("LOCATION" "J31")
		)
		("@s9s_mb_2u_lib.s9s_mb_2u(sch_1):page397_i179@pure_quanta.sconn288_adr50001p013c01(chips)"
			("LOCATION" "J31")
		)
		("@s9s_mb_2u_lib.s9s_mb_2u(sch_1):page397_i178@pure_quanta.sconn288_adr50001p013c01(chips)"
			("LOCATION" "J31")
		)
		("@s9s_mb_2u_lib.s9s_mb_2u(sch_1):page397_i3@pure_quanta.q_res(chips)"
			("LOCATION" "R73")
		)
		("@s9s_mb_2u_lib.s9s_mb_2u(sch_1):page396_i54@pure_quanta.q_cap(chips)"
			("LOCATION" "C78")
		)
		("@s9s_mb_2u_lib.s9s_mb_2u(sch_1):page396_i56@pure_quanta.q_cap(chips)"
			("LOCATION" "C79")
		)
		("@s9s_mb_2u_lib.s9s_mb_2u(sch_1):page396_i59@pure_quanta.q_cap(chips)"
			("LOCATION" "C80")
		)
		("@s9s_mb_2u_lib.s9s_mb_2u(sch_1):page396_i179@pure_quanta.sconn288_adr50001p003c01(chips)"
			("LOCATION" "J30")
		)
		("@s9s_mb_2u_lib.s9s_mb_2u(sch_1):page396_i177@pure_quanta.sconn288_adr50001p003c01(chips)"
			("LOCATION" "J30")
		)
		("@s9s_mb_2u_lib.s9s_mb_2u(sch_1):page396_i178@pure_quanta.sconn288_adr50001p003c01(chips)"
			("LOCATION" "J30")
		)
		("@s9s_mb_2u_lib.s9s_mb_2u(sch_1):page396_i5@pure_quanta.q_res(chips)"
			("LOCATION" "R74")
		)
		("@s9s_mb_2u_lib.s9s_mb_2u(sch_1):page395_i120@pure_quanta.q_cap(chips)"
			("LOCATION" "C81")
		)
		("@s9s_mb_2u_lib.s9s_mb_2u(sch_1):page395_i124@pure_quanta.q_cap(chips)"
			("LOCATION" "C82")
		)
		("@s9s_mb_2u_lib.s9s_mb_2u(sch_1):page395_i126@pure_quanta.q_cap(chips)"
			("LOCATION" "C83")
		)
		("@s9s_mb_2u_lib.s9s_mb_2u(sch_1):page395_i179@pure_quanta.sconn288_adr50001p013c01(chips)"
			("LOCATION" "J29")
		)
		("@s9s_mb_2u_lib.s9s_mb_2u(sch_1):page395_i177@pure_quanta.sconn288_adr50001p013c01(chips)"
			("LOCATION" "J29")
		)
		("@s9s_mb_2u_lib.s9s_mb_2u(sch_1):page395_i178@pure_quanta.sconn288_adr50001p013c01(chips)"
			("LOCATION" "J29")
		)
		("@s9s_mb_2u_lib.s9s_mb_2u(sch_1):page395_i47@pure_quanta.q_res(chips)"
			("LOCATION" "R75")
		)
		("@s9s_mb_2u_lib.s9s_mb_2u(sch_1):page394_i121@pure_quanta.q_cap(chips)"
			("LOCATION" "C84")
		)
		("@s9s_mb_2u_lib.s9s_mb_2u(sch_1):page394_i125@pure_quanta.q_cap(chips)"
			("LOCATION" "C85")
		)
		("@s9s_mb_2u_lib.s9s_mb_2u(sch_1):page394_i128@pure_quanta.q_cap(chips)"
			("LOCATION" "C86")
		)
		("@s9s_mb_2u_lib.s9s_mb_2u(sch_1):page394_i47@pure_quanta.sconn288_adr50001p003c01(chips)"
			("LOCATION" "J28")
		)
		("@s9s_mb_2u_lib.s9s_mb_2u(sch_1):page394_i124@pure_quanta.sconn288_adr50001p003c01(chips)"
			("LOCATION" "J28")
		)
		("@s9s_mb_2u_lib.s9s_mb_2u(sch_1):page394_i176@pure_quanta.sconn288_adr50001p003c01(chips)"
			("LOCATION" "J28")
		)
		("@s9s_mb_2u_lib.s9s_mb_2u(sch_1):page394_i46@pure_quanta.q_res(chips)"
			("LOCATION" "R76")
		)
		("@s9s_mb_2u_lib.s9s_mb_2u(sch_1):page393_i121@pure_quanta.q_cap(chips)"
			("LOCATION" "C87")
		)
		("@s9s_mb_2u_lib.s9s_mb_2u(sch_1):page393_i123@pure_quanta.q_cap(chips)"
			("LOCATION" "C88")
		)
		("@s9s_mb_2u_lib.s9s_mb_2u(sch_1):page393_i160@pure_quanta.q_cap(chips)"
			("LOCATION" "C89")
		)
		("@s9s_mb_2u_lib.s9s_mb_2u(sch_1):page393_i179@pure_quanta.sconn288_adr50001p013c01(chips)"
			("LOCATION" "J27")
		)
		("@s9s_mb_2u_lib.s9s_mb_2u(sch_1):page393_i177@pure_quanta.sconn288_adr50001p013c01(chips)"
			("LOCATION" "J27")
		)
		("@s9s_mb_2u_lib.s9s_mb_2u(sch_1):page393_i178@pure_quanta.sconn288_adr50001p013c01(chips)"
			("LOCATION" "J27")
		)
		("@s9s_mb_2u_lib.s9s_mb_2u(sch_1):page393_i10@pure_quanta.q_res(chips)"
			("LOCATION" "R77")
		)
		("@s9s_mb_2u_lib.s9s_mb_2u(sch_1):page392_i122@pure_quanta.q_cap(chips)"
			("LOCATION" "C90")
		)
		("@s9s_mb_2u_lib.s9s_mb_2u(sch_1):page392_i126@pure_quanta.q_cap(chips)"
			("LOCATION" "C91")
		)
		("@s9s_mb_2u_lib.s9s_mb_2u(sch_1):page392_i128@pure_quanta.q_cap(chips)"
			("LOCATION" "C92")
		)
		("@s9s_mb_2u_lib.s9s_mb_2u(sch_1):page392_i180@pure_quanta.sconn288_adr50001p003c01(chips)"
			("LOCATION" "J26")
		)
		("@s9s_mb_2u_lib.s9s_mb_2u(sch_1):page392_i178@pure_quanta.sconn288_adr50001p003c01(chips)"
			("LOCATION" "J26")
		)
		("@s9s_mb_2u_lib.s9s_mb_2u(sch_1):page392_i179@pure_quanta.sconn288_adr50001p003c01(chips)"
			("LOCATION" "J26")
		)
		("@s9s_mb_2u_lib.s9s_mb_2u(sch_1):page392_i2@pure_quanta.q_res(chips)"
			("LOCATION" "R78")
		)
		("@s9s_mb_2u_lib.s9s_mb_2u(sch_1):page391_i122@pure_quanta.q_cap(chips)"
			("LOCATION" "C93")
		)
		("@s9s_mb_2u_lib.s9s_mb_2u(sch_1):page391_i127@pure_quanta.q_cap(chips)"
			("LOCATION" "C94")
		)
		("@s9s_mb_2u_lib.s9s_mb_2u(sch_1):page391_i130@pure_quanta.q_cap(chips)"
			("LOCATION" "C95")
		)
		("@s9s_mb_2u_lib.s9s_mb_2u(sch_1):page391_i180@pure_quanta.sconn288_adr50001p013c01(chips)"
			("LOCATION" "J25")
		)
		("@s9s_mb_2u_lib.s9s_mb_2u(sch_1):page391_i179@pure_quanta.sconn288_adr50001p013c01(chips)"
			("LOCATION" "J25")
		)
		("@s9s_mb_2u_lib.s9s_mb_2u(sch_1):page391_i178@pure_quanta.sconn288_adr50001p013c01(chips)"
			("LOCATION" "J25")
		)
		("@s9s_mb_2u_lib.s9s_mb_2u(sch_1):page391_i2@pure_quanta.q_res(chips)"
			("LOCATION" "R79")
		)
		("@s9s_mb_2u_lib.s9s_mb_2u(sch_1):page390_i123@pure_quanta.q_cap(chips)"
			("LOCATION" "C96")
		)
		("@s9s_mb_2u_lib.s9s_mb_2u(sch_1):page390_i124@pure_quanta.q_cap(chips)"
			("LOCATION" "C97")
		)
		("@s9s_mb_2u_lib.s9s_mb_2u(sch_1):page390_i146@pure_quanta.q_cap(chips)"
			("LOCATION" "C98")
		)
		("@s9s_mb_2u_lib.s9s_mb_2u(sch_1):page390_i178@pure_quanta.sconn288_adr50001p003c01(chips)"
			("LOCATION" "J24")
		)
		("@s9s_mb_2u_lib.s9s_mb_2u(sch_1):page390_i179@pure_quanta.sconn288_adr50001p003c01(chips)"
			("LOCATION" "J24")
		)
		("@s9s_mb_2u_lib.s9s_mb_2u(sch_1):page390_i180@pure_quanta.sconn288_adr50001p003c01(chips)"
			("LOCATION" "J24")
		)
		("@s9s_mb_2u_lib.s9s_mb_2u(sch_1):page390_i2@pure_quanta.q_res(chips)"
			("LOCATION" "R80")
		)
		("@s9s_mb_2u_lib.s9s_mb_2u(sch_1):page484_i82@pure_quanta.q_cap(chips)"
			("LOCATION" "C99")
		)
		("@s9s_mb_2u_lib.s9s_mb_2u(sch_1):page484_i114@pure_quanta.q_cap(chips)"
			("LOCATION" "C106")
		)
		("@s9s_mb_2u_lib.s9s_mb_2u(sch_1):page484_i120@pure_quanta.mosfet_n_123(chips)"
			("LOCATION" "Q27")
		)
		("@s9s_mb_2u_lib.s9s_mb_2u(sch_1):page484_i121@pure_quanta.mosfet_n_123(chips)"
			("LOCATION" "Q28")
		)
		("@s9s_mb_2u_lib.s9s_mb_2u(sch_1):page484_i78@pure_quanta.q_res(chips)"
			("LOCATION" "R81")
		)
		("@s9s_mb_2u_lib.s9s_mb_2u(sch_1):page484_i111@pure_quanta.q_res(chips)"
			("LOCATION" "R199")
		)
		("@s9s_mb_2u_lib.s9s_mb_2u(sch_1):page484_i102@pure_quanta.q_res(chips)"
			("LOCATION" "R200")
		)
		("@s9s_mb_2u_lib.s9s_mb_2u(sch_1):page484_i108@pure_quanta.q_res(chips)"
			("LOCATION" "R201")
		)
		("@s9s_mb_2u_lib.s9s_mb_2u(sch_1):page484_i110@pure_quanta.q_res(chips)"
			("LOCATION" "R202")
		)
		("@s9s_mb_2u_lib.s9s_mb_2u(sch_1):page484_i98@pure_quanta.q_res(chips)"
			("LOCATION" "R203")
		)
		("@s9s_mb_2u_lib.s9s_mb_2u(sch_1):page484_i100@pure_quanta.q_res(chips)"
			("LOCATION" "R204")
		)
		("@s9s_mb_2u_lib.s9s_mb_2u(sch_1):page484_i101@pure_quanta.q_res(chips)"
			("LOCATION" "R205")
		)
		("@s9s_mb_2u_lib.s9s_mb_2u(sch_1):page484_i99@pure_quanta.q_res(chips)"
			("LOCATION" "R206")
		)
		("@s9s_mb_2u_lib.s9s_mb_2u(sch_1):page484_i23@pure_quanta.q_res(chips)"
			("LOCATION" "R207")
		)
		("@s9s_mb_2u_lib.s9s_mb_2u(sch_1):page484_i26@pure_quanta.q_res(chips)"
			("LOCATION" "R208")
		)
		("@s9s_mb_2u_lib.s9s_mb_2u(sch_1):page484_i65@pure_quanta.q_res(chips)"
			("LOCATION" "R209")
		)
		("@s9s_mb_2u_lib.s9s_mb_2u(sch_1):page484_i66@pure_quanta.q_res(chips)"
			("LOCATION" "R210")
		)
		("@s9s_mb_2u_lib.s9s_mb_2u(sch_1):page484_i87@pure_quanta.q_res(chips)"
			("LOCATION" "R211")
		)
		("@s9s_mb_2u_lib.s9s_mb_2u(sch_1):page484_i88@pure_quanta.q_res(chips)"
			("LOCATION" "R212")
		)
		("@s9s_mb_2u_lib.s9s_mb_2u(sch_1):page484_i89@pure_quanta.q_res(chips)"
			("LOCATION" "R213")
		)
		("@s9s_mb_2u_lib.s9s_mb_2u(sch_1):page484_i90@pure_quanta.q_res(chips)"
			("LOCATION" "R214")
		)
		("@s9s_mb_2u_lib.s9s_mb_2u(sch_1):page484_i91@pure_quanta.q_res(chips)"
			("LOCATION" "R215")
		)
		("@s9s_mb_2u_lib.s9s_mb_2u(sch_1):page484_i94@pure_quanta.q_res(chips)"
			("LOCATION" "R216")
		)
		("@s9s_mb_2u_lib.s9s_mb_2u(sch_1):page484_i92@pure_quanta.q_res(chips)"
			("LOCATION" "R217")
		)
		("@s9s_mb_2u_lib.s9s_mb_2u(sch_1):page484_i93@pure_quanta.q_res(chips)"
			("LOCATION" "R218")
		)
		("@s9s_mb_2u_lib.s9s_mb_2u(sch_1):page484_i54@pure_quanta.q_res(chips)"
			("LOCATION" "R219")
		)
		("@s9s_mb_2u_lib.s9s_mb_2u(sch_1):page484_i63@pure_quanta.q_res(chips)"
			("LOCATION" "R220")
		)
		("@s9s_mb_2u_lib.s9s_mb_2u(sch_1):page484_i53@pure_quanta.q_res(chips)"
			("LOCATION" "R221")
		)
		("@s9s_mb_2u_lib.s9s_mb_2u(sch_1):page484_i62@pure_quanta.q_res(chips)"
			("LOCATION" "R222")
		)
		("@s9s_mb_2u_lib.s9s_mb_2u(sch_1):page484_i116@pure_quanta.q_res(chips)"
			("LOCATION" "R223")
		)
		("@s9s_mb_2u_lib.s9s_mb_2u(sch_1):page484_i117@pure_quanta.q_res(chips)"
			("LOCATION" "R224")
		)
		("@s9s_mb_2u_lib.s9s_mb_2u(sch_1):page484_i75@pure_quanta.q_res(chips)"
			("LOCATION" "R225")
		)
		("@s9s_mb_2u_lib.s9s_mb_2u(sch_1):page484_i79@pure_quanta.q_res(chips)"
			("LOCATION" "R226")
		)
		("@s9s_mb_2u_lib.s9s_mb_2u(sch_1):page484_i80@pure_quanta.q_res(chips)"
			("LOCATION" "R227")
		)
		("@s9s_mb_2u_lib.s9s_mb_2u(sch_1):page484_i81@pure_quanta.q_res(chips)"
			("LOCATION" "R228")
		)
		("@s9s_mb_2u_lib.s9s_mb_2u(sch_1):page484_i122@pure_quanta.q_res(chips)"
			("LOCATION" "R1774")
		)
		("@s9s_mb_2u_lib.s9s_mb_2u(sch_1):page484_i124@pure_quanta.q_res(chips)"
			("LOCATION" "R1775")
		)
		("@s9s_mb_2u_lib.s9s_mb_2u(sch_1):page484_i85@pure_quanta.gtl2014pw(chips)"
			("LOCATION" "U8")
		)
		("@s9s_mb_2u_lib.s9s_mb_2u(sch_1):page480_i43@pure_quanta.q_cap(chips)"
			("LOCATION" "C100")
		)
		("@s9s_mb_2u_lib.s9s_mb_2u(sch_1):page480_i95@pure_quanta.q_cap(chips)"
			("LOCATION" "C107")
		)
		("@s9s_mb_2u_lib.s9s_mb_2u(sch_1):page480_i30@pure_quanta.q_res(chips)"
			("LOCATION" "R82")
		)
		("@s9s_mb_2u_lib.s9s_mb_2u(sch_1):page480_i41@pure_quanta.q_res(chips)"
			("LOCATION" "R83")
		)
		("@s9s_mb_2u_lib.s9s_mb_2u(sch_1):page480_i65@pure_quanta.q_res(chips)"
			("LOCATION" "R296")
		)
		("@s9s_mb_2u_lib.s9s_mb_2u(sch_1):page480_i23@pure_quanta.q_res(chips)"
			("LOCATION" "R297")
		)
		("@s9s_mb_2u_lib.s9s_mb_2u(sch_1):page480_i67@pure_quanta.q_res(chips)"
			("LOCATION" "R298")
		)
		("@s9s_mb_2u_lib.s9s_mb_2u(sch_1):page480_i63@pure_quanta.q_res(chips)"
			("LOCATION" "R299")
		)
		("@s9s_mb_2u_lib.s9s_mb_2u(sch_1):page480_i69@pure_quanta.q_res(chips)"
			("LOCATION" "R300")
		)
		("@s9s_mb_2u_lib.s9s_mb_2u(sch_1):page480_i73@pure_quanta.q_res(chips)"
			("LOCATION" "R301")
		)
		("@s9s_mb_2u_lib.s9s_mb_2u(sch_1):page480_i75@pure_quanta.q_res(chips)"
			("LOCATION" "R302")
		)
		("@s9s_mb_2u_lib.s9s_mb_2u(sch_1):page480_i76@pure_quanta.q_res(chips)"
			("LOCATION" "R303")
		)
		("@s9s_mb_2u_lib.s9s_mb_2u(sch_1):page480_i72@pure_quanta.q_res(chips)"
			("LOCATION" "R304")
		)
		("@s9s_mb_2u_lib.s9s_mb_2u(sch_1):page480_i77@pure_quanta.q_res(chips)"
			("LOCATION" "R305")
		)
		("@s9s_mb_2u_lib.s9s_mb_2u(sch_1):page480_i71@pure_quanta.q_res(chips)"
			("LOCATION" "R306")
		)
		("@s9s_mb_2u_lib.s9s_mb_2u(sch_1):page480_i82@pure_quanta.q_res(chips)"
			("LOCATION" "R307")
		)
		("@s9s_mb_2u_lib.s9s_mb_2u(sch_1):page480_i91@pure_quanta.q_res(chips)"
			("LOCATION" "R308")
		)
		("@s9s_mb_2u_lib.s9s_mb_2u(sch_1):page480_i93@pure_quanta.q_res(chips)"
			("LOCATION" "R309")
		)
		("@s9s_mb_2u_lib.s9s_mb_2u(sch_1):page480_i45@pure_quanta.q_res(chips)"
			("LOCATION" "R310")
		)
		("@s9s_mb_2u_lib.s9s_mb_2u(sch_1):page480_i44@pure_quanta.q_res(chips)"
			("LOCATION" "R311")
		)
		("@s9s_mb_2u_lib.s9s_mb_2u(sch_1):page480_i85@pure_quanta.q_res(chips)"
			("LOCATION" "R312")
		)
		("@s9s_mb_2u_lib.s9s_mb_2u(sch_1):page480_i86@pure_quanta.q_res(chips)"
			("LOCATION" "R313")
		)
		("@s9s_mb_2u_lib.s9s_mb_2u(sch_1):page480_i89@pure_quanta.q_res(chips)"
			("LOCATION" "R314")
		)
		("@s9s_mb_2u_lib.s9s_mb_2u(sch_1):page480_i92@pure_quanta.q_res(chips)"
			("LOCATION" "R315")
		)
		("@s9s_mb_2u_lib.s9s_mb_2u(sch_1):page480_i34@pure_quanta.gtl2014pw(chips)"
			("LOCATION" "U9")
		)
		("@s9s_mb_2u_lib.s9s_mb_2u(sch_1):page364_i148@pure_quanta.q_cap(chips)"
			("LOCATION" "C101")
		)
		("@s9s_mb_2u_lib.s9s_mb_2u(sch_1):page364_i159@pure_quanta.q_cap(chips)"
			("LOCATION" "C212")
		)
		("@s9s_mb_2u_lib.s9s_mb_2u(sch_1):page364_i149@pure_quanta.q_cap(chips)"
			("LOCATION" "C213")
		)
		("@s9s_mb_2u_lib.s9s_mb_2u(sch_1):page364_i151@pure_quanta.q_cap(chips)"
			("LOCATION" "C214")
		)
		("@s9s_mb_2u_lib.s9s_mb_2u(sch_1):page364_i152@pure_quanta.q_cap(chips)"
			("LOCATION" "C215")
		)
		("@s9s_mb_2u_lib.s9s_mb_2u(sch_1):page364_i153@pure_quanta.q_cap(chips)"
			("LOCATION" "C216")
		)
		("@s9s_mb_2u_lib.s9s_mb_2u(sch_1):page364_i154@pure_quanta.q_cap(chips)"
			("LOCATION" "C217")
		)
		("@s9s_mb_2u_lib.s9s_mb_2u(sch_1):page364_i155@pure_quanta.q_cap(chips)"
			("LOCATION" "C218")
		)
		("@s9s_mb_2u_lib.s9s_mb_2u(sch_1):page364_i156@pure_quanta.q_cap(chips)"
			("LOCATION" "C219")
		)
		("@s9s_mb_2u_lib.s9s_mb_2u(sch_1):page364_i158@pure_quanta.q_cap(chips)"
			("LOCATION" "C220")
		)
		("@s9s_mb_2u_lib.s9s_mb_2u(sch_1):page364_i102@pure_quanta.q_cap(chips)"
			("LOCATION" "C399")
		)
		("@s9s_mb_2u_lib.s9s_mb_2u(sch_1):page364_i134@pure_quanta.q_cap(chips)"
			("LOCATION" "C400")
		)
		("@s9s_mb_2u_lib.s9s_mb_2u(sch_1):page364_i105@pure_quanta.q_cap(chips)"
			("LOCATION" "C401")
		)
		("@s9s_mb_2u_lib.s9s_mb_2u(sch_1):page364_i133@pure_quanta.q_cap(chips)"
			("LOCATION" "C402")
		)
		("@s9s_mb_2u_lib.s9s_mb_2u(sch_1):page364_i104@pure_quanta.q_cap(chips)"
			("LOCATION" "C403")
		)
		("@s9s_mb_2u_lib.s9s_mb_2u(sch_1):page364_i132@pure_quanta.q_cap(chips)"
			("LOCATION" "C404")
		)
		("@s9s_mb_2u_lib.s9s_mb_2u(sch_1):page364_i103@pure_quanta.q_cap(chips)"
			("LOCATION" "C405")
		)
		("@s9s_mb_2u_lib.s9s_mb_2u(sch_1):page364_i131@pure_quanta.q_cap(chips)"
			("LOCATION" "C406")
		)
		("@s9s_mb_2u_lib.s9s_mb_2u(sch_1):page364_i135@pure_quanta.q_cap(chips)"
			("LOCATION" "C407")
		)
		("@s9s_mb_2u_lib.s9s_mb_2u(sch_1):page364_i115@pure_quanta.q_cap(chips)"
			("LOCATION" "C408")
		)
		("@s9s_mb_2u_lib.s9s_mb_2u(sch_1):page364_i136@pure_quanta.q_cap(chips)"
			("LOCATION" "C409")
		)
		("@s9s_mb_2u_lib.s9s_mb_2u(sch_1):page364_i114@pure_quanta.q_cap(chips)"
			("LOCATION" "C410")
		)
		("@s9s_mb_2u_lib.s9s_mb_2u(sch_1):page364_i137@pure_quanta.q_cap(chips)"
			("LOCATION" "C411")
		)
		("@s9s_mb_2u_lib.s9s_mb_2u(sch_1):page364_i113@pure_quanta.q_cap(chips)"
			("LOCATION" "C412")
		)
		("@s9s_mb_2u_lib.s9s_mb_2u(sch_1):page364_i138@pure_quanta.q_cap(chips)"
			("LOCATION" "C413")
		)
		("@s9s_mb_2u_lib.s9s_mb_2u(sch_1):page364_i112@pure_quanta.q_cap(chips)"
			("LOCATION" "C414")
		)
		("@s9s_mb_2u_lib.s9s_mb_2u(sch_1):page364_i139@pure_quanta.q_cap(chips)"
			("LOCATION" "C415")
		)
		("@s9s_mb_2u_lib.s9s_mb_2u(sch_1):page364_i111@pure_quanta.q_cap(chips)"
			("LOCATION" "C416")
		)
		("@s9s_mb_2u_lib.s9s_mb_2u(sch_1):page364_i140@pure_quanta.q_cap(chips)"
			("LOCATION" "C417")
		)
		("@s9s_mb_2u_lib.s9s_mb_2u(sch_1):page364_i141@pure_quanta.q_cap(chips)"
			("LOCATION" "C418")
		)
		("@s9s_mb_2u_lib.s9s_mb_2u(sch_1):page364_i142@pure_quanta.q_cap(chips)"
			("LOCATION" "C419")
		)
		("@s9s_mb_2u_lib.s9s_mb_2u(sch_1):page364_i146@pure_quanta.q_cap(chips)"
			("LOCATION" "C420")
		)
		("@s9s_mb_2u_lib.s9s_mb_2u(sch_1):page364_i145@pure_quanta.q_cap(chips)"
			("LOCATION" "C421")
		)
		("@s9s_mb_2u_lib.s9s_mb_2u(sch_1):page364_i143@pure_quanta.q_cap(chips)"
			("LOCATION" "C422")
		)
		("@s9s_mb_2u_lib.s9s_mb_2u(sch_1):page364_i171@pure_quanta.q_cap(chips)"
			("LOCATION" "C590")
		)
		("@s9s_mb_2u_lib.s9s_mb_2u(sch_1):page364_i7@pure_quanta.q_cap(chips)"
			("LOCATION" "C966")
		)
		("@s9s_mb_2u_lib.s9s_mb_2u(sch_1):page364_i53@pure_quanta.q_cap(chips)"
			("LOCATION" "C967")
		)
		("@s9s_mb_2u_lib.s9s_mb_2u(sch_1):page364_i99@pure_quanta.q_cap(chips)"
			("LOCATION" "C968")
		)
		("@s9s_mb_2u_lib.s9s_mb_2u(sch_1):page364_i101@pure_quanta.q_cap(chips)"
			("LOCATION" "C969")
		)
		("@s9s_mb_2u_lib.s9s_mb_2u(sch_1):page364_i8@pure_quanta.q_cap(chips)"
			("LOCATION" "C970")
		)
		("@s9s_mb_2u_lib.s9s_mb_2u(sch_1):page364_i52@pure_quanta.q_cap(chips)"
			("LOCATION" "C971")
		)
		("@s9s_mb_2u_lib.s9s_mb_2u(sch_1):page364_i97@pure_quanta.q_cap(chips)"
			("LOCATION" "C972")
		)
		("@s9s_mb_2u_lib.s9s_mb_2u(sch_1):page364_i98@pure_quanta.q_cap(chips)"
			("LOCATION" "C973")
		)
		("@s9s_mb_2u_lib.s9s_mb_2u(sch_1):page364_i9@pure_quanta.q_cap(chips)"
			("LOCATION" "C974")
		)
		("@s9s_mb_2u_lib.s9s_mb_2u(sch_1):page364_i51@pure_quanta.q_cap(chips)"
			("LOCATION" "C975")
		)
		("@s9s_mb_2u_lib.s9s_mb_2u(sch_1):page364_i95@pure_quanta.q_cap(chips)"
			("LOCATION" "C976")
		)
		("@s9s_mb_2u_lib.s9s_mb_2u(sch_1):page364_i96@pure_quanta.q_cap(chips)"
			("LOCATION" "C977")
		)
		("@s9s_mb_2u_lib.s9s_mb_2u(sch_1):page364_i10@pure_quanta.q_cap(chips)"
			("LOCATION" "C978")
		)
		("@s9s_mb_2u_lib.s9s_mb_2u(sch_1):page364_i50@pure_quanta.q_cap(chips)"
			("LOCATION" "C979")
		)
		("@s9s_mb_2u_lib.s9s_mb_2u(sch_1):page364_i93@pure_quanta.q_cap(chips)"
			("LOCATION" "C980")
		)
		("@s9s_mb_2u_lib.s9s_mb_2u(sch_1):page364_i94@pure_quanta.q_cap(chips)"
			("LOCATION" "C981")
		)
		("@s9s_mb_2u_lib.s9s_mb_2u(sch_1):page364_i12@pure_quanta.q_cap(chips)"
			("LOCATION" "C982")
		)
		("@s9s_mb_2u_lib.s9s_mb_2u(sch_1):page364_i49@pure_quanta.q_cap(chips)"
			("LOCATION" "C983")
		)
		("@s9s_mb_2u_lib.s9s_mb_2u(sch_1):page364_i91@pure_quanta.q_cap(chips)"
			("LOCATION" "C984")
		)
		("@s9s_mb_2u_lib.s9s_mb_2u(sch_1):page364_i92@pure_quanta.q_cap(chips)"
			("LOCATION" "C985")
		)
		("@s9s_mb_2u_lib.s9s_mb_2u(sch_1):page364_i14@pure_quanta.q_cap(chips)"
			("LOCATION" "C986")
		)
		("@s9s_mb_2u_lib.s9s_mb_2u(sch_1):page364_i48@pure_quanta.q_cap(chips)"
			("LOCATION" "C987")
		)
		("@s9s_mb_2u_lib.s9s_mb_2u(sch_1):page364_i89@pure_quanta.q_cap(chips)"
			("LOCATION" "C988")
		)
		("@s9s_mb_2u_lib.s9s_mb_2u(sch_1):page364_i90@pure_quanta.q_cap(chips)"
			("LOCATION" "C989")
		)
		("@s9s_mb_2u_lib.s9s_mb_2u(sch_1):page364_i13@pure_quanta.q_cap(chips)"
			("LOCATION" "C990")
		)
		("@s9s_mb_2u_lib.s9s_mb_2u(sch_1):page364_i47@pure_quanta.q_cap(chips)"
			("LOCATION" "C991")
		)
		("@s9s_mb_2u_lib.s9s_mb_2u(sch_1):page364_i88@pure_quanta.q_cap(chips)"
			("LOCATION" "C992")
		)
		("@s9s_mb_2u_lib.s9s_mb_2u(sch_1):page364_i87@pure_quanta.q_cap(chips)"
			("LOCATION" "C993")
		)
		("@s9s_mb_2u_lib.s9s_mb_2u(sch_1):page364_i17@pure_quanta.q_cap(chips)"
			("LOCATION" "C994")
		)
		("@s9s_mb_2u_lib.s9s_mb_2u(sch_1):page364_i46@pure_quanta.q_cap(chips)"
			("LOCATION" "C995")
		)
		("@s9s_mb_2u_lib.s9s_mb_2u(sch_1):page364_i85@pure_quanta.q_cap(chips)"
			("LOCATION" "C996")
		)
		("@s9s_mb_2u_lib.s9s_mb_2u(sch_1):page364_i86@pure_quanta.q_cap(chips)"
			("LOCATION" "C997")
		)
		("@s9s_mb_2u_lib.s9s_mb_2u(sch_1):page364_i15@pure_quanta.q_cap(chips)"
			("LOCATION" "C998")
		)
		("@s9s_mb_2u_lib.s9s_mb_2u(sch_1):page364_i44@pure_quanta.q_cap(chips)"
			("LOCATION" "C999")
		)
		("@s9s_mb_2u_lib.s9s_mb_2u(sch_1):page364_i81@pure_quanta.q_cap(chips)"
			("LOCATION" "C1000")
		)
		("@s9s_mb_2u_lib.s9s_mb_2u(sch_1):page364_i82@pure_quanta.q_cap(chips)"
			("LOCATION" "C1001")
		)
		("@s9s_mb_2u_lib.s9s_mb_2u(sch_1):page364_i16@pure_quanta.q_cap(chips)"
			("LOCATION" "C1002")
		)
		("@s9s_mb_2u_lib.s9s_mb_2u(sch_1):page364_i42@pure_quanta.q_cap(chips)"
			("LOCATION" "C1003")
		)
		("@s9s_mb_2u_lib.s9s_mb_2u(sch_1):page364_i78@pure_quanta.q_cap(chips)"
			("LOCATION" "C1004")
		)
		("@s9s_mb_2u_lib.s9s_mb_2u(sch_1):page364_i80@pure_quanta.q_cap(chips)"
			("LOCATION" "C1005")
		)
		("@s9s_mb_2u_lib.s9s_mb_2u(sch_1):page364_i29@pure_quanta.q_cap(chips)"
			("LOCATION" "C1006")
		)
		("@s9s_mb_2u_lib.s9s_mb_2u(sch_1):page364_i41@pure_quanta.q_cap(chips)"
			("LOCATION" "C1007")
		)
		("@s9s_mb_2u_lib.s9s_mb_2u(sch_1):page364_i75@pure_quanta.q_cap(chips)"
			("LOCATION" "C1008")
		)
		("@s9s_mb_2u_lib.s9s_mb_2u(sch_1):page364_i77@pure_quanta.q_cap(chips)"
			("LOCATION" "C1009")
		)
		("@s9s_mb_2u_lib.s9s_mb_2u(sch_1):page364_i18@pure_quanta.q_cap(chips)"
			("LOCATION" "C1010")
		)
		("@s9s_mb_2u_lib.s9s_mb_2u(sch_1):page364_i40@pure_quanta.q_cap(chips)"
			("LOCATION" "C1011")
		)
		("@s9s_mb_2u_lib.s9s_mb_2u(sch_1):page364_i73@pure_quanta.q_cap(chips)"
			("LOCATION" "C1012")
		)
		("@s9s_mb_2u_lib.s9s_mb_2u(sch_1):page364_i74@pure_quanta.q_cap(chips)"
			("LOCATION" "C1013")
		)
		("@s9s_mb_2u_lib.s9s_mb_2u(sch_1):page364_i19@pure_quanta.q_cap(chips)"
			("LOCATION" "C1014")
		)
		("@s9s_mb_2u_lib.s9s_mb_2u(sch_1):page364_i39@pure_quanta.q_cap(chips)"
			("LOCATION" "C1015")
		)
		("@s9s_mb_2u_lib.s9s_mb_2u(sch_1):page364_i71@pure_quanta.q_cap(chips)"
			("LOCATION" "C1016")
		)
		("@s9s_mb_2u_lib.s9s_mb_2u(sch_1):page364_i72@pure_quanta.q_cap(chips)"
			("LOCATION" "C1017")
		)
		("@s9s_mb_2u_lib.s9s_mb_2u(sch_1):page364_i20@pure_quanta.q_cap(chips)"
			("LOCATION" "C1018")
		)
		("@s9s_mb_2u_lib.s9s_mb_2u(sch_1):page364_i38@pure_quanta.q_cap(chips)"
			("LOCATION" "C1019")
		)
		("@s9s_mb_2u_lib.s9s_mb_2u(sch_1):page364_i69@pure_quanta.q_cap(chips)"
			("LOCATION" "C1020")
		)
		("@s9s_mb_2u_lib.s9s_mb_2u(sch_1):page364_i70@pure_quanta.q_cap(chips)"
			("LOCATION" "C1021")
		)
		("@s9s_mb_2u_lib.s9s_mb_2u(sch_1):page364_i21@pure_quanta.q_cap(chips)"
			("LOCATION" "C1022")
		)
		("@s9s_mb_2u_lib.s9s_mb_2u(sch_1):page364_i37@pure_quanta.q_cap(chips)"
			("LOCATION" "C1023")
		)
		("@s9s_mb_2u_lib.s9s_mb_2u(sch_1):page364_i66@pure_quanta.q_cap(chips)"
			("LOCATION" "C1024")
		)
		("@s9s_mb_2u_lib.s9s_mb_2u(sch_1):page364_i68@pure_quanta.q_cap(chips)"
			("LOCATION" "C1025")
		)
		("@s9s_mb_2u_lib.s9s_mb_2u(sch_1):page364_i22@pure_quanta.q_cap(chips)"
			("LOCATION" "C1026")
		)
		("@s9s_mb_2u_lib.s9s_mb_2u(sch_1):page364_i36@pure_quanta.q_cap(chips)"
			("LOCATION" "C1027")
		)
		("@s9s_mb_2u_lib.s9s_mb_2u(sch_1):page364_i65@pure_quanta.q_cap(chips)"
			("LOCATION" "C1028")
		)
		("@s9s_mb_2u_lib.s9s_mb_2u(sch_1):page364_i67@pure_quanta.q_cap(chips)"
			("LOCATION" "C1029")
		)
		("@s9s_mb_2u_lib.s9s_mb_2u(sch_1):page364_i23@pure_quanta.q_cap(chips)"
			("LOCATION" "C1030")
		)
		("@s9s_mb_2u_lib.s9s_mb_2u(sch_1):page364_i35@pure_quanta.q_cap(chips)"
			("LOCATION" "C1031")
		)
		("@s9s_mb_2u_lib.s9s_mb_2u(sch_1):page364_i63@pure_quanta.q_cap(chips)"
			("LOCATION" "C1032")
		)
		("@s9s_mb_2u_lib.s9s_mb_2u(sch_1):page364_i64@pure_quanta.q_cap(chips)"
			("LOCATION" "C1033")
		)
		("@s9s_mb_2u_lib.s9s_mb_2u(sch_1):page364_i24@pure_quanta.q_cap(chips)"
			("LOCATION" "C1034")
		)
		("@s9s_mb_2u_lib.s9s_mb_2u(sch_1):page364_i33@pure_quanta.q_cap(chips)"
			("LOCATION" "C1035")
		)
		("@s9s_mb_2u_lib.s9s_mb_2u(sch_1):page364_i60@pure_quanta.q_cap(chips)"
			("LOCATION" "C1036")
		)
		("@s9s_mb_2u_lib.s9s_mb_2u(sch_1):page364_i61@pure_quanta.q_cap(chips)"
			("LOCATION" "C1037")
		)
		("@s9s_mb_2u_lib.s9s_mb_2u(sch_1):page364_i26@pure_quanta.q_cap(chips)"
			("LOCATION" "C1038")
		)
		("@s9s_mb_2u_lib.s9s_mb_2u(sch_1):page364_i32@pure_quanta.q_cap(chips)"
			("LOCATION" "C1039")
		)
		("@s9s_mb_2u_lib.s9s_mb_2u(sch_1):page364_i58@pure_quanta.q_cap(chips)"
			("LOCATION" "C1040")
		)
		("@s9s_mb_2u_lib.s9s_mb_2u(sch_1):page364_i59@pure_quanta.q_cap(chips)"
			("LOCATION" "C1041")
		)
		("@s9s_mb_2u_lib.s9s_mb_2u(sch_1):page364_i30@pure_quanta.q_cap(chips)"
			("LOCATION" "C1043")
		)
		("@s9s_mb_2u_lib.s9s_mb_2u(sch_1):page364_i54@pure_quanta.q_cap(chips)"
			("LOCATION" "C1044")
		)
		("@s9s_mb_2u_lib.s9s_mb_2u(sch_1):page364_i56@pure_quanta.q_cap(chips)"
			("LOCATION" "C1045")
		)
		("@s9s_mb_2u_lib.s9s_mb_2u(sch_1):page478_i19@pure_quanta.q_cap(chips)"
			("LOCATION" "C102")
		)
		("@s9s_mb_2u_lib.s9s_mb_2u(sch_1):page478_i89@pure_quanta.q_cap(chips)"
			("LOCATION" "C1212")
		)
		("@s9s_mb_2u_lib.s9s_mb_2u(sch_1):page478_i31@pure_quanta.q_res(chips)"
			("LOCATION" "R88")
		)
		("@s9s_mb_2u_lib.s9s_mb_2u(sch_1):page478_i77@pure_quanta.q_res(chips)"
			("LOCATION" "R89")
		)
		("@s9s_mb_2u_lib.s9s_mb_2u(sch_1):page478_i37@pure_quanta.q_res(chips)"
			("LOCATION" "R336")
		)
		("@s9s_mb_2u_lib.s9s_mb_2u(sch_1):page478_i33@pure_quanta.q_res(chips)"
			("LOCATION" "R337")
		)
		("@s9s_mb_2u_lib.s9s_mb_2u(sch_1):page478_i49@pure_quanta.q_res(chips)"
			("LOCATION" "R338")
		)
		("@s9s_mb_2u_lib.s9s_mb_2u(sch_1):page478_i52@pure_quanta.q_res(chips)"
			("LOCATION" "R339")
		)
		("@s9s_mb_2u_lib.s9s_mb_2u(sch_1):page478_i43@pure_quanta.q_res(chips)"
			("LOCATION" "R340")
		)
		("@s9s_mb_2u_lib.s9s_mb_2u(sch_1):page478_i44@pure_quanta.q_res(chips)"
			("LOCATION" "R341")
		)
		("@s9s_mb_2u_lib.s9s_mb_2u(sch_1):page478_i54@pure_quanta.q_res(chips)"
			("LOCATION" "R342")
		)
		("@s9s_mb_2u_lib.s9s_mb_2u(sch_1):page478_i53@pure_quanta.q_res(chips)"
			("LOCATION" "R343")
		)
		("@s9s_mb_2u_lib.s9s_mb_2u(sch_1):page478_i45@pure_quanta.q_res(chips)"
			("LOCATION" "R344")
		)
		("@s9s_mb_2u_lib.s9s_mb_2u(sch_1):page478_i46@pure_quanta.q_res(chips)"
			("LOCATION" "R345")
		)
		("@s9s_mb_2u_lib.s9s_mb_2u(sch_1):page478_i59@pure_quanta.q_res(chips)"
			("LOCATION" "R346")
		)
		("@s9s_mb_2u_lib.s9s_mb_2u(sch_1):page478_i60@pure_quanta.q_res(chips)"
			("LOCATION" "R347")
		)
		("@s9s_mb_2u_lib.s9s_mb_2u(sch_1):page478_i38@pure_quanta.q_res(chips)"
			("LOCATION" "R348")
		)
		("@s9s_mb_2u_lib.s9s_mb_2u(sch_1):page478_i39@pure_quanta.q_res(chips)"
			("LOCATION" "R349")
		)
		("@s9s_mb_2u_lib.s9s_mb_2u(sch_1):page478_i40@pure_quanta.q_res(chips)"
			("LOCATION" "R350")
		)
		("@s9s_mb_2u_lib.s9s_mb_2u(sch_1):page478_i63@pure_quanta.q_res(chips)"
			("LOCATION" "R351")
		)
		("@s9s_mb_2u_lib.s9s_mb_2u(sch_1):page478_i62@pure_quanta.q_res(chips)"
			("LOCATION" "R352")
		)
		("@s9s_mb_2u_lib.s9s_mb_2u(sch_1):page478_i61@pure_quanta.q_res(chips)"
			("LOCATION" "R353")
		)
		("@s9s_mb_2u_lib.s9s_mb_2u(sch_1):page478_i71@pure_quanta.q_res(chips)"
			("LOCATION" "R354")
		)
		("@s9s_mb_2u_lib.s9s_mb_2u(sch_1):page478_i73@pure_quanta.q_res(chips)"
			("LOCATION" "R355")
		)
		("@s9s_mb_2u_lib.s9s_mb_2u(sch_1):page478_i79@pure_quanta.q_res(chips)"
			("LOCATION" "R356")
		)
		("@s9s_mb_2u_lib.s9s_mb_2u(sch_1):page478_i68@pure_quanta.q_res(chips)"
			("LOCATION" "R357")
		)
		("@s9s_mb_2u_lib.s9s_mb_2u(sch_1):page478_i80@pure_quanta.q_res(chips)"
			("LOCATION" "R358")
		)
		("@s9s_mb_2u_lib.s9s_mb_2u(sch_1):page478_i67@pure_quanta.q_res(chips)"
			("LOCATION" "R359")
		)
		("@s9s_mb_2u_lib.s9s_mb_2u(sch_1):page478_i75@pure_quanta.q_res(chips)"
			("LOCATION" "R360")
		)
		("@s9s_mb_2u_lib.s9s_mb_2u(sch_1):page478_i84@pure_quanta.q_res(chips)"
			("LOCATION" "R361")
		)
		("@s9s_mb_2u_lib.s9s_mb_2u(sch_1):page478_i81@pure_quanta.q_res(chips)"
			("LOCATION" "R362")
		)
		("@s9s_mb_2u_lib.s9s_mb_2u(sch_1):page478_i85@pure_quanta.q_res(chips)"
			("LOCATION" "R363")
		)
		("@s9s_mb_2u_lib.s9s_mb_2u(sch_1):page478_i88@pure_quanta.q_res(chips)"
			("LOCATION" "R364")
		)
		("@s9s_mb_2u_lib.s9s_mb_2u(sch_1):page478_i30@pure_quanta.gtl2014pw(chips)"
			("LOCATION" "U11")
		)
		("@s9s_mb_2u_lib.s9s_mb_2u(sch_1):page515_i77@pure_quanta.q_cap(chips)"
			("LOCATION" "C103")
		)
		("@s9s_mb_2u_lib.s9s_mb_2u(sch_1):page515_i76@pure_quanta.q_cap(chips)"
			("LOCATION" "C104")
		)
		("@s9s_mb_2u_lib.s9s_mb_2u(sch_1):page515_i89@pure_quanta.q_cap(chips)"
			("LOCATION" "C609")
		)
		("@s9s_mb_2u_lib.s9s_mb_2u(sch_1):page515_i10@pure_quanta.q_cap(chips)"
			("LOCATION" "C1507")
		)
		("@s9s_mb_2u_lib.s9s_mb_2u(sch_1):page515_i17@pure_quanta.q_cap(chips)"
			("LOCATION" "C1508")
		)
		("@s9s_mb_2u_lib.s9s_mb_2u(sch_1):page515_i74@pure_quanta.q_res(chips)"
			("LOCATION" "R120")
		)
		("@s9s_mb_2u_lib.s9s_mb_2u(sch_1):page515_i69@pure_quanta.q_res(chips)"
			("LOCATION" "R477")
		)
		("@s9s_mb_2u_lib.s9s_mb_2u(sch_1):page515_i92@pure_quanta.q_res(chips)"
			("LOCATION" "R1316")
		)
		("@s9s_mb_2u_lib.s9s_mb_2u(sch_1):page515_i103@pure_quanta.q_res(chips)"
			("LOCATION" "R1720")
		)
		("@s9s_mb_2u_lib.s9s_mb_2u(sch_1):page515_i104@pure_quanta.q_res(chips)"
			("LOCATION" "R1721")
		)
		("@s9s_mb_2u_lib.s9s_mb_2u(sch_1):page515_i78@pure_quanta.emmitsburg_rev0p9(chips)"
			("LOCATION" "U4")
		)
		("@s9s_mb_2u_lib.s9s_mb_2u(sch_1):page515_i11@pure_quanta.q_crystal(chips)"
			("LOCATION" "Y1")
		)
		("@s9s_mb_2u_lib.s9s_mb_2u(sch_1):page515_i75@pure_quanta.q_xtal_4p_13bi_24gnd(chips)"
			("LOCATION" "Y3")
		)
		("@s9s_mb_2u_lib.s9s_mb_2u(sch_1):page485_i58@pure_quanta.q_cap(chips)"
			("LOCATION" "C105")
		)
		("@s9s_mb_2u_lib.s9s_mb_2u(sch_1):page485_i9@pure_quanta.q_res(chips)"
			("LOCATION" "R187")
		)
		("@s9s_mb_2u_lib.s9s_mb_2u(sch_1):page485_i8@pure_quanta.q_res(chips)"
			("LOCATION" "R188")
		)
		("@s9s_mb_2u_lib.s9s_mb_2u(sch_1):page485_i50@pure_quanta.q_res(chips)"
			("LOCATION" "R189")
		)
		("@s9s_mb_2u_lib.s9s_mb_2u(sch_1):page485_i60@pure_quanta.q_res(chips)"
			("LOCATION" "R190")
		)
		("@s9s_mb_2u_lib.s9s_mb_2u(sch_1):page485_i61@pure_quanta.q_res(chips)"
			("LOCATION" "R191")
		)
		("@s9s_mb_2u_lib.s9s_mb_2u(sch_1):page485_i64@pure_quanta.q_res(chips)"
			("LOCATION" "R192")
		)
		("@s9s_mb_2u_lib.s9s_mb_2u(sch_1):page485_i44@pure_quanta.q_res(chips)"
			("LOCATION" "R193")
		)
		("@s9s_mb_2u_lib.s9s_mb_2u(sch_1):page485_i66@pure_quanta.q_res(chips)"
			("LOCATION" "R194")
		)
		("@s9s_mb_2u_lib.s9s_mb_2u(sch_1):page485_i49@pure_quanta.q_res(chips)"
			("LOCATION" "R195")
		)
		("@s9s_mb_2u_lib.s9s_mb_2u(sch_1):page485_i57@pure_quanta.q_res(chips)"
			("LOCATION" "R196")
		)
		("@s9s_mb_2u_lib.s9s_mb_2u(sch_1):page485_i53@pure_quanta.q_res(chips)"
			("LOCATION" "R197")
		)
		("@s9s_mb_2u_lib.s9s_mb_2u(sch_1):page485_i54@pure_quanta.q_res(chips)"
			("LOCATION" "R198")
		)
		("@s9s_mb_2u_lib.s9s_mb_2u(sch_1):page485_i43@pure_quanta.\\74lvc1g07gv\\(chips)"
			("LOCATION" "U7")
		)
		("@s9s_mb_2u_lib.s9s_mb_2u(sch_1):page536_i19@pure_quanta.q_cap(chips)"
			("LOCATION" "C108")
		)
		("@s9s_mb_2u_lib.s9s_mb_2u(sch_1):page536_i18@pure_quanta.q_cap(chips)"
			("LOCATION" "C109")
		)
		("@s9s_mb_2u_lib.s9s_mb_2u(sch_1):page536_i17@pure_quanta.q_cap(chips)"
			("LOCATION" "C110")
		)
		("@s9s_mb_2u_lib.s9s_mb_2u(sch_1):page536_i46@pure_quanta.q_cap(chips)"
			("LOCATION" "C111")
		)
		("@s9s_mb_2u_lib.s9s_mb_2u(sch_1):page536_i45@pure_quanta.q_cap(chips)"
			("LOCATION" "C112")
		)
		("@s9s_mb_2u_lib.s9s_mb_2u(sch_1):page536_i47@pure_quanta.q_cap(chips)"
			("LOCATION" "C114")
		)
		("@s9s_mb_2u_lib.s9s_mb_2u(sch_1):page536_i66@pure_quanta.q_cap(chips)"
			("LOCATION" "C115")
		)
		("@s9s_mb_2u_lib.s9s_mb_2u(sch_1):page536_i65@pure_quanta.q_cap(chips)"
			("LOCATION" "C116")
		)
		("@s9s_mb_2u_lib.s9s_mb_2u(sch_1):page536_i64@pure_quanta.q_cap(chips)"
			("LOCATION" "C117")
		)
		("@s9s_mb_2u_lib.s9s_mb_2u(sch_1):page536_i67@pure_quanta.q_cap(chips)"
			("LOCATION" "C119")
		)
		("@s9s_mb_2u_lib.s9s_mb_2u(sch_1):page536_i68@pure_quanta.q_cap(chips)"
			("LOCATION" "C120")
		)
		("@s9s_mb_2u_lib.s9s_mb_2u(sch_1):page536_i2@pure_quanta.q_cap(chips)"
			("LOCATION" "C171")
		)
		("@s9s_mb_2u_lib.s9s_mb_2u(sch_1):page536_i6@pure_quanta.q_cap(chips)"
			("LOCATION" "C172")
		)
		("@s9s_mb_2u_lib.s9s_mb_2u(sch_1):page536_i4@pure_quanta.q_cap(chips)"
			("LOCATION" "C173")
		)
		("@s9s_mb_2u_lib.s9s_mb_2u(sch_1):page536_i44@pure_quanta.q_cap(chips)"
			("LOCATION" "C1309")
		)
		("@s9s_mb_2u_lib.s9s_mb_2u(sch_1):page536_i59@pure_quanta.q_cap(chips)"
			("LOCATION" "C1310")
		)
		("@s9s_mb_2u_lib.s9s_mb_2u(sch_1):page536_i43@pure_quanta.q_cap(chips)"
			("LOCATION" "C1311")
		)
		("@s9s_mb_2u_lib.s9s_mb_2u(sch_1):page536_i58@pure_quanta.q_cap(chips)"
			("LOCATION" "C1312")
		)
		("@s9s_mb_2u_lib.s9s_mb_2u(sch_1):page536_i48@pure_quanta.q_cap(chips)"
			("LOCATION" "C1313")
		)
		("@s9s_mb_2u_lib.s9s_mb_2u(sch_1):page536_i53@pure_quanta.q_cap(chips)"
			("LOCATION" "C1314")
		)
		("@s9s_mb_2u_lib.s9s_mb_2u(sch_1):page536_i20@pure_quanta.q_inductor(chips)"
			("LOCATION" "L1")
		)
		("@s9s_mb_2u_lib.s9s_mb_2u(sch_1):page536_i41@pure_quanta.q_inductor(chips)"
			("LOCATION" "L13")
		)
		("@s9s_mb_2u_lib.s9s_mb_2u(sch_1):page536_i60@pure_quanta.q_inductor(chips)"
			("LOCATION" "L14")
		)
		("@s9s_mb_2u_lib.s9s_mb_2u(sch_1):page536_i36@pure_quanta.q_res(chips)"
			("LOCATION" "R442")
		)
		("@s9s_mb_2u_lib.s9s_mb_2u(sch_1):page536_i55@pure_quanta.q_res(chips)"
			("LOCATION" "R447")
		)
		("@s9s_mb_2u_lib.s9s_mb_2u(sch_1):page536_i7@pure_quanta.q_res(chips)"
			("LOCATION" "R519")
		)
		("@s9s_mb_2u_lib.s9s_mb_2u(sch_1):page534_i186@pure_quanta.q_cap(chips)"
			("LOCATION" "C113")
		)
		("@s9s_mb_2u_lib.s9s_mb_2u(sch_1):page534_i183@pure_quanta.q_cap(chips)"
			("LOCATION" "C118")
		)
		("@s9s_mb_2u_lib.s9s_mb_2u(sch_1):page534_i286@pure_quanta.q_cap(chips)"
			("LOCATION" "C1324")
		)
		("@s9s_mb_2u_lib.s9s_mb_2u(sch_1):page534_i280@pure_quanta.q_res(chips)"
			("LOCATION" "R562")
		)
		("@s9s_mb_2u_lib.s9s_mb_2u(sch_1):page534_i283@pure_quanta.q_res(chips)"
			("LOCATION" "R734")
		)
		("@s9s_mb_2u_lib.s9s_mb_2u(sch_1):page534_i278@pure_quanta.q_res(chips)"
			("LOCATION" "R912")
		)
		("@s9s_mb_2u_lib.s9s_mb_2u(sch_1):page534_i282@pure_quanta.q_res(chips)"
			("LOCATION" "R953")
		)
		("@s9s_mb_2u_lib.s9s_mb_2u(sch_1):page534_i277@pure_quanta.q_res(chips)"
			("LOCATION" "R1194")
		)
		("@s9s_mb_2u_lib.s9s_mb_2u(sch_1):page534_i281@pure_quanta.q_res(chips)"
			("LOCATION" "R1196")
		)
		("@s9s_mb_2u_lib.s9s_mb_2u(sch_1):page534_i273@pure_quanta.q_res(chips)"
			("LOCATION" "R1204")
		)
		("@s9s_mb_2u_lib.s9s_mb_2u(sch_1):page534_i276@pure_quanta.q_res(chips)"
			("LOCATION" "R1267")
		)
		("@s9s_mb_2u_lib.s9s_mb_2u(sch_1):page534_i272@pure_quanta.q_res(chips)"
			("LOCATION" "R1305")
		)
		("@s9s_mb_2u_lib.s9s_mb_2u(sch_1):page534_i275@pure_quanta.q_res(chips)"
			("LOCATION" "R1390")
		)
		("@s9s_mb_2u_lib.s9s_mb_2u(sch_1):page534_i274@pure_quanta.q_res(chips)"
			("LOCATION" "R1462")
		)
		("@s9s_mb_2u_lib.s9s_mb_2u(sch_1):page534_i267@pure_quanta.q_res(chips)"
			("LOCATION" "R1471")
		)
		("@s9s_mb_2u_lib.s9s_mb_2u(sch_1):page534_i265@pure_quanta.q_res(chips)"
			("LOCATION" "R1483")
		)
		("@s9s_mb_2u_lib.s9s_mb_2u(sch_1):page534_i268@pure_quanta.q_res(chips)"
			("LOCATION" "R1484")
		)
		("@s9s_mb_2u_lib.s9s_mb_2u(sch_1):page534_i271@pure_quanta.q_res(chips)"
			("LOCATION" "R1500")
		)
		("@s9s_mb_2u_lib.s9s_mb_2u(sch_1):page534_i270@pure_quanta.q_res(chips)"
			("LOCATION" "R1502")
		)
		("@s9s_mb_2u_lib.s9s_mb_2u(sch_1):page534_i269@pure_quanta.q_res(chips)"
			("LOCATION" "R1527")
		)
		("@s9s_mb_2u_lib.s9s_mb_2u(sch_1):page534_i252@pure_quanta.q_res(chips)"
			("LOCATION" "R1680")
		)
		("@s9s_mb_2u_lib.s9s_mb_2u(sch_1):page534_i287@pure_quanta.q_res(chips)"
			("LOCATION" "R1724")
		)
		("@s9s_mb_2u_lib.s9s_mb_2u(sch_1):page534_i180@pure_quanta.\\9sq440nqqi8\\(chips)"
			("LOCATION" "U13")
		)
		("@s9s_mb_2u_lib.s9s_mb_2u(sch_1):page534_i288@pure_quanta.\\9sq440nqqi8\\(chips)"
			("LOCATION" "U13")
		)
		("@s9s_mb_2u_lib.s9s_mb_2u(sch_1):page534_i185@pure_quanta.q_xtal_4p_13(chips)"
			("LOCATION" "Y2")
		)
		("@s9s_mb_2u_lib.s9s_mb_2u(sch_1):page493_i32@pure_quanta.q_capp(chips)"
			("LOCATION" "C121")
		)
		("@s9s_mb_2u_lib.s9s_mb_2u(sch_1):page493_i99@pure_quanta.q_cap(chips)"
			("LOCATION" "C122")
		)
		("@s9s_mb_2u_lib.s9s_mb_2u(sch_1):page493_i98@pure_quanta.q_capp(chips)"
			("LOCATION" "C123")
		)
		("@s9s_mb_2u_lib.s9s_mb_2u(sch_1):page493_i93@pure_quanta.q_cap(chips)"
			("LOCATION" "C124")
		)
		("@s9s_mb_2u_lib.s9s_mb_2u(sch_1):page493_i94@pure_quanta.q_cap(chips)"
			("LOCATION" "C125")
		)
		("@s9s_mb_2u_lib.s9s_mb_2u(sch_1):page493_i97@pure_quanta.q_cap(chips)"
			("LOCATION" "C126")
		)
		("@s9s_mb_2u_lib.s9s_mb_2u(sch_1):page493_i101@pure_quanta.sconn140_me1014010101011(chips)"
			("LOCATION" "J55")
		)
		("@s9s_mb_2u_lib.s9s_mb_2u(sch_1):page493_i294@pure_quanta.q_res(chips)"
			("LOCATION" "R84")
		)
		("@s9s_mb_2u_lib.s9s_mb_2u(sch_1):page493_i190@pure_quanta.q_res(chips)"
			("LOCATION" "R384")
		)
		("@s9s_mb_2u_lib.s9s_mb_2u(sch_1):page493_i314@pure_quanta.q_res(chips)"
			("LOCATION" "R386")
		)
		("@s9s_mb_2u_lib.s9s_mb_2u(sch_1):page493_i322@pure_quanta.q_res(chips)"
			("LOCATION" "R387")
		)
		("@s9s_mb_2u_lib.s9s_mb_2u(sch_1):page493_i321@pure_quanta.q_res(chips)"
			("LOCATION" "R390")
		)
		("@s9s_mb_2u_lib.s9s_mb_2u(sch_1):page493_i296@pure_quanta.q_res(chips)"
			("LOCATION" "R636")
		)
		("@s9s_mb_2u_lib.s9s_mb_2u(sch_1):page493_i298@pure_quanta.q_res(chips)"
			("LOCATION" "R637")
		)
		("@s9s_mb_2u_lib.s9s_mb_2u(sch_1):page493_i301@pure_quanta.q_res(chips)"
			("LOCATION" "R638")
		)
		("@s9s_mb_2u_lib.s9s_mb_2u(sch_1):page493_i303@pure_quanta.q_res(chips)"
			("LOCATION" "R639")
		)
		("@s9s_mb_2u_lib.s9s_mb_2u(sch_1):page493_i280@pure_quanta.q_res(chips)"
			("LOCATION" "R1480")
		)
		("@s9s_mb_2u_lib.s9s_mb_2u(sch_1):page493_i316@pure_quanta.q_res(chips)"
			("LOCATION" "R1570")
		)
		("@s9s_mb_2u_lib.s9s_mb_2u(sch_1):page493_i312@pure_quanta.q_res(chips)"
			("LOCATION" "R1571")
		)
		("@s9s_mb_2u_lib.s9s_mb_2u(sch_1):page493_i310@pure_quanta.q_res(chips)"
			("LOCATION" "R1572")
		)
		("@s9s_mb_2u_lib.s9s_mb_2u(sch_1):page494_i50@pure_quanta.q_capp(chips)"
			("LOCATION" "C127")
		)
		("@s9s_mb_2u_lib.s9s_mb_2u(sch_1):page494_i52@pure_quanta.q_cap(chips)"
			("LOCATION" "C128")
		)
		("@s9s_mb_2u_lib.s9s_mb_2u(sch_1):page494_i54@pure_quanta.q_capp(chips)"
			("LOCATION" "C129")
		)
		("@s9s_mb_2u_lib.s9s_mb_2u(sch_1):page494_i56@pure_quanta.q_cap(chips)"
			("LOCATION" "C130")
		)
		("@s9s_mb_2u_lib.s9s_mb_2u(sch_1):page494_i103@pure_quanta.q_cap(chips)"
			("LOCATION" "C131")
		)
		("@s9s_mb_2u_lib.s9s_mb_2u(sch_1):page494_i106@pure_quanta.q_cap(chips)"
			("LOCATION" "C132")
		)
		("@s9s_mb_2u_lib.s9s_mb_2u(sch_1):page494_i27@pure_quanta.sconn140_me1014010101011(chips)"
			("LOCATION" "J56")
		)
		("@s9s_mb_2u_lib.s9s_mb_2u(sch_1):page494_i173@pure_quanta.q_res(chips)"
			("LOCATION" "R85")
		)
		("@s9s_mb_2u_lib.s9s_mb_2u(sch_1):page494_i108@pure_quanta.q_res(chips)"
			("LOCATION" "R388")
		)
		("@s9s_mb_2u_lib.s9s_mb_2u(sch_1):page494_i231@pure_quanta.q_res(chips)"
			("LOCATION" "R389")
		)
		("@s9s_mb_2u_lib.s9s_mb_2u(sch_1):page494_i164@pure_quanta.q_res(chips)"
			("LOCATION" "R640")
		)
		("@s9s_mb_2u_lib.s9s_mb_2u(sch_1):page494_i172@pure_quanta.q_res(chips)"
			("LOCATION" "R1481")
		)
		("@s9s_mb_2u_lib.s9s_mb_2u(sch_1):page494_i163@pure_quanta.q_res(chips)"
			("LOCATION" "R1528")
		)
		("@s9s_mb_2u_lib.s9s_mb_2u(sch_1):page494_i162@pure_quanta.q_res(chips)"
			("LOCATION" "R1529")
		)
		("@s9s_mb_2u_lib.s9s_mb_2u(sch_1):page494_i161@pure_quanta.q_res(chips)"
			("LOCATION" "R1530")
		)
		("@s9s_mb_2u_lib.s9s_mb_2u(sch_1):page494_i160@pure_quanta.q_res(chips)"
			("LOCATION" "R1531")
		)
		("@s9s_mb_2u_lib.s9s_mb_2u(sch_1):page494_i237@pure_quanta.q_res(chips)"
			("LOCATION" "R1573")
		)
		("@s9s_mb_2u_lib.s9s_mb_2u(sch_1):page494_i234@pure_quanta.q_res(chips)"
			("LOCATION" "R1574")
		)
		("@s9s_mb_2u_lib.s9s_mb_2u(sch_1):page494_i226@pure_quanta.q_res(chips)"
			("LOCATION" "R1575")
		)
		("@s9s_mb_2u_lib.s9s_mb_2u(sch_1):page494_i228@pure_quanta.q_res(chips)"
			("LOCATION" "R1576")
		)
		("@s9s_mb_2u_lib.s9s_mb_2u(sch_1):page495_i18@pure_quanta.q_capp(chips)"
			("LOCATION" "C133")
		)
		("@s9s_mb_2u_lib.s9s_mb_2u(sch_1):page495_i20@pure_quanta.q_cap(chips)"
			("LOCATION" "C134")
		)
		("@s9s_mb_2u_lib.s9s_mb_2u(sch_1):page495_i21@pure_quanta.q_capp(chips)"
			("LOCATION" "C135")
		)
		("@s9s_mb_2u_lib.s9s_mb_2u(sch_1):page495_i23@pure_quanta.q_cap(chips)"
			("LOCATION" "C136")
		)
		("@s9s_mb_2u_lib.s9s_mb_2u(sch_1):page495_i24@pure_quanta.q_cap(chips)"
			("LOCATION" "C137")
		)
		("@s9s_mb_2u_lib.s9s_mb_2u(sch_1):page495_i26@pure_quanta.q_cap(chips)"
			("LOCATION" "C138")
		)
		("@s9s_mb_2u_lib.s9s_mb_2u(sch_1):page495_i36@pure_quanta.sconn140_me1014010101011(chips)"
			("LOCATION" "J57")
		)
		("@s9s_mb_2u_lib.s9s_mb_2u(sch_1):page495_i240@pure_quanta.q_res(chips)"
			("LOCATION" "R86")
		)
		("@s9s_mb_2u_lib.s9s_mb_2u(sch_1):page495_i108@pure_quanta.q_res(chips)"
			("LOCATION" "R391")
		)
		("@s9s_mb_2u_lib.s9s_mb_2u(sch_1):page495_i231@pure_quanta.q_res(chips)"
			("LOCATION" "R392")
		)
		("@s9s_mb_2u_lib.s9s_mb_2u(sch_1):page495_i172@pure_quanta.q_res(chips)"
			("LOCATION" "R1482")
		)
		("@s9s_mb_2u_lib.s9s_mb_2u(sch_1):page495_i170@pure_quanta.q_res(chips)"
			("LOCATION" "R1532")
		)
		("@s9s_mb_2u_lib.s9s_mb_2u(sch_1):page495_i168@pure_quanta.q_res(chips)"
			("LOCATION" "R1533")
		)
		("@s9s_mb_2u_lib.s9s_mb_2u(sch_1):page495_i167@pure_quanta.q_res(chips)"
			("LOCATION" "R1534")
		)
		("@s9s_mb_2u_lib.s9s_mb_2u(sch_1):page495_i166@pure_quanta.q_res(chips)"
			("LOCATION" "R1535")
		)
		("@s9s_mb_2u_lib.s9s_mb_2u(sch_1):page495_i165@pure_quanta.q_res(chips)"
			("LOCATION" "R1536")
		)
		("@s9s_mb_2u_lib.s9s_mb_2u(sch_1):page495_i239@pure_quanta.q_res(chips)"
			("LOCATION" "R1577")
		)
		("@s9s_mb_2u_lib.s9s_mb_2u(sch_1):page495_i234@pure_quanta.q_res(chips)"
			("LOCATION" "R1578")
		)
		("@s9s_mb_2u_lib.s9s_mb_2u(sch_1):page495_i226@pure_quanta.q_res(chips)"
			("LOCATION" "R1579")
		)
		("@s9s_mb_2u_lib.s9s_mb_2u(sch_1):page495_i228@pure_quanta.q_res(chips)"
			("LOCATION" "R1580")
		)
		("@s9s_mb_2u_lib.s9s_mb_2u(sch_1):page513_i35@pure_quanta.q_cap_diffbus(chips)"
			("LOCATION" "C139")
		)
		("@s9s_mb_2u_lib.s9s_mb_2u(sch_1):page513_i36@pure_quanta.q_cap_diffbus(chips)"
			("LOCATION" "C140")
		)
		("@s9s_mb_2u_lib.s9s_mb_2u(sch_1):page513_i34@pure_quanta.q_cap_diffbus(chips)"
			("LOCATION" "C141")
		)
		("@s9s_mb_2u_lib.s9s_mb_2u(sch_1):page513_i33@pure_quanta.q_cap_diffbus(chips)"
			("LOCATION" "C142")
		)
		("@s9s_mb_2u_lib.s9s_mb_2u(sch_1):page513_i32@pure_quanta.q_cap_diffbus(chips)"
			("LOCATION" "C143")
		)
		("@s9s_mb_2u_lib.s9s_mb_2u(sch_1):page513_i31@pure_quanta.q_cap_diffbus(chips)"
			("LOCATION" "C144")
		)
		("@s9s_mb_2u_lib.s9s_mb_2u(sch_1):page513_i30@pure_quanta.q_cap_diffbus(chips)"
			("LOCATION" "C145")
		)
		("@s9s_mb_2u_lib.s9s_mb_2u(sch_1):page513_i29@pure_quanta.q_cap_diffbus(chips)"
			("LOCATION" "C146")
		)
		("@s9s_mb_2u_lib.s9s_mb_2u(sch_1):page513_i28@pure_quanta.q_cap_diffbus(chips)"
			("LOCATION" "C147")
		)
		("@s9s_mb_2u_lib.s9s_mb_2u(sch_1):page513_i27@pure_quanta.q_cap_diffbus(chips)"
			("LOCATION" "C148")
		)
		("@s9s_mb_2u_lib.s9s_mb_2u(sch_1):page513_i25@pure_quanta.q_cap_diffbus(chips)"
			("LOCATION" "C149")
		)
		("@s9s_mb_2u_lib.s9s_mb_2u(sch_1):page513_i26@pure_quanta.q_cap_diffbus(chips)"
			("LOCATION" "C150")
		)
		("@s9s_mb_2u_lib.s9s_mb_2u(sch_1):page513_i24@pure_quanta.q_cap_diffbus(chips)"
			("LOCATION" "C151")
		)
		("@s9s_mb_2u_lib.s9s_mb_2u(sch_1):page513_i23@pure_quanta.q_cap_diffbus(chips)"
			("LOCATION" "C152")
		)
		("@s9s_mb_2u_lib.s9s_mb_2u(sch_1):page513_i21@pure_quanta.q_cap_diffbus(chips)"
			("LOCATION" "C153")
		)
		("@s9s_mb_2u_lib.s9s_mb_2u(sch_1):page513_i22@pure_quanta.q_cap_diffbus(chips)"
			("LOCATION" "C154")
		)
		("@s9s_mb_2u_lib.s9s_mb_2u(sch_1):page513_i113@pure_quanta.q_cap_diffbus(chips)"
			("LOCATION" "C155")
		)
		("@s9s_mb_2u_lib.s9s_mb_2u(sch_1):page513_i114@pure_quanta.q_cap_diffbus(chips)"
			("LOCATION" "C156")
		)
		("@s9s_mb_2u_lib.s9s_mb_2u(sch_1):page513_i115@pure_quanta.q_cap_diffbus(chips)"
			("LOCATION" "C157")
		)
		("@s9s_mb_2u_lib.s9s_mb_2u(sch_1):page513_i116@pure_quanta.q_cap_diffbus(chips)"
			("LOCATION" "C158")
		)
		("@s9s_mb_2u_lib.s9s_mb_2u(sch_1):page513_i117@pure_quanta.q_cap_diffbus(chips)"
			("LOCATION" "C159")
		)
		("@s9s_mb_2u_lib.s9s_mb_2u(sch_1):page513_i118@pure_quanta.q_cap_diffbus(chips)"
			("LOCATION" "C160")
		)
		("@s9s_mb_2u_lib.s9s_mb_2u(sch_1):page513_i119@pure_quanta.q_cap_diffbus(chips)"
			("LOCATION" "C161")
		)
		("@s9s_mb_2u_lib.s9s_mb_2u(sch_1):page513_i120@pure_quanta.q_cap_diffbus(chips)"
			("LOCATION" "C162")
		)
		("@s9s_mb_2u_lib.s9s_mb_2u(sch_1):page513_i121@pure_quanta.q_cap_diffbus(chips)"
			("LOCATION" "C163")
		)
		("@s9s_mb_2u_lib.s9s_mb_2u(sch_1):page513_i122@pure_quanta.q_cap_diffbus(chips)"
			("LOCATION" "C164")
		)
		("@s9s_mb_2u_lib.s9s_mb_2u(sch_1):page513_i123@pure_quanta.q_cap_diffbus(chips)"
			("LOCATION" "C165")
		)
		("@s9s_mb_2u_lib.s9s_mb_2u(sch_1):page513_i124@pure_quanta.q_cap_diffbus(chips)"
			("LOCATION" "C166")
		)
		("@s9s_mb_2u_lib.s9s_mb_2u(sch_1):page513_i126@pure_quanta.q_cap_diffbus(chips)"
			("LOCATION" "C167")
		)
		("@s9s_mb_2u_lib.s9s_mb_2u(sch_1):page513_i125@pure_quanta.q_cap_diffbus(chips)"
			("LOCATION" "C168")
		)
		("@s9s_mb_2u_lib.s9s_mb_2u(sch_1):page513_i127@pure_quanta.q_cap_diffbus(chips)"
			("LOCATION" "C169")
		)
		("@s9s_mb_2u_lib.s9s_mb_2u(sch_1):page513_i128@pure_quanta.q_cap_diffbus(chips)"
			("LOCATION" "C170")
		)
		("@s9s_mb_2u_lib.s9s_mb_2u(sch_1):page621_i25@pure_quanta.q_cap(chips)"
			("LOCATION" "C174")
		)
		("@s9s_mb_2u_lib.s9s_mb_2u(sch_1):page621_i7@pure_quanta.q_res(chips)"
			("LOCATION" "R536")
		)
		("@s9s_mb_2u_lib.s9s_mb_2u(sch_1):page621_i2@pure_quanta.q_res(chips)"
			("LOCATION" "R537")
		)
		("@s9s_mb_2u_lib.s9s_mb_2u(sch_1):page621_i9@pure_quanta.q_res(chips)"
			("LOCATION" "R538")
		)
		("@s9s_mb_2u_lib.s9s_mb_2u(sch_1):page621_i4@pure_quanta.q_res(chips)"
			("LOCATION" "R539")
		)
		("@s9s_mb_2u_lib.s9s_mb_2u(sch_1):page621_i10@pure_quanta.q_res(chips)"
			("LOCATION" "R540")
		)
		("@s9s_mb_2u_lib.s9s_mb_2u(sch_1):page621_i6@pure_quanta.q_res(chips)"
			("LOCATION" "R587")
		)
		("@s9s_mb_2u_lib.s9s_mb_2u(sch_1):page621_i19@pure_quanta.q_res(chips)"
			("LOCATION" "R588")
		)
		("@s9s_mb_2u_lib.s9s_mb_2u(sch_1):page621_i20@pure_quanta.q_res(chips)"
			("LOCATION" "R589")
		)
		("@s9s_mb_2u_lib.s9s_mb_2u(sch_1):page621_i65@pure_quanta.q_res(chips)"
			("LOCATION" "R590")
		)
		("@s9s_mb_2u_lib.s9s_mb_2u(sch_1):page621_i64@pure_quanta.q_res(chips)"
			("LOCATION" "R591")
		)
		("@s9s_mb_2u_lib.s9s_mb_2u(sch_1):page621_i49@pure_quanta.q_res(chips)"
			("LOCATION" "R592")
		)
		("@s9s_mb_2u_lib.s9s_mb_2u(sch_1):page621_i48@pure_quanta.q_res(chips)"
			("LOCATION" "R601")
		)
		("@s9s_mb_2u_lib.s9s_mb_2u(sch_1):page621_i47@pure_quanta.q_res(chips)"
			("LOCATION" "R602")
		)
		("@s9s_mb_2u_lib.s9s_mb_2u(sch_1):page621_i46@pure_quanta.q_res(chips)"
			("LOCATION" "R603")
		)
		("@s9s_mb_2u_lib.s9s_mb_2u(sch_1):page621_i44@pure_quanta.q_res(chips)"
			("LOCATION" "R604")
		)
		("@s9s_mb_2u_lib.s9s_mb_2u(sch_1):page621_i43@pure_quanta.q_res(chips)"
			("LOCATION" "R605")
		)
		("@s9s_mb_2u_lib.s9s_mb_2u(sch_1):page621_i41@pure_quanta.q_res(chips)"
			("LOCATION" "R606")
		)
		("@s9s_mb_2u_lib.s9s_mb_2u(sch_1):page621_i42@pure_quanta.q_res(chips)"
			("LOCATION" "R649")
		)
		("@s9s_mb_2u_lib.s9s_mb_2u(sch_1):page621_i63@pure_quanta.q_res(chips)"
			("LOCATION" "R1073")
		)
		("@s9s_mb_2u_lib.s9s_mb_2u(sch_1):page621_i62@pure_quanta.q_res(chips)"
			("LOCATION" "R1074")
		)
		("@s9s_mb_2u_lib.s9s_mb_2u(sch_1):page621_i92@pure_quanta.q_res(chips)"
			("LOCATION" "R1075")
		)
		("@s9s_mb_2u_lib.s9s_mb_2u(sch_1):page621_i61@pure_quanta.q_res(chips)"
			("LOCATION" "R1076")
		)
		("@s9s_mb_2u_lib.s9s_mb_2u(sch_1):page621_i59@pure_quanta.q_res(chips)"
			("LOCATION" "R1077")
		)
		("@s9s_mb_2u_lib.s9s_mb_2u(sch_1):page621_i58@pure_quanta.q_res(chips)"
			("LOCATION" "R1078")
		)
		("@s9s_mb_2u_lib.s9s_mb_2u(sch_1):page621_i57@pure_quanta.q_res(chips)"
			("LOCATION" "R1079")
		)
		("@s9s_mb_2u_lib.s9s_mb_2u(sch_1):page621_i56@pure_quanta.q_res(chips)"
			("LOCATION" "R1080")
		)
		("@s9s_mb_2u_lib.s9s_mb_2u(sch_1):page621_i55@pure_quanta.q_res(chips)"
			("LOCATION" "R1081")
		)
		("@s9s_mb_2u_lib.s9s_mb_2u(sch_1):page621_i54@pure_quanta.q_res(chips)"
			("LOCATION" "R1082")
		)
		("@s9s_mb_2u_lib.s9s_mb_2u(sch_1):page621_i53@pure_quanta.q_res(chips)"
			("LOCATION" "R1083")
		)
		("@s9s_mb_2u_lib.s9s_mb_2u(sch_1):page621_i52@pure_quanta.q_res(chips)"
			("LOCATION" "R1084")
		)
		("@s9s_mb_2u_lib.s9s_mb_2u(sch_1):page621_i51@pure_quanta.q_res(chips)"
			("LOCATION" "R1085")
		)
		("@s9s_mb_2u_lib.s9s_mb_2u(sch_1):page621_i50@pure_quanta.q_res(chips)"
			("LOCATION" "R1086")
		)
		("@s9s_mb_2u_lib.s9s_mb_2u(sch_1):page621_i39@pure_quanta.q_res(chips)"
			("LOCATION" "R1087")
		)
		("@s9s_mb_2u_lib.s9s_mb_2u(sch_1):page621_i40@pure_quanta.q_res(chips)"
			("LOCATION" "R1088")
		)
		("@s9s_mb_2u_lib.s9s_mb_2u(sch_1):page621_i31@pure_quanta.q_res(chips)"
			("LOCATION" "R1089")
		)
		("@s9s_mb_2u_lib.s9s_mb_2u(sch_1):page621_i32@pure_quanta.q_res(chips)"
			("LOCATION" "R1090")
		)
		("@s9s_mb_2u_lib.s9s_mb_2u(sch_1):page621_i30@pure_quanta.q_res(chips)"
			("LOCATION" "R1091")
		)
		("@s9s_mb_2u_lib.s9s_mb_2u(sch_1):page621_i29@pure_quanta.q_res(chips)"
			("LOCATION" "R1092")
		)
		("@s9s_mb_2u_lib.s9s_mb_2u(sch_1):page621_i27@pure_quanta.q_res(chips)"
			("LOCATION" "R1093")
		)
		("@s9s_mb_2u_lib.s9s_mb_2u(sch_1):page621_i28@pure_quanta.q_res(chips)"
			("LOCATION" "R1094")
		)
		("@s9s_mb_2u_lib.s9s_mb_2u(sch_1):page621_i101@pure_quanta.q_res(chips)"
			("LOCATION" "R1336")
		)
		("@s9s_mb_2u_lib.s9s_mb_2u(sch_1):page621_i104@pure_quanta.q_res(chips)"
			("LOCATION" "R1460")
		)
		("@s9s_mb_2u_lib.s9s_mb_2u(sch_1):page621_i97@pure_quanta.q_res(chips)"
			("LOCATION" "R1806")
		)
		("@s9s_mb_2u_lib.s9s_mb_2u(sch_1):page621_i100@pure_quanta.q_res(chips)"
			("LOCATION" "R1822")
		)
		("@s9s_mb_2u_lib.s9s_mb_2u(sch_1):page621_i23@pure_quanta.pca9548apw(chips)"
			("LOCATION" "U36")
		)
		("@s9s_mb_2u_lib.s9s_mb_2u(sch_1):page572_i32@pure_quanta.q_cap(chips)"
			("LOCATION" "C175")
		)
		("@s9s_mb_2u_lib.s9s_mb_2u(sch_1):page572_i38@pure_quanta.q_cap(chips)"
			("LOCATION" "C176")
		)
		("@s9s_mb_2u_lib.s9s_mb_2u(sch_1):page572_i55@pure_quanta.q_cap(chips)"
			("LOCATION" "C177")
		)
		("@s9s_mb_2u_lib.s9s_mb_2u(sch_1):page572_i9@pure_quanta.q_cap(chips)"
			("LOCATION" "C178")
		)
		("@s9s_mb_2u_lib.s9s_mb_2u(sch_1):page572_i92@pure_quanta.mosfet_nch_dual(chips)"
			("LOCATION" "Q17")
		)
		("@s9s_mb_2u_lib.s9s_mb_2u(sch_1):page572_i94@pure_quanta.mosfet_nch_dual(chips)"
			("LOCATION" "Q17")
		)
		("@s9s_mb_2u_lib.s9s_mb_2u(sch_1):page572_i90@pure_quanta.mosfet_nch_dual(chips)"
			("LOCATION" "Q18")
		)
		("@s9s_mb_2u_lib.s9s_mb_2u(sch_1):page572_i93@pure_quanta.mosfet_nch_dual(chips)"
			("LOCATION" "Q18")
		)
		("@s9s_mb_2u_lib.s9s_mb_2u(sch_1):page572_i97@pure_quanta.q_res(chips)"
			("LOCATION" "R385")
		)
		("@s9s_mb_2u_lib.s9s_mb_2u(sch_1):page572_i77@pure_quanta.q_res(chips)"
			("LOCATION" "R1027")
		)
		("@s9s_mb_2u_lib.s9s_mb_2u(sch_1):page572_i78@pure_quanta.q_res(chips)"
			("LOCATION" "R1028")
		)
		("@s9s_mb_2u_lib.s9s_mb_2u(sch_1):page572_i35@pure_quanta.q_res(chips)"
			("LOCATION" "R1029")
		)
		("@s9s_mb_2u_lib.s9s_mb_2u(sch_1):page572_i42@pure_quanta.q_res(chips)"
			("LOCATION" "R1030")
		)
		("@s9s_mb_2u_lib.s9s_mb_2u(sch_1):page572_i44@pure_quanta.q_res(chips)"
			("LOCATION" "R1031")
		)
		("@s9s_mb_2u_lib.s9s_mb_2u(sch_1):page572_i68@pure_quanta.q_res(chips)"
			("LOCATION" "R1032")
		)
		("@s9s_mb_2u_lib.s9s_mb_2u(sch_1):page572_i34@pure_quanta.q_res(chips)"
			("LOCATION" "R1033")
		)
		("@s9s_mb_2u_lib.s9s_mb_2u(sch_1):page572_i40@pure_quanta.q_res(chips)"
			("LOCATION" "R1034")
		)
		("@s9s_mb_2u_lib.s9s_mb_2u(sch_1):page572_i63@pure_quanta.q_res(chips)"
			("LOCATION" "R1035")
		)
		("@s9s_mb_2u_lib.s9s_mb_2u(sch_1):page572_i66@pure_quanta.q_res(chips)"
			("LOCATION" "R1036")
		)
		("@s9s_mb_2u_lib.s9s_mb_2u(sch_1):page572_i72@pure_quanta.q_res(chips)"
			("LOCATION" "R1037")
		)
		("@s9s_mb_2u_lib.s9s_mb_2u(sch_1):page572_i73@pure_quanta.q_res(chips)"
			("LOCATION" "R1038")
		)
		("@s9s_mb_2u_lib.s9s_mb_2u(sch_1):page572_i59@pure_quanta.q_res(chips)"
			("LOCATION" "R1039")
		)
		("@s9s_mb_2u_lib.s9s_mb_2u(sch_1):page572_i18@pure_quanta.q_res(chips)"
			("LOCATION" "R1040")
		)
		("@s9s_mb_2u_lib.s9s_mb_2u(sch_1):page572_i29@pure_quanta.q_res(chips)"
			("LOCATION" "R1041")
		)
		("@s9s_mb_2u_lib.s9s_mb_2u(sch_1):page572_i17@pure_quanta.q_res(chips)"
			("LOCATION" "R1042")
		)
		("@s9s_mb_2u_lib.s9s_mb_2u(sch_1):page572_i24@pure_quanta.q_res(chips)"
			("LOCATION" "R1043")
		)
		("@s9s_mb_2u_lib.s9s_mb_2u(sch_1):page572_i27@pure_quanta.q_res(chips)"
			("LOCATION" "R1044")
		)
		("@s9s_mb_2u_lib.s9s_mb_2u(sch_1):page572_i20@pure_quanta.q_res(chips)"
			("LOCATION" "R1045")
		)
		("@s9s_mb_2u_lib.s9s_mb_2u(sch_1):page572_i53@pure_quanta.q_res(chips)"
			("LOCATION" "R1046")
		)
		("@s9s_mb_2u_lib.s9s_mb_2u(sch_1):page572_i4@pure_quanta.q_res(chips)"
			("LOCATION" "R1047")
		)
		("@s9s_mb_2u_lib.s9s_mb_2u(sch_1):page572_i51@pure_quanta.q_res(chips)"
			("LOCATION" "R1048")
		)
		("@s9s_mb_2u_lib.s9s_mb_2u(sch_1):page572_i13@pure_quanta.q_res(chips)"
			("LOCATION" "R1049")
		)
		("@s9s_mb_2u_lib.s9s_mb_2u(sch_1):page572_i6@pure_quanta.q_res(chips)"
			("LOCATION" "R1050")
		)
		("@s9s_mb_2u_lib.s9s_mb_2u(sch_1):page572_i48@pure_quanta.q_res(chips)"
			("LOCATION" "R1424")
		)
		("@s9s_mb_2u_lib.s9s_mb_2u(sch_1):page572_i87@pure_quanta.q_res(chips)"
			("LOCATION" "R1846")
		)
		("@s9s_mb_2u_lib.s9s_mb_2u(sch_1):page572_i85@pure_quanta.q_res(chips)"
			("LOCATION" "R1847")
		)
		("@s9s_mb_2u_lib.s9s_mb_2u(sch_1):page572_i81@pure_quanta.q_res(chips)"
			("LOCATION" "R1848")
		)
		("@s9s_mb_2u_lib.s9s_mb_2u(sch_1):page572_i83@pure_quanta.q_res(chips)"
			("LOCATION" "R1849")
		)
		("@s9s_mb_2u_lib.s9s_mb_2u(sch_1):page572_i31@pure_quanta.tps3700dser(chips)"
			("LOCATION" "U32")
		)
		("@s9s_mb_2u_lib.s9s_mb_2u(sch_1):page572_i61@pure_quanta.tps3700dser(chips)"
			("LOCATION" "U33")
		)
		("@s9s_mb_2u_lib.s9s_mb_2u(sch_1):page572_i57@pure_quanta.tps3700dser(chips)"
			("LOCATION" "U34")
		)
		("@s9s_mb_2u_lib.s9s_mb_2u(sch_1):page572_i10@pure_quanta.sn74lvc1g126dckr(chips)"
			("LOCATION" "U35")
		)
		("@s9s_mb_2u_lib.s9s_mb_2u(sch_1):page509_i73@pure_quanta.q_cap(chips)"
			("LOCATION" "C179")
		)
		("@s9s_mb_2u_lib.s9s_mb_2u(sch_1):page509_i77@pure_quanta.q_cap(chips)"
			("LOCATION" "C180")
		)
		("@s9s_mb_2u_lib.s9s_mb_2u(sch_1):page509_i70@pure_quanta.q_cap(chips)"
			("LOCATION" "C181")
		)
		("@s9s_mb_2u_lib.s9s_mb_2u(sch_1):page509_i71@pure_quanta.q_cap(chips)"
			("LOCATION" "C182")
		)
		("@s9s_mb_2u_lib.s9s_mb_2u(sch_1):page509_i29@pure_quanta.q_cap(chips)"
			("LOCATION" "C183")
		)
		("@s9s_mb_2u_lib.s9s_mb_2u(sch_1):page509_i24@pure_quanta.q_cap(chips)"
			("LOCATION" "C184")
		)
		("@s9s_mb_2u_lib.s9s_mb_2u(sch_1):page509_i22@pure_quanta.q_cap(chips)"
			("LOCATION" "C185")
		)
		("@s9s_mb_2u_lib.s9s_mb_2u(sch_1):page509_i15@pure_quanta.q_cap(chips)"
			("LOCATION" "C186")
		)
		("@s9s_mb_2u_lib.s9s_mb_2u(sch_1):page509_i97@pure_quanta.q_cap(chips)"
			("LOCATION" "C334")
		)
		("@s9s_mb_2u_lib.s9s_mb_2u(sch_1):page509_i94@pure_quanta.q_cap(chips)"
			("LOCATION" "C375")
		)
		("@s9s_mb_2u_lib.s9s_mb_2u(sch_1):page509_i95@pure_quanta.q_cap(chips)"
			("LOCATION" "C378")
		)
		("@s9s_mb_2u_lib.s9s_mb_2u(sch_1):page509_i96@pure_quanta.q_cap(chips)"
			("LOCATION" "C469")
		)
		("@s9s_mb_2u_lib.s9s_mb_2u(sch_1):page509_i21@pure_quanta.q_cap(chips)"
			("LOCATION" "C571")
		)
		("@s9s_mb_2u_lib.s9s_mb_2u(sch_1):page509_i51@pure_quanta.q_cap(chips)"
			("LOCATION" "C572")
		)
		("@s9s_mb_2u_lib.s9s_mb_2u(sch_1):page509_i55@pure_quanta.q_cap(chips)"
			("LOCATION" "C573")
		)
		("@s9s_mb_2u_lib.s9s_mb_2u(sch_1):page509_i16@pure_quanta.schottky_ac(chips)"
			("LOCATION" "D2")
		)
		("@s9s_mb_2u_lib.s9s_mb_2u(sch_1):page509_i80@pure_quanta.q_res(chips)"
			("LOCATION" "R1095")
		)
		("@s9s_mb_2u_lib.s9s_mb_2u(sch_1):page509_i37@pure_quanta.q_res(chips)"
			("LOCATION" "R1096")
		)
		("@s9s_mb_2u_lib.s9s_mb_2u(sch_1):page509_i36@pure_quanta.q_res(chips)"
			("LOCATION" "R1097")
		)
		("@s9s_mb_2u_lib.s9s_mb_2u(sch_1):page509_i34@pure_quanta.q_res(chips)"
			("LOCATION" "R1098")
		)
		("@s9s_mb_2u_lib.s9s_mb_2u(sch_1):page509_i13@pure_quanta.q_res(chips)"
			("LOCATION" "R1103")
		)
		("@s9s_mb_2u_lib.s9s_mb_2u(sch_1):page509_i12@pure_quanta.q_res(chips)"
			("LOCATION" "R1104")
		)
		("@s9s_mb_2u_lib.s9s_mb_2u(sch_1):page509_i18@pure_quanta.q_res(chips)"
			("LOCATION" "R1105")
		)
		("@s9s_mb_2u_lib.s9s_mb_2u(sch_1):page509_i3@pure_quanta.q_res(chips)"
			("LOCATION" "R1107")
		)
		("@s9s_mb_2u_lib.s9s_mb_2u(sch_1):page509_i49@pure_quanta.q_res(chips)"
			("LOCATION" "R1108")
		)
		("@s9s_mb_2u_lib.s9s_mb_2u(sch_1):page509_i48@pure_quanta.q_res(chips)"
			("LOCATION" "R1109")
		)
		("@s9s_mb_2u_lib.s9s_mb_2u(sch_1):page509_i45@pure_quanta.q_res(chips)"
			("LOCATION" "R1110")
		)
		("@s9s_mb_2u_lib.s9s_mb_2u(sch_1):page509_i43@pure_quanta.q_res(chips)"
			("LOCATION" "R1111")
		)
		("@s9s_mb_2u_lib.s9s_mb_2u(sch_1):page509_i98@pure_quanta.q_res(chips)"
			("LOCATION" "R1909")
		)
		("@s9s_mb_2u_lib.s9s_mb_2u(sch_1):page509_i100@pure_quanta.q_res(chips)"
			("LOCATION" "R1910")
		)
		("@s9s_mb_2u_lib.s9s_mb_2u(sch_1):page509_i101@pure_quanta.q_res(chips)"
			("LOCATION" "R1911")
		)
		("@s9s_mb_2u_lib.s9s_mb_2u(sch_1):page509_i102@pure_quanta.q_res(chips)"
			("LOCATION" "R1912")
		)
		("@s9s_mb_2u_lib.s9s_mb_2u(sch_1):page509_i112@pure_quanta.q_res(chips)"
			("LOCATION" "R1913")
		)
		("@s9s_mb_2u_lib.s9s_mb_2u(sch_1):page509_i111@pure_quanta.q_res(chips)"
			("LOCATION" "R1914")
		)
		("@s9s_mb_2u_lib.s9s_mb_2u(sch_1):page509_i110@pure_quanta.q_res(chips)"
			("LOCATION" "R1915")
		)
		("@s9s_mb_2u_lib.s9s_mb_2u(sch_1):page509_i117@pure_quanta.q_res(chips)"
			("LOCATION" "R1916")
		)
		("@s9s_mb_2u_lib.s9s_mb_2u(sch_1):page509_i83@pure_quanta.sn74lvc2g07dckr(chips)"
			("LOCATION" "U37")
		)
		("@s9s_mb_2u_lib.s9s_mb_2u(sch_1):page509_i88@pure_quanta.sn74lvc2g07dckr(chips)"
			("LOCATION" "U39")
		)
		("@s9s_mb_2u_lib.s9s_mb_2u(sch_1):page509_i27@pure_quanta.tps259520dsgr(chips)"
			("LOCATION" "U40")
		)
		("@s9s_mb_2u_lib.s9s_mb_2u(sch_1):page509_i30@pure_quanta.tps259824onrger(chips)"
			("LOCATION" "U41")
		)
		("@s9s_mb_2u_lib.s9s_mb_2u(sch_1):page509_i56@pure_quanta.sn74lvc2g07dckr(chips)"
			("LOCATION" "U42")
		)
		("@s9s_mb_2u_lib.s9s_mb_2u(sch_1):page509_i58@pure_quanta.sn74lvc2g07dckr(chips)"
			("LOCATION" "U43")
		)
		("@s9s_mb_2u_lib.s9s_mb_2u(sch_1):page507_i74@pure_quanta.q_cap(chips)"
			("LOCATION" "C187")
		)
		("@s9s_mb_2u_lib.s9s_mb_2u(sch_1):page507_i76@pure_quanta.q_cap(chips)"
			("LOCATION" "C189")
		)
		("@s9s_mb_2u_lib.s9s_mb_2u(sch_1):page507_i77@pure_quanta.q_cap(chips)"
			("LOCATION" "C319")
		)
		("@s9s_mb_2u_lib.s9s_mb_2u(sch_1):page507_i75@pure_quanta.q_cap(chips)"
			("LOCATION" "C331")
		)
		("@s9s_mb_2u_lib.s9s_mb_2u(sch_1):page507_i57@pure_quanta.q_cap(chips)"
			("LOCATION" "C582")
		)
		("@s9s_mb_2u_lib.s9s_mb_2u(sch_1):page507_i62@pure_quanta.q_cap(chips)"
			("LOCATION" "C583")
		)
		("@s9s_mb_2u_lib.s9s_mb_2u(sch_1):page507_i61@pure_quanta.q_cap(chips)"
			("LOCATION" "C586")
		)
		("@s9s_mb_2u_lib.s9s_mb_2u(sch_1):page507_i24@pure_quanta.q_cap(chips)"
			("LOCATION" "C587")
		)
		("@s9s_mb_2u_lib.s9s_mb_2u(sch_1):page507_i18@pure_quanta.q_cap(chips)"
			("LOCATION" "C588")
		)
		("@s9s_mb_2u_lib.s9s_mb_2u(sch_1):page507_i12@pure_quanta.q_cap(chips)"
			("LOCATION" "C589")
		)
		("@s9s_mb_2u_lib.s9s_mb_2u(sch_1):page507_i16@pure_quanta.q_cap(chips)"
			("LOCATION" "C591")
		)
		("@s9s_mb_2u_lib.s9s_mb_2u(sch_1):page507_i38@pure_quanta.q_cap(chips)"
			("LOCATION" "C592")
		)
		("@s9s_mb_2u_lib.s9s_mb_2u(sch_1):page507_i43@pure_quanta.q_cap(chips)"
			("LOCATION" "C593")
		)
		("@s9s_mb_2u_lib.s9s_mb_2u(sch_1):page507_i23@pure_quanta.schottky_ac(chips)"
			("LOCATION" "D4")
		)
		("@s9s_mb_2u_lib.s9s_mb_2u(sch_1):page507_i71@pure_quanta.q_res(chips)"
			("LOCATION" "R1134")
		)
		("@s9s_mb_2u_lib.s9s_mb_2u(sch_1):page507_i70@pure_quanta.q_res(chips)"
			("LOCATION" "R1135")
		)
		("@s9s_mb_2u_lib.s9s_mb_2u(sch_1):page507_i67@pure_quanta.q_res(chips)"
			("LOCATION" "R1136")
		)
		("@s9s_mb_2u_lib.s9s_mb_2u(sch_1):page507_i66@pure_quanta.q_res(chips)"
			("LOCATION" "R1137")
		)
		("@s9s_mb_2u_lib.s9s_mb_2u(sch_1):page507_i21@pure_quanta.q_res(chips)"
			("LOCATION" "R1142")
		)
		("@s9s_mb_2u_lib.s9s_mb_2u(sch_1):page507_i4@pure_quanta.q_res(chips)"
			("LOCATION" "R1143")
		)
		("@s9s_mb_2u_lib.s9s_mb_2u(sch_1):page507_i15@pure_quanta.q_res(chips)"
			("LOCATION" "R1144")
		)
		("@s9s_mb_2u_lib.s9s_mb_2u(sch_1):page507_i8@pure_quanta.q_res(chips)"
			("LOCATION" "R1146")
		)
		("@s9s_mb_2u_lib.s9s_mb_2u(sch_1):page507_i36@pure_quanta.q_res(chips)"
			("LOCATION" "R1147")
		)
		("@s9s_mb_2u_lib.s9s_mb_2u(sch_1):page507_i37@pure_quanta.q_res(chips)"
			("LOCATION" "R1148")
		)
		("@s9s_mb_2u_lib.s9s_mb_2u(sch_1):page507_i35@pure_quanta.q_res(chips)"
			("LOCATION" "R1149")
		)
		("@s9s_mb_2u_lib.s9s_mb_2u(sch_1):page507_i32@pure_quanta.q_res(chips)"
			("LOCATION" "R1150")
		)
		("@s9s_mb_2u_lib.s9s_mb_2u(sch_1):page507_i79@pure_quanta.q_res(chips)"
			("LOCATION" "R1905")
		)
		("@s9s_mb_2u_lib.s9s_mb_2u(sch_1):page507_i83@pure_quanta.q_res(chips)"
			("LOCATION" "R1906")
		)
		("@s9s_mb_2u_lib.s9s_mb_2u(sch_1):page507_i80@pure_quanta.q_res(chips)"
			("LOCATION" "R1907")
		)
		("@s9s_mb_2u_lib.s9s_mb_2u(sch_1):page507_i81@pure_quanta.q_res(chips)"
			("LOCATION" "R1908")
		)
		("@s9s_mb_2u_lib.s9s_mb_2u(sch_1):page507_i56@pure_quanta.tps259520dsgr(chips)"
			("LOCATION" "U56")
		)
		("@s9s_mb_2u_lib.s9s_mb_2u(sch_1):page507_i27@pure_quanta.tps259824onrger(chips)"
			("LOCATION" "U57")
		)
		("@s9s_mb_2u_lib.s9s_mb_2u(sch_1):page507_i44@pure_quanta.sn74lvc2g07dckr(chips)"
			("LOCATION" "U58")
		)
		("@s9s_mb_2u_lib.s9s_mb_2u(sch_1):page507_i46@pure_quanta.sn74lvc2g07dckr(chips)"
			("LOCATION" "U59")
		)
		("@s9s_mb_2u_lib.s9s_mb_2u(sch_1):page502_i44@pure_quanta.q_cap(chips)"
			("LOCATION" "C188")
		)
		("@s9s_mb_2u_lib.s9s_mb_2u(sch_1):page502_i4@pure_quanta.q_cap(chips)"
			("LOCATION" "C1173")
		)
		("@s9s_mb_2u_lib.s9s_mb_2u(sch_1):page502_i24@pure_quanta.q_cap(chips)"
			("LOCATION" "C1175")
		)
		("@s9s_mb_2u_lib.s9s_mb_2u(sch_1):page502_i59@pure_quanta.q_cap(chips)"
			("LOCATION" "C1274")
		)
		("@s9s_mb_2u_lib.s9s_mb_2u(sch_1):page502_i49@pure_quanta.q_cap(chips)"
			("LOCATION" "C1275")
		)
		("@s9s_mb_2u_lib.s9s_mb_2u(sch_1):page502_i58@pure_quanta.osc4_sit1602ai2233e50000000d(chips)"
			("LOCATION" "OSC1")
		)
		("@s9s_mb_2u_lib.s9s_mb_2u(sch_1):page502_i6@pure_quanta.q_res(chips)"
			("LOCATION" "R419")
		)
		("@s9s_mb_2u_lib.s9s_mb_2u(sch_1):page502_i8@pure_quanta.q_res(chips)"
			("LOCATION" "R435")
		)
		("@s9s_mb_2u_lib.s9s_mb_2u(sch_1):page502_i61@pure_quanta.q_res(chips)"
			("LOCATION" "R1138")
		)
		("@s9s_mb_2u_lib.s9s_mb_2u(sch_1):page502_i56@pure_quanta.q_res(chips)"
			("LOCATION" "R1139")
		)
		("@s9s_mb_2u_lib.s9s_mb_2u(sch_1):page502_i52@pure_quanta.q_res(chips)"
			("LOCATION" "R1140")
		)
		("@s9s_mb_2u_lib.s9s_mb_2u(sch_1):page502_i53@pure_quanta.q_res(chips)"
			("LOCATION" "R1141")
		)
		("@s9s_mb_2u_lib.s9s_mb_2u(sch_1):page502_i10@pure_quanta.q_res(chips)"
			("LOCATION" "R1504")
		)
		("@s9s_mb_2u_lib.s9s_mb_2u(sch_1):page502_i13@pure_quanta.q_res(chips)"
			("LOCATION" "R1505")
		)
		("@s9s_mb_2u_lib.s9s_mb_2u(sch_1):page502_i37@pure_quanta.q_res(chips)"
			("LOCATION" "R1592")
		)
		("@s9s_mb_2u_lib.s9s_mb_2u(sch_1):page502_i42@pure_quanta.q_res(chips)"
			("LOCATION" "R1593")
		)
		("@s9s_mb_2u_lib.s9s_mb_2u(sch_1):page502_i26@pure_quanta.q_res(chips)"
			("LOCATION" "R1594")
		)
		("@s9s_mb_2u_lib.s9s_mb_2u(sch_1):page502_i40@pure_quanta.q_res(chips)"
			("LOCATION" "R1595")
		)
		("@s9s_mb_2u_lib.s9s_mb_2u(sch_1):page502_i62@pure_quanta.q_res(chips)"
			("LOCATION" "R1824")
		)
		("@s9s_mb_2u_lib.s9s_mb_2u(sch_1):page502_i1@pure_quanta.sn74lvc1g17dckr(chips)"
			("LOCATION" "U75")
		)
		("@s9s_mb_2u_lib.s9s_mb_2u(sch_1):page502_i35@pure_quanta.\\74lvc1g126gw\\(chips)"
			("LOCATION" "U82")
		)
		("@s9s_mb_2u_lib.s9s_mb_2u(sch_1):page502_i46@pure_quanta.pi6cv304le(chips)"
			("LOCATION" "U90")
		)
		("@s9s_mb_2u_lib.s9s_mb_2u(sch_1):page502_i63@pure_quanta.\\74lvc1g07gv\\(chips)"
			("LOCATION" "U104")
		)
		("@s9s_mb_2u_lib.s9s_mb_2u(sch_1):page628_i140@pure_quanta.q_cap(chips)"
			("LOCATION" "C190")
		)
		("@s9s_mb_2u_lib.s9s_mb_2u(sch_1):page628_i154@pure_quanta.q_cap(chips)"
			("LOCATION" "C585")
		)
		("@s9s_mb_2u_lib.s9s_mb_2u(sch_1):page628_i137@pure_quanta.q_cap(chips)"
			("LOCATION" "C594")
		)
		("@s9s_mb_2u_lib.s9s_mb_2u(sch_1):page628_i109@pure_quanta.q_cap(chips)"
			("LOCATION" "C595")
		)
		("@s9s_mb_2u_lib.s9s_mb_2u(sch_1):page628_i115@pure_quanta.q_cap(chips)"
			("LOCATION" "C596")
		)
		("@s9s_mb_2u_lib.s9s_mb_2u(sch_1):page628_i75@pure_quanta.q_cap(chips)"
			("LOCATION" "C597")
		)
		("@s9s_mb_2u_lib.s9s_mb_2u(sch_1):page628_i59@pure_quanta.q_cap(chips)"
			("LOCATION" "C598")
		)
		("@s9s_mb_2u_lib.s9s_mb_2u(sch_1):page628_i148@pure_quanta.q_cap(chips)"
			("LOCATION" "C599")
		)
		("@s9s_mb_2u_lib.s9s_mb_2u(sch_1):page628_i52@pure_quanta.q_cap(chips)"
			("LOCATION" "C600")
		)
		("@s9s_mb_2u_lib.s9s_mb_2u(sch_1):page628_i50@pure_quanta.q_cap(chips)"
			("LOCATION" "C601")
		)
		("@s9s_mb_2u_lib.s9s_mb_2u(sch_1):page628_i96@pure_quanta.q_cap(chips)"
			("LOCATION" "C602")
		)
		("@s9s_mb_2u_lib.s9s_mb_2u(sch_1):page628_i12@pure_quanta.q_cap(chips)"
			("LOCATION" "C603")
		)
		("@s9s_mb_2u_lib.s9s_mb_2u(sch_1):page628_i10@pure_quanta.q_cap(chips)"
			("LOCATION" "C604")
		)
		("@s9s_mb_2u_lib.s9s_mb_2u(sch_1):page628_i134@pure_quanta.zener_ac(chips)"
			("LOCATION" "D5")
		)
		("@s9s_mb_2u_lib.s9s_mb_2u(sch_1):page628_i124@pure_quanta.conn3_210hp1030br1(chips)"
			("LOCATION" "JP3")
		)
		("@s9s_mb_2u_lib.s9s_mb_2u(sch_1):page628_i94@pure_quanta.mosfet_nch_1d3s(chips)"
			("LOCATION" "PQ11")
		)
		("@s9s_mb_2u_lib.s9s_mb_2u(sch_1):page628_i45@pure_quanta.mosfet_nch_1d3s(chips)"
			("LOCATION" "PQ12")
		)
		("@s9s_mb_2u_lib.s9s_mb_2u(sch_1):page628_i43@pure_quanta.mosfet_nch_1d3s(chips)"
			("LOCATION" "PQ13")
		)
		("@s9s_mb_2u_lib.s9s_mb_2u(sch_1):page628_i41@pure_quanta.mosfet_nch_1d3s(chips)"
			("LOCATION" "PQ14")
		)
		("@s9s_mb_2u_lib.s9s_mb_2u(sch_1):page628_i29@pure_quanta.mosfet_nch_1d3s(chips)"
			("LOCATION" "PQ15")
		)
		("@s9s_mb_2u_lib.s9s_mb_2u(sch_1):page628_i160@pure_quanta.mosfet_nch_1d3s(chips)"
			("LOCATION" "PQ16")
		)
		("@s9s_mb_2u_lib.s9s_mb_2u(sch_1):page628_i71@pure_quanta.mosfet_dual_6p(chips)"
			("LOCATION" "Q25")
		)
		("@s9s_mb_2u_lib.s9s_mb_2u(sch_1):page628_i11@pure_quanta.\\2n7002a7\\(chips)"
			("LOCATION" "Q26")
		)
		("@s9s_mb_2u_lib.s9s_mb_2u(sch_1):page628_i151@pure_quanta.mmbt39047f(chips)"
			("LOCATION" "Q36")
		)
		("@s9s_mb_2u_lib.s9s_mb_2u(sch_1):page628_i133@pure_quanta.q_res(chips)"
			("LOCATION" "R1151")
		)
		("@s9s_mb_2u_lib.s9s_mb_2u(sch_1):page628_i136@pure_quanta.q_res(chips)"
			("LOCATION" "R1152")
		)
		("@s9s_mb_2u_lib.s9s_mb_2u(sch_1):page628_i161@pure_quanta.q_res(chips)"
			("LOCATION" "R1153")
		)
		("@s9s_mb_2u_lib.s9s_mb_2u(sch_1):page628_i120@pure_quanta.q_res(chips)"
			("LOCATION" "R1154")
		)
		("@s9s_mb_2u_lib.s9s_mb_2u(sch_1):page628_i123@pure_quanta.q_res(chips)"
			("LOCATION" "R1155")
		)
		("@s9s_mb_2u_lib.s9s_mb_2u(sch_1):page628_i163@pure_quanta.q_res(chips)"
			("LOCATION" "R1156")
		)
		("@s9s_mb_2u_lib.s9s_mb_2u(sch_1):page628_i110@pure_quanta.q_res(chips)"
			("LOCATION" "R1157")
		)
		("@s9s_mb_2u_lib.s9s_mb_2u(sch_1):page628_i113@pure_quanta.q_res(chips)"
			("LOCATION" "R1158")
		)
		("@s9s_mb_2u_lib.s9s_mb_2u(sch_1):page628_i76@pure_quanta.q_res(chips)"
			("LOCATION" "R1159")
		)
		("@s9s_mb_2u_lib.s9s_mb_2u(sch_1):page628_i77@pure_quanta.q_res(chips)"
			("LOCATION" "R1160")
		)
		("@s9s_mb_2u_lib.s9s_mb_2u(sch_1):page628_i67@pure_quanta.q_res(chips)"
			("LOCATION" "R1161")
		)
		("@s9s_mb_2u_lib.s9s_mb_2u(sch_1):page628_i68@pure_quanta.q_res(chips)"
			("LOCATION" "R1162")
		)
		("@s9s_mb_2u_lib.s9s_mb_2u(sch_1):page628_i69@pure_quanta.q_res(chips)"
			("LOCATION" "R1163")
		)
		("@s9s_mb_2u_lib.s9s_mb_2u(sch_1):page628_i70@pure_quanta.q_res(chips)"
			("LOCATION" "R1164")
		)
		("@s9s_mb_2u_lib.s9s_mb_2u(sch_1):page628_i102@pure_quanta.q_res(chips)"
			("LOCATION" "R1165")
		)
		("@s9s_mb_2u_lib.s9s_mb_2u(sch_1):page628_i101@pure_quanta.q_res(chips)"
			("LOCATION" "R1166")
		)
		("@s9s_mb_2u_lib.s9s_mb_2u(sch_1):page628_i104@pure_quanta.q_res(chips)"
			("LOCATION" "R1167")
		)
		("@s9s_mb_2u_lib.s9s_mb_2u(sch_1):page628_i103@pure_quanta.q_res(chips)"
			("LOCATION" "R1168")
		)
		("@s9s_mb_2u_lib.s9s_mb_2u(sch_1):page628_i74@pure_quanta.q_res(chips)"
			("LOCATION" "R1169")
		)
		("@s9s_mb_2u_lib.s9s_mb_2u(sch_1):page628_i100@pure_quanta.q_res(chips)"
			("LOCATION" "R1170")
		)
		("@s9s_mb_2u_lib.s9s_mb_2u(sch_1):page628_i92@pure_quanta.q_sp_res4p(chips)"
			("LOCATION" "R1171")
		)
		("@s9s_mb_2u_lib.s9s_mb_2u(sch_1):page628_i93@pure_quanta.q_sp_res4p(chips)"
			("LOCATION" "R1172")
		)
		("@s9s_mb_2u_lib.s9s_mb_2u(sch_1):page628_i58@pure_quanta.q_res(chips)"
			("LOCATION" "R1173")
		)
		("@s9s_mb_2u_lib.s9s_mb_2u(sch_1):page628_i98@pure_quanta.q_res(chips)"
			("LOCATION" "R1174")
		)
		("@s9s_mb_2u_lib.s9s_mb_2u(sch_1):page628_i81@pure_quanta.q_res(chips)"
			("LOCATION" "R1175")
		)
		("@s9s_mb_2u_lib.s9s_mb_2u(sch_1):page628_i95@pure_quanta.q_res(chips)"
			("LOCATION" "R1176")
		)
		("@s9s_mb_2u_lib.s9s_mb_2u(sch_1):page628_i57@pure_quanta.q_res(chips)"
			("LOCATION" "R1177")
		)
		("@s9s_mb_2u_lib.s9s_mb_2u(sch_1):page628_i49@pure_quanta.q_res(chips)"
			("LOCATION" "R1178")
		)
		("@s9s_mb_2u_lib.s9s_mb_2u(sch_1):page628_i54@pure_quanta.q_res(chips)"
			("LOCATION" "R1179")
		)
		("@s9s_mb_2u_lib.s9s_mb_2u(sch_1):page628_i79@pure_quanta.q_res(chips)"
			("LOCATION" "R1180")
		)
		("@s9s_mb_2u_lib.s9s_mb_2u(sch_1):page628_i46@pure_quanta.q_res(chips)"
			("LOCATION" "R1181")
		)
		("@s9s_mb_2u_lib.s9s_mb_2u(sch_1):page628_i37@pure_quanta.q_res(chips)"
			("LOCATION" "R1182")
		)
		("@s9s_mb_2u_lib.s9s_mb_2u(sch_1):page628_i44@pure_quanta.q_res(chips)"
			("LOCATION" "R1183")
		)
		("@s9s_mb_2u_lib.s9s_mb_2u(sch_1):page628_i42@pure_quanta.q_res(chips)"
			("LOCATION" "R1185")
		)
		("@s9s_mb_2u_lib.s9s_mb_2u(sch_1):page628_i34@pure_quanta.q_res(chips)"
			("LOCATION" "R1186")
		)
		("@s9s_mb_2u_lib.s9s_mb_2u(sch_1):page628_i33@pure_quanta.q_res(chips)"
			("LOCATION" "R1187")
		)
		("@s9s_mb_2u_lib.s9s_mb_2u(sch_1):page628_i30@pure_quanta.q_res(chips)"
			("LOCATION" "R1188")
		)
		("@s9s_mb_2u_lib.s9s_mb_2u(sch_1):page628_i26@pure_quanta.q_res(chips)"
			("LOCATION" "R1189")
		)
		("@s9s_mb_2u_lib.s9s_mb_2u(sch_1):page628_i13@pure_quanta.q_res(chips)"
			("LOCATION" "R1190")
		)
		("@s9s_mb_2u_lib.s9s_mb_2u(sch_1):page628_i14@pure_quanta.q_res(chips)"
			("LOCATION" "R1191")
		)
		("@s9s_mb_2u_lib.s9s_mb_2u(sch_1):page628_i24@pure_quanta.q_res(chips)"
			("LOCATION" "R1192")
		)
		("@s9s_mb_2u_lib.s9s_mb_2u(sch_1):page628_i31@pure_quanta.q_res(chips)"
			("LOCATION" "R1193")
		)
		("@s9s_mb_2u_lib.s9s_mb_2u(sch_1):page628_i142@pure_quanta.q_res(chips)"
			("LOCATION" "R1548")
		)
		("@s9s_mb_2u_lib.s9s_mb_2u(sch_1):page628_i144@pure_quanta.q_res(chips)"
			("LOCATION" "R1553")
		)
		("@s9s_mb_2u_lib.s9s_mb_2u(sch_1):page628_i152@pure_quanta.q_res(chips)"
			("LOCATION" "R1602")
		)
		("@s9s_mb_2u_lib.s9s_mb_2u(sch_1):page628_i153@pure_quanta.q_res(chips)"
			("LOCATION" "R1603")
		)
		("@s9s_mb_2u_lib.s9s_mb_2u(sch_1):page628_i147@pure_quanta.q_res(chips)"
			("LOCATION" "R1807")
		)
		("@s9s_mb_2u_lib.s9s_mb_2u(sch_1):page628_i149@pure_quanta.q_res(chips)"
			("LOCATION" "R1808")
		)
		("@s9s_mb_2u_lib.s9s_mb_2u(sch_1):page628_i159@pure_quanta.q_res(chips)"
			("LOCATION" "R1922")
		)
		("@s9s_mb_2u_lib.s9s_mb_2u(sch_1):page628_i21@pure_quanta.adm12781acpzrl_reva(chips)"
			("LOCATION" "U12")
		)
		("@s9s_mb_2u_lib.s9s_mb_2u(sch_1):page570_i54@pure_quanta.q_cap(chips)"
			("LOCATION" "C191")
		)
		("@s9s_mb_2u_lib.s9s_mb_2u(sch_1):page570_i45@pure_quanta.q_cap(chips)"
			("LOCATION" "C193")
		)
		("@s9s_mb_2u_lib.s9s_mb_2u(sch_1):page570_i43@pure_quanta.q_cap(chips)"
			("LOCATION" "C195")
		)
		("@s9s_mb_2u_lib.s9s_mb_2u(sch_1):page570_i14@pure_quanta.q_cap(chips)"
			("LOCATION" "C197")
		)
		("@s9s_mb_2u_lib.s9s_mb_2u(sch_1):page570_i9@pure_quanta.q_cap(chips)"
			("LOCATION" "C199")
		)
		("@s9s_mb_2u_lib.s9s_mb_2u(sch_1):page570_i7@pure_quanta.q_cap(chips)"
			("LOCATION" "C201")
		)
		("@s9s_mb_2u_lib.s9s_mb_2u(sch_1):page570_i6@pure_quanta.q_cap(chips)"
			("LOCATION" "C203")
		)
		("@s9s_mb_2u_lib.s9s_mb_2u(sch_1):page570_i1@pure_quanta.q_cap(chips)"
			("LOCATION" "C642")
		)
		("@s9s_mb_2u_lib.s9s_mb_2u(sch_1):page570_i95@pure_quanta.q_cap(chips)"
			("LOCATION" "C1354")
		)
		("@s9s_mb_2u_lib.s9s_mb_2u(sch_1):page570_i91@pure_quanta.q_cap(chips)"
			("LOCATION" "C1355")
		)
		("@s9s_mb_2u_lib.s9s_mb_2u(sch_1):page570_i92@pure_quanta.q_cap(chips)"
			("LOCATION" "C1356")
		)
		("@s9s_mb_2u_lib.s9s_mb_2u(sch_1):page570_i87@pure_quanta.q_cap(chips)"
			("LOCATION" "C1357")
		)
		("@s9s_mb_2u_lib.s9s_mb_2u(sch_1):page570_i82@pure_quanta.q_cap(chips)"
			("LOCATION" "C1358")
		)
		("@s9s_mb_2u_lib.s9s_mb_2u(sch_1):page570_i83@pure_quanta.q_cap(chips)"
			("LOCATION" "C1359")
		)
		("@s9s_mb_2u_lib.s9s_mb_2u(sch_1):page570_i84@pure_quanta.q_cap(chips)"
			("LOCATION" "C1360")
		)
		("@s9s_mb_2u_lib.s9s_mb_2u(sch_1):page570_i85@pure_quanta.q_cap(chips)"
			("LOCATION" "C1361")
		)
		("@s9s_mb_2u_lib.s9s_mb_2u(sch_1):page570_i13@pure_quanta.bsc010ne2lsi(chips)"
			("LOCATION" "Q29")
		)
		("@s9s_mb_2u_lib.s9s_mb_2u(sch_1):page570_i86@pure_quanta.bsc010ne2lsi(chips)"
			("LOCATION" "Q38")
		)
		("@s9s_mb_2u_lib.s9s_mb_2u(sch_1):page570_i99@pure_quanta.bsc010ne2lsi(chips)"
			("LOCATION" "Q40")
		)
		("@s9s_mb_2u_lib.s9s_mb_2u(sch_1):page570_i48@pure_quanta.q_res(chips)"
			("LOCATION" "R1561")
		)
		("@s9s_mb_2u_lib.s9s_mb_2u(sch_1):page570_i47@pure_quanta.q_res(chips)"
			("LOCATION" "R1563")
		)
		("@s9s_mb_2u_lib.s9s_mb_2u(sch_1):page570_i17@pure_quanta.q_res(chips)"
			("LOCATION" "R1565")
		)
		("@s9s_mb_2u_lib.s9s_mb_2u(sch_1):page570_i40@pure_quanta.q_res(chips)"
			("LOCATION" "R1567")
		)
		("@s9s_mb_2u_lib.s9s_mb_2u(sch_1):page570_i41@pure_quanta.q_res(chips)"
			("LOCATION" "R1568")
		)
		("@s9s_mb_2u_lib.s9s_mb_2u(sch_1):page570_i39@pure_quanta.q_res(chips)"
			("LOCATION" "R1569")
		)
		("@s9s_mb_2u_lib.s9s_mb_2u(sch_1):page570_i98@pure_quanta.q_res(chips)"
			("LOCATION" "R1802")
		)
		("@s9s_mb_2u_lib.s9s_mb_2u(sch_1):page570_i90@pure_quanta.q_res(chips)"
			("LOCATION" "R1803")
		)
		("@s9s_mb_2u_lib.s9s_mb_2u(sch_1):page570_i93@pure_quanta.q_res(chips)"
			("LOCATION" "R1804")
		)
		("@s9s_mb_2u_lib.s9s_mb_2u(sch_1):page570_i88@pure_quanta.q_res(chips)"
			("LOCATION" "R1805")
		)
		("@s9s_mb_2u_lib.s9s_mb_2u(sch_1):page570_i50@pure_quanta.sn74lvc1g17dckr(chips)"
			("LOCATION" "U20")
		)
		("@s9s_mb_2u_lib.s9s_mb_2u(sch_1):page570_i19@pure_quanta.slg55021200010vtr(chips)"
			("LOCATION" "U80")
		)
		("@s9s_mb_2u_lib.s9s_mb_2u(sch_1):page570_i94@pure_quanta.sn74lvc1g17dckr(chips)"
			("LOCATION" "U106")
		)
		("@s9s_mb_2u_lib.s9s_mb_2u(sch_1):page570_i89@pure_quanta.slg55021200010vtr(chips)"
			("LOCATION" "U107")
		)
		("@s9s_mb_2u_lib.s9s_mb_2u(sch_1):page622_i14@pure_quanta.q_cap(chips)"
			("LOCATION" "C192")
		)
		("@s9s_mb_2u_lib.s9s_mb_2u(sch_1):page622_i8@pure_quanta.q_cap(chips)"
			("LOCATION" "C194")
		)
		("@s9s_mb_2u_lib.s9s_mb_2u(sch_1):page622_i30@pure_quanta.q_cap(chips)"
			("LOCATION" "C196")
		)
		("@s9s_mb_2u_lib.s9s_mb_2u(sch_1):page622_i53@pure_quanta.q_cap(chips)"
			("LOCATION" "C198")
		)
		("@s9s_mb_2u_lib.s9s_mb_2u(sch_1):page622_i65@pure_quanta.q_cap(chips)"
			("LOCATION" "C200")
		)
		("@s9s_mb_2u_lib.s9s_mb_2u(sch_1):page622_i66@pure_quanta.q_cap(chips)"
			("LOCATION" "C202")
		)
		("@s9s_mb_2u_lib.s9s_mb_2u(sch_1):page622_i69@pure_quanta.q_cap(chips)"
			("LOCATION" "C612")
		)
		("@s9s_mb_2u_lib.s9s_mb_2u(sch_1):page622_i70@pure_quanta.q_cap(chips)"
			("LOCATION" "C645")
		)
		("@s9s_mb_2u_lib.s9s_mb_2u(sch_1):page622_i26@pure_quanta.q_cap(chips)"
			("LOCATION" "C1306")
		)
		("@s9s_mb_2u_lib.s9s_mb_2u(sch_1):page622_i54@pure_quanta.bsc010ne2lsi(chips)"
			("LOCATION" "Q30")
		)
		("@s9s_mb_2u_lib.s9s_mb_2u(sch_1):page622_i71@pure_quanta.bsc010ne2lsi(chips)"
			("LOCATION" "Q42")
		)
		("@s9s_mb_2u_lib.s9s_mb_2u(sch_1):page622_i12@pure_quanta.q_res(chips)"
			("LOCATION" "R1555")
		)
		("@s9s_mb_2u_lib.s9s_mb_2u(sch_1):page622_i5@pure_quanta.q_res(chips)"
			("LOCATION" "R1562")
		)
		("@s9s_mb_2u_lib.s9s_mb_2u(sch_1):page622_i6@pure_quanta.q_res(chips)"
			("LOCATION" "R1564")
		)
		("@s9s_mb_2u_lib.s9s_mb_2u(sch_1):page622_i51@pure_quanta.q_res(chips)"
			("LOCATION" "R1566")
		)
		("@s9s_mb_2u_lib.s9s_mb_2u(sch_1):page622_i3@pure_quanta.sn74lvc1g17dckr(chips)"
			("LOCATION" "U69")
		)
		("@s9s_mb_2u_lib.s9s_mb_2u(sch_1):page622_i49@pure_quanta.slg55021200010vtr(chips)"
			("LOCATION" "U81")
		)
		("@s9s_mb_2u_lib.s9s_mb_2u(sch_1):page622_i18@pure_quanta.sn74lvc1g08dbvr(chips)"
			("LOCATION" "U93")
		)
		("@s9s_mb_2u_lib.s9s_mb_2u(sch_1):page532_i171@pure_quanta.q_cap(chips)"
			("LOCATION" "C204")
		)
		("@s9s_mb_2u_lib.s9s_mb_2u(sch_1):page532_i172@pure_quanta.q_cap(chips)"
			("LOCATION" "C205")
		)
		("@s9s_mb_2u_lib.s9s_mb_2u(sch_1):page532_i173@pure_quanta.q_cap(chips)"
			("LOCATION" "C206")
		)
		("@s9s_mb_2u_lib.s9s_mb_2u(sch_1):page532_i174@pure_quanta.q_cap(chips)"
			("LOCATION" "C207")
		)
		("@s9s_mb_2u_lib.s9s_mb_2u(sch_1):page532_i167@pure_quanta.q_cap(chips)"
			("LOCATION" "C208")
		)
		("@s9s_mb_2u_lib.s9s_mb_2u(sch_1):page532_i164@pure_quanta.q_cap(chips)"
			("LOCATION" "C209")
		)
		("@s9s_mb_2u_lib.s9s_mb_2u(sch_1):page532_i168@pure_quanta.q_cap(chips)"
			("LOCATION" "C210")
		)
		("@s9s_mb_2u_lib.s9s_mb_2u(sch_1):page532_i165@pure_quanta.q_cap(chips)"
			("LOCATION" "C211")
		)
		("@s9s_mb_2u_lib.s9s_mb_2u(sch_1):page532_i419@pure_quanta.q_cap(chips)"
			("LOCATION" "C1409")
		)
		("@s9s_mb_2u_lib.s9s_mb_2u(sch_1):page532_i170@pure_quanta.q_inductor(chips)"
			("LOCATION" "L3")
		)
		("@s9s_mb_2u_lib.s9s_mb_2u(sch_1):page532_i177@pure_quanta.q_inductor(chips)"
			("LOCATION" "L4")
		)
		("@s9s_mb_2u_lib.s9s_mb_2u(sch_1):page532_i304@pure_quanta.q_res(chips)"
			("LOCATION" "R106")
		)
		("@s9s_mb_2u_lib.s9s_mb_2u(sch_1):page532_i413@pure_quanta.q_res(chips)"
			("LOCATION" "R112")
		)
		("@s9s_mb_2u_lib.s9s_mb_2u(sch_1):page532_i179@pure_quanta.q_res(chips)"
			("LOCATION" "R567")
		)
		("@s9s_mb_2u_lib.s9s_mb_2u(sch_1):page532_i178@pure_quanta.q_res(chips)"
			("LOCATION" "R568")
		)
		("@s9s_mb_2u_lib.s9s_mb_2u(sch_1):page532_i185@pure_quanta.q_res(chips)"
			("LOCATION" "R569")
		)
		("@s9s_mb_2u_lib.s9s_mb_2u(sch_1):page532_i187@pure_quanta.q_res(chips)"
			("LOCATION" "R570")
		)
		("@s9s_mb_2u_lib.s9s_mb_2u(sch_1):page532_i163@pure_quanta.q_res(chips)"
			("LOCATION" "R571")
		)
		("@s9s_mb_2u_lib.s9s_mb_2u(sch_1):page532_i162@pure_quanta.q_res(chips)"
			("LOCATION" "R572")
		)
		("@s9s_mb_2u_lib.s9s_mb_2u(sch_1):page532_i194@pure_quanta.q_res(chips)"
			("LOCATION" "R573")
		)
		("@s9s_mb_2u_lib.s9s_mb_2u(sch_1):page532_i197@pure_quanta.q_res(chips)"
			("LOCATION" "R574")
		)
		("@s9s_mb_2u_lib.s9s_mb_2u(sch_1):page532_i199@pure_quanta.q_res(chips)"
			("LOCATION" "R575")
		)
		("@s9s_mb_2u_lib.s9s_mb_2u(sch_1):page532_i156@pure_quanta.q_res(chips)"
			("LOCATION" "R576")
		)
		("@s9s_mb_2u_lib.s9s_mb_2u(sch_1):page532_i418@pure_quanta.q_res(chips)"
			("LOCATION" "R1542")
		)
		("@s9s_mb_2u_lib.s9s_mb_2u(sch_1):page532_i411@pure_quanta.q_res(chips)"
			("LOCATION" "R1543")
		)
		("@s9s_mb_2u_lib.s9s_mb_2u(sch_1):page532_i416@pure_quanta.q_res(chips)"
			("LOCATION" "R1544")
		)
		("@s9s_mb_2u_lib.s9s_mb_2u(sch_1):page532_i119@pure_quanta.\\9qxl2001bnhgi8\\(chips)"
			("LOCATION" "U38")
		)
		("@s9s_mb_2u_lib.s9s_mb_2u(sch_1):page615_i27@pure_quanta.q_cap(chips)"
			("LOCATION" "C221")
		)
		("@s9s_mb_2u_lib.s9s_mb_2u(sch_1):page615_i25@pure_quanta.q_cap(chips)"
			("LOCATION" "C222")
		)
		("@s9s_mb_2u_lib.s9s_mb_2u(sch_1):page615_i23@pure_quanta.q_cap(chips)"
			("LOCATION" "C223")
		)
		("@s9s_mb_2u_lib.s9s_mb_2u(sch_1):page615_i15@pure_quanta.q_cap(chips)"
			("LOCATION" "C224")
		)
		("@s9s_mb_2u_lib.s9s_mb_2u(sch_1):page615_i13@pure_quanta.q_cap(chips)"
			("LOCATION" "C225")
		)
		("@s9s_mb_2u_lib.s9s_mb_2u(sch_1):page615_i31@pure_quanta.q_cap(chips)"
			("LOCATION" "C226")
		)
		("@s9s_mb_2u_lib.s9s_mb_2u(sch_1):page615_i30@pure_quanta.q_cap(chips)"
			("LOCATION" "C227")
		)
		("@s9s_mb_2u_lib.s9s_mb_2u(sch_1):page615_i28@pure_quanta.q_cap(chips)"
			("LOCATION" "C228")
		)
		("@s9s_mb_2u_lib.s9s_mb_2u(sch_1):page615_i21@pure_quanta.q_cap(chips)"
			("LOCATION" "C229")
		)
		("@s9s_mb_2u_lib.s9s_mb_2u(sch_1):page615_i18@pure_quanta.q_cap(chips)"
			("LOCATION" "C230")
		)
		("@s9s_mb_2u_lib.s9s_mb_2u(sch_1):page615_i33@pure_quanta.q_cap(chips)"
			("LOCATION" "C231")
		)
		("@s9s_mb_2u_lib.s9s_mb_2u(sch_1):page615_i32@pure_quanta.q_cap(chips)"
			("LOCATION" "C232")
		)
		("@s9s_mb_2u_lib.s9s_mb_2u(sch_1):page615_i29@pure_quanta.q_cap(chips)"
			("LOCATION" "C233")
		)
		("@s9s_mb_2u_lib.s9s_mb_2u(sch_1):page615_i22@pure_quanta.q_cap(chips)"
			("LOCATION" "C234")
		)
		("@s9s_mb_2u_lib.s9s_mb_2u(sch_1):page615_i20@pure_quanta.q_cap(chips)"
			("LOCATION" "C235")
		)
		("@s9s_mb_2u_lib.s9s_mb_2u(sch_1):page615_i52@pure_quanta.q_cap(chips)"
			("LOCATION" "C236")
		)
		("@s9s_mb_2u_lib.s9s_mb_2u(sch_1):page615_i51@pure_quanta.q_cap(chips)"
			("LOCATION" "C237")
		)
		("@s9s_mb_2u_lib.s9s_mb_2u(sch_1):page615_i49@pure_quanta.q_cap(chips)"
			("LOCATION" "C238")
		)
		("@s9s_mb_2u_lib.s9s_mb_2u(sch_1):page615_i37@pure_quanta.q_cap(chips)"
			("LOCATION" "C239")
		)
		("@s9s_mb_2u_lib.s9s_mb_2u(sch_1):page615_i35@pure_quanta.q_cap(chips)"
			("LOCATION" "C240")
		)
		("@s9s_mb_2u_lib.s9s_mb_2u(sch_1):page615_i54@pure_quanta.q_cap(chips)"
			("LOCATION" "C241")
		)
		("@s9s_mb_2u_lib.s9s_mb_2u(sch_1):page615_i53@pure_quanta.q_cap(chips)"
			("LOCATION" "C242")
		)
		("@s9s_mb_2u_lib.s9s_mb_2u(sch_1):page615_i50@pure_quanta.q_cap(chips)"
			("LOCATION" "C243")
		)
		("@s9s_mb_2u_lib.s9s_mb_2u(sch_1):page615_i38@pure_quanta.q_cap(chips)"
			("LOCATION" "C244")
		)
		("@s9s_mb_2u_lib.s9s_mb_2u(sch_1):page615_i36@pure_quanta.q_cap(chips)"
			("LOCATION" "C245")
		)
		("@s9s_mb_2u_lib.s9s_mb_2u(sch_1):page615_i59@pure_quanta.q_cap(chips)"
			("LOCATION" "C246")
		)
		("@s9s_mb_2u_lib.s9s_mb_2u(sch_1):page615_i58@pure_quanta.q_cap(chips)"
			("LOCATION" "C247")
		)
		("@s9s_mb_2u_lib.s9s_mb_2u(sch_1):page615_i55@pure_quanta.q_cap(chips)"
			("LOCATION" "C248")
		)
		("@s9s_mb_2u_lib.s9s_mb_2u(sch_1):page615_i46@pure_quanta.q_cap(chips)"
			("LOCATION" "C249")
		)
		("@s9s_mb_2u_lib.s9s_mb_2u(sch_1):page615_i41@pure_quanta.q_cap(chips)"
			("LOCATION" "C250")
		)
		("@s9s_mb_2u_lib.s9s_mb_2u(sch_1):page615_i61@pure_quanta.q_cap(chips)"
			("LOCATION" "C251")
		)
		("@s9s_mb_2u_lib.s9s_mb_2u(sch_1):page615_i60@pure_quanta.q_cap(chips)"
			("LOCATION" "C252")
		)
		("@s9s_mb_2u_lib.s9s_mb_2u(sch_1):page615_i56@pure_quanta.q_cap(chips)"
			("LOCATION" "C253")
		)
		("@s9s_mb_2u_lib.s9s_mb_2u(sch_1):page615_i47@pure_quanta.q_cap(chips)"
			("LOCATION" "C254")
		)
		("@s9s_mb_2u_lib.s9s_mb_2u(sch_1):page615_i44@pure_quanta.q_cap(chips)"
			("LOCATION" "C255")
		)
		("@s9s_mb_2u_lib.s9s_mb_2u(sch_1):page615_i63@pure_quanta.q_cap(chips)"
			("LOCATION" "C256")
		)
		("@s9s_mb_2u_lib.s9s_mb_2u(sch_1):page615_i62@pure_quanta.q_cap(chips)"
			("LOCATION" "C257")
		)
		("@s9s_mb_2u_lib.s9s_mb_2u(sch_1):page615_i57@pure_quanta.q_cap(chips)"
			("LOCATION" "C258")
		)
		("@s9s_mb_2u_lib.s9s_mb_2u(sch_1):page615_i48@pure_quanta.q_cap(chips)"
			("LOCATION" "C259")
		)
		("@s9s_mb_2u_lib.s9s_mb_2u(sch_1):page615_i45@pure_quanta.q_cap(chips)"
			("LOCATION" "C260")
		)
		("@s9s_mb_2u_lib.s9s_mb_2u(sch_1):page615_i89@pure_quanta.q_cap(chips)"
			("LOCATION" "C261")
		)
		("@s9s_mb_2u_lib.s9s_mb_2u(sch_1):page615_i88@pure_quanta.q_cap(chips)"
			("LOCATION" "C262")
		)
		("@s9s_mb_2u_lib.s9s_mb_2u(sch_1):page615_i84@pure_quanta.q_cap(chips)"
			("LOCATION" "C263")
		)
		("@s9s_mb_2u_lib.s9s_mb_2u(sch_1):page615_i76@pure_quanta.q_cap(chips)"
			("LOCATION" "C264")
		)
		("@s9s_mb_2u_lib.s9s_mb_2u(sch_1):page615_i72@pure_quanta.q_cap(chips)"
			("LOCATION" "C265")
		)
		("@s9s_mb_2u_lib.s9s_mb_2u(sch_1):page615_i92@pure_quanta.q_cap(chips)"
			("LOCATION" "C266")
		)
		("@s9s_mb_2u_lib.s9s_mb_2u(sch_1):page615_i90@pure_quanta.q_cap(chips)"
			("LOCATION" "C267")
		)
		("@s9s_mb_2u_lib.s9s_mb_2u(sch_1):page615_i86@pure_quanta.q_cap(chips)"
			("LOCATION" "C268")
		)
		("@s9s_mb_2u_lib.s9s_mb_2u(sch_1):page615_i78@pure_quanta.q_cap(chips)"
			("LOCATION" "C269")
		)
		("@s9s_mb_2u_lib.s9s_mb_2u(sch_1):page615_i75@pure_quanta.q_cap(chips)"
			("LOCATION" "C270")
		)
		("@s9s_mb_2u_lib.s9s_mb_2u(sch_1):page615_i98@pure_quanta.q_cap(chips)"
			("LOCATION" "C271")
		)
		("@s9s_mb_2u_lib.s9s_mb_2u(sch_1):page615_i96@pure_quanta.q_cap(chips)"
			("LOCATION" "C272")
		)
		("@s9s_mb_2u_lib.s9s_mb_2u(sch_1):page615_i93@pure_quanta.q_cap(chips)"
			("LOCATION" "C273")
		)
		("@s9s_mb_2u_lib.s9s_mb_2u(sch_1):page615_i81@pure_quanta.q_cap(chips)"
			("LOCATION" "C274")
		)
		("@s9s_mb_2u_lib.s9s_mb_2u(sch_1):page615_i100@pure_quanta.q_cap(chips)"
			("LOCATION" "C275")
		)
		("@s9s_mb_2u_lib.s9s_mb_2u(sch_1):page615_i99@pure_quanta.q_cap(chips)"
			("LOCATION" "C276")
		)
		("@s9s_mb_2u_lib.s9s_mb_2u(sch_1):page615_i95@pure_quanta.q_cap(chips)"
			("LOCATION" "C277")
		)
		("@s9s_mb_2u_lib.s9s_mb_2u(sch_1):page615_i83@pure_quanta.q_cap(chips)"
			("LOCATION" "C278")
		)
		("@s9s_mb_2u_lib.s9s_mb_2u(sch_1):page615_i112@pure_quanta.q_cap(chips)"
			("LOCATION" "C279")
		)
		("@s9s_mb_2u_lib.s9s_mb_2u(sch_1):page615_i111@pure_quanta.q_cap(chips)"
			("LOCATION" "C280")
		)
		("@s9s_mb_2u_lib.s9s_mb_2u(sch_1):page615_i109@pure_quanta.q_cap(chips)"
			("LOCATION" "C281")
		)
		("@s9s_mb_2u_lib.s9s_mb_2u(sch_1):page615_i103@pure_quanta.q_cap(chips)"
			("LOCATION" "C282")
		)
		("@s9s_mb_2u_lib.s9s_mb_2u(sch_1):page615_i114@pure_quanta.q_cap(chips)"
			("LOCATION" "C283")
		)
		("@s9s_mb_2u_lib.s9s_mb_2u(sch_1):page615_i113@pure_quanta.q_cap(chips)"
			("LOCATION" "C284")
		)
		("@s9s_mb_2u_lib.s9s_mb_2u(sch_1):page615_i110@pure_quanta.q_cap(chips)"
			("LOCATION" "C285")
		)
		("@s9s_mb_2u_lib.s9s_mb_2u(sch_1):page615_i104@pure_quanta.q_cap(chips)"
			("LOCATION" "C286")
		)
		("@s9s_mb_2u_lib.s9s_mb_2u(sch_1):page615_i120@pure_quanta.q_cap(chips)"
			("LOCATION" "C287")
		)
		("@s9s_mb_2u_lib.s9s_mb_2u(sch_1):page615_i118@pure_quanta.q_cap(chips)"
			("LOCATION" "C288")
		)
		("@s9s_mb_2u_lib.s9s_mb_2u(sch_1):page615_i115@pure_quanta.q_cap(chips)"
			("LOCATION" "C289")
		)
		("@s9s_mb_2u_lib.s9s_mb_2u(sch_1):page615_i106@pure_quanta.q_cap(chips)"
			("LOCATION" "C290")
		)
		("@s9s_mb_2u_lib.s9s_mb_2u(sch_1):page615_i121@pure_quanta.q_cap(chips)"
			("LOCATION" "C291")
		)
		("@s9s_mb_2u_lib.s9s_mb_2u(sch_1):page615_i119@pure_quanta.q_cap(chips)"
			("LOCATION" "C292")
		)
		("@s9s_mb_2u_lib.s9s_mb_2u(sch_1):page615_i116@pure_quanta.q_cap(chips)"
			("LOCATION" "C293")
		)
		("@s9s_mb_2u_lib.s9s_mb_2u(sch_1):page615_i107@pure_quanta.q_cap(chips)"
			("LOCATION" "C294")
		)
		("@s9s_mb_2u_lib.s9s_mb_2u(sch_1):page615_i123@pure_quanta.q_cap(chips)"
			("LOCATION" "C295")
		)
		("@s9s_mb_2u_lib.s9s_mb_2u(sch_1):page615_i122@pure_quanta.q_cap(chips)"
			("LOCATION" "C296")
		)
		("@s9s_mb_2u_lib.s9s_mb_2u(sch_1):page615_i117@pure_quanta.q_cap(chips)"
			("LOCATION" "C297")
		)
		("@s9s_mb_2u_lib.s9s_mb_2u(sch_1):page615_i108@pure_quanta.q_cap(chips)"
			("LOCATION" "C298")
		)
		("@s9s_mb_2u_lib.s9s_mb_2u(sch_1):page615_i132@pure_quanta.q_cap(chips)"
			("LOCATION" "C299")
		)
		("@s9s_mb_2u_lib.s9s_mb_2u(sch_1):page615_i131@pure_quanta.q_cap(chips)"
			("LOCATION" "C300")
		)
		("@s9s_mb_2u_lib.s9s_mb_2u(sch_1):page615_i129@pure_quanta.q_cap(chips)"
			("LOCATION" "C301")
		)
		("@s9s_mb_2u_lib.s9s_mb_2u(sch_1):page615_i125@pure_quanta.q_cap(chips)"
			("LOCATION" "C302")
		)
		("@s9s_mb_2u_lib.s9s_mb_2u(sch_1):page615_i134@pure_quanta.q_cap(chips)"
			("LOCATION" "C303")
		)
		("@s9s_mb_2u_lib.s9s_mb_2u(sch_1):page615_i133@pure_quanta.q_cap(chips)"
			("LOCATION" "C304")
		)
		("@s9s_mb_2u_lib.s9s_mb_2u(sch_1):page615_i130@pure_quanta.q_cap(chips)"
			("LOCATION" "C305")
		)
		("@s9s_mb_2u_lib.s9s_mb_2u(sch_1):page615_i126@pure_quanta.q_cap(chips)"
			("LOCATION" "C306")
		)
		("@s9s_mb_2u_lib.s9s_mb_2u(sch_1):page615_i140@pure_quanta.q_cap(chips)"
			("LOCATION" "C307")
		)
		("@s9s_mb_2u_lib.s9s_mb_2u(sch_1):page615_i138@pure_quanta.q_cap(chips)"
			("LOCATION" "C308")
		)
		("@s9s_mb_2u_lib.s9s_mb_2u(sch_1):page615_i136@pure_quanta.q_cap(chips)"
			("LOCATION" "C309")
		)
		("@s9s_mb_2u_lib.s9s_mb_2u(sch_1):page615_i148@pure_quanta.q_cap(chips)"
			("LOCATION" "C310")
		)
		("@s9s_mb_2u_lib.s9s_mb_2u(sch_1):page615_i11@pure_quanta.q_cap(chips)"
			("LOCATION" "C423")
		)
		("@s9s_mb_2u_lib.s9s_mb_2u(sch_1):page615_i1@pure_quanta.q_cap(chips)"
			("LOCATION" "C424")
		)
		("@s9s_mb_2u_lib.s9s_mb_2u(sch_1):page615_i17@pure_quanta.q_cap(chips)"
			("LOCATION" "C425")
		)
		("@s9s_mb_2u_lib.s9s_mb_2u(sch_1):page615_i3@pure_quanta.q_cap(chips)"
			("LOCATION" "C426")
		)
		("@s9s_mb_2u_lib.s9s_mb_2u(sch_1):page615_i19@pure_quanta.q_cap(chips)"
			("LOCATION" "C427")
		)
		("@s9s_mb_2u_lib.s9s_mb_2u(sch_1):page615_i4@pure_quanta.q_cap(chips)"
			("LOCATION" "C428")
		)
		("@s9s_mb_2u_lib.s9s_mb_2u(sch_1):page615_i34@pure_quanta.q_cap(chips)"
			("LOCATION" "C429")
		)
		("@s9s_mb_2u_lib.s9s_mb_2u(sch_1):page615_i5@pure_quanta.q_cap(chips)"
			("LOCATION" "C430")
		)
		("@s9s_mb_2u_lib.s9s_mb_2u(sch_1):page615_i7@pure_quanta.q_cap(chips)"
			("LOCATION" "C431")
		)
		("@s9s_mb_2u_lib.s9s_mb_2u(sch_1):page615_i39@pure_quanta.q_cap(chips)"
			("LOCATION" "C432")
		)
		("@s9s_mb_2u_lib.s9s_mb_2u(sch_1):page615_i8@pure_quanta.q_cap(chips)"
			("LOCATION" "C433")
		)
		("@s9s_mb_2u_lib.s9s_mb_2u(sch_1):page615_i42@pure_quanta.q_cap(chips)"
			("LOCATION" "C434")
		)
		("@s9s_mb_2u_lib.s9s_mb_2u(sch_1):page615_i9@pure_quanta.q_cap(chips)"
			("LOCATION" "C435")
		)
		("@s9s_mb_2u_lib.s9s_mb_2u(sch_1):page615_i43@pure_quanta.q_cap(chips)"
			("LOCATION" "C436")
		)
		("@s9s_mb_2u_lib.s9s_mb_2u(sch_1):page615_i10@pure_quanta.q_cap(chips)"
			("LOCATION" "C437")
		)
		("@s9s_mb_2u_lib.s9s_mb_2u(sch_1):page615_i71@pure_quanta.q_cap(chips)"
			("LOCATION" "C438")
		)
		("@s9s_mb_2u_lib.s9s_mb_2u(sch_1):page615_i65@pure_quanta.q_cap(chips)"
			("LOCATION" "C439")
		)
		("@s9s_mb_2u_lib.s9s_mb_2u(sch_1):page615_i73@pure_quanta.q_cap(chips)"
			("LOCATION" "C440")
		)
		("@s9s_mb_2u_lib.s9s_mb_2u(sch_1):page615_i66@pure_quanta.q_cap(chips)"
			("LOCATION" "C441")
		)
		("@s9s_mb_2u_lib.s9s_mb_2u(sch_1):page615_i69@pure_quanta.q_cap(chips)"
			("LOCATION" "C442")
		)
		("@s9s_mb_2u_lib.s9s_mb_2u(sch_1):page615_i79@pure_quanta.q_cap(chips)"
			("LOCATION" "C443")
		)
		("@s9s_mb_2u_lib.s9s_mb_2u(sch_1):page615_i101@pure_quanta.q_cap(chips)"
			("LOCATION" "C444")
		)
		("@s9s_mb_2u_lib.s9s_mb_2u(sch_1):page615_i102@pure_quanta.q_cap(chips)"
			("LOCATION" "C445")
		)
		("@s9s_mb_2u_lib.s9s_mb_2u(sch_1):page615_i105@pure_quanta.q_cap(chips)"
			("LOCATION" "C446")
		)
		("@s9s_mb_2u_lib.s9s_mb_2u(sch_1):page616_i35@pure_quanta.q_cap(chips)"
			("LOCATION" "C311")
		)
		("@s9s_mb_2u_lib.s9s_mb_2u(sch_1):page616_i32@pure_quanta.q_cap(chips)"
			("LOCATION" "C312")
		)
		("@s9s_mb_2u_lib.s9s_mb_2u(sch_1):page616_i128@pure_quanta.q_cap(chips)"
			("LOCATION" "C313")
		)
		("@s9s_mb_2u_lib.s9s_mb_2u(sch_1):page616_i40@pure_quanta.q_cap(chips)"
			("LOCATION" "C314")
		)
		("@s9s_mb_2u_lib.s9s_mb_2u(sch_1):page616_i37@pure_quanta.q_cap(chips)"
			("LOCATION" "C315")
		)
		("@s9s_mb_2u_lib.s9s_mb_2u(sch_1):page616_i129@pure_quanta.q_cap(chips)"
			("LOCATION" "C316")
		)
		("@s9s_mb_2u_lib.s9s_mb_2u(sch_1):page616_i41@pure_quanta.q_cap(chips)"
			("LOCATION" "C317")
		)
		("@s9s_mb_2u_lib.s9s_mb_2u(sch_1):page616_i39@pure_quanta.q_cap(chips)"
			("LOCATION" "C318")
		)
		("@s9s_mb_2u_lib.s9s_mb_2u(sch_1):page616_i59@pure_quanta.q_cap(chips)"
			("LOCATION" "C320")
		)
		("@s9s_mb_2u_lib.s9s_mb_2u(sch_1):page616_i56@pure_quanta.q_cap(chips)"
			("LOCATION" "C321")
		)
		("@s9s_mb_2u_lib.s9s_mb_2u(sch_1):page616_i60@pure_quanta.q_cap(chips)"
			("LOCATION" "C323")
		)
		("@s9s_mb_2u_lib.s9s_mb_2u(sch_1):page616_i58@pure_quanta.q_cap(chips)"
			("LOCATION" "C324")
		)
		("@s9s_mb_2u_lib.s9s_mb_2u(sch_1):page616_i67@pure_quanta.q_cap(chips)"
			("LOCATION" "C326")
		)
		("@s9s_mb_2u_lib.s9s_mb_2u(sch_1):page616_i62@pure_quanta.q_cap(chips)"
			("LOCATION" "C327")
		)
		("@s9s_mb_2u_lib.s9s_mb_2u(sch_1):page616_i68@pure_quanta.q_cap(chips)"
			("LOCATION" "C329")
		)
		("@s9s_mb_2u_lib.s9s_mb_2u(sch_1):page616_i65@pure_quanta.q_cap(chips)"
			("LOCATION" "C330")
		)
		("@s9s_mb_2u_lib.s9s_mb_2u(sch_1):page616_i69@pure_quanta.q_cap(chips)"
			("LOCATION" "C332")
		)
		("@s9s_mb_2u_lib.s9s_mb_2u(sch_1):page616_i66@pure_quanta.q_cap(chips)"
			("LOCATION" "C333")
		)
		("@s9s_mb_2u_lib.s9s_mb_2u(sch_1):page616_i80@pure_quanta.q_cap(chips)"
			("LOCATION" "C335")
		)
		("@s9s_mb_2u_lib.s9s_mb_2u(sch_1):page616_i76@pure_quanta.q_cap(chips)"
			("LOCATION" "C336")
		)
		("@s9s_mb_2u_lib.s9s_mb_2u(sch_1):page616_i121@pure_quanta.q_cap(chips)"
			("LOCATION" "C337")
		)
		("@s9s_mb_2u_lib.s9s_mb_2u(sch_1):page616_i82@pure_quanta.q_cap(chips)"
			("LOCATION" "C338")
		)
		("@s9s_mb_2u_lib.s9s_mb_2u(sch_1):page616_i79@pure_quanta.q_cap(chips)"
			("LOCATION" "C339")
		)
		("@s9s_mb_2u_lib.s9s_mb_2u(sch_1):page616_i120@pure_quanta.q_cap(chips)"
			("LOCATION" "C340")
		)
		("@s9s_mb_2u_lib.s9s_mb_2u(sch_1):page616_i124@pure_quanta.q_cap(chips)"
			("LOCATION" "C349")
		)
		("@s9s_mb_2u_lib.s9s_mb_2u(sch_1):page616_i126@pure_quanta.q_cap(chips)"
			("LOCATION" "C351")
		)
		("@s9s_mb_2u_lib.s9s_mb_2u(sch_1):page616_i125@pure_quanta.q_cap(chips)"
			("LOCATION" "C353")
		)
		("@s9s_mb_2u_lib.s9s_mb_2u(sch_1):page616_i24@pure_quanta.q_cap(chips)"
			("LOCATION" "C447")
		)
		("@s9s_mb_2u_lib.s9s_mb_2u(sch_1):page616_i23@pure_quanta.q_cap(chips)"
			("LOCATION" "C448")
		)
		("@s9s_mb_2u_lib.s9s_mb_2u(sch_1):page616_i3@pure_quanta.q_cap(chips)"
			("LOCATION" "C449")
		)
		("@s9s_mb_2u_lib.s9s_mb_2u(sch_1):page616_i29@pure_quanta.q_cap(chips)"
			("LOCATION" "C451")
		)
		("@s9s_mb_2u_lib.s9s_mb_2u(sch_1):page616_i27@pure_quanta.q_cap(chips)"
			("LOCATION" "C452")
		)
		("@s9s_mb_2u_lib.s9s_mb_2u(sch_1):page616_i5@pure_quanta.q_cap(chips)"
			("LOCATION" "C453")
		)
		("@s9s_mb_2u_lib.s9s_mb_2u(sch_1):page616_i7@pure_quanta.q_cap(chips)"
			("LOCATION" "C457")
		)
		("@s9s_mb_2u_lib.s9s_mb_2u(sch_1):page616_i9@pure_quanta.q_cap(chips)"
			("LOCATION" "C461")
		)
		("@s9s_mb_2u_lib.s9s_mb_2u(sch_1):page616_i11@pure_quanta.q_cap(chips)"
			("LOCATION" "C465")
		)
		("@s9s_mb_2u_lib.s9s_mb_2u(sch_1):page616_i52@pure_quanta.q_cap(chips)"
			("LOCATION" "C471")
		)
		("@s9s_mb_2u_lib.s9s_mb_2u(sch_1):page616_i54@pure_quanta.q_cap(chips)"
			("LOCATION" "C474")
		)
		("@s9s_mb_2u_lib.s9s_mb_2u(sch_1):page616_i70@pure_quanta.q_cap(chips)"
			("LOCATION" "C478")
		)
		("@s9s_mb_2u_lib.s9s_mb_2u(sch_1):page616_i119@pure_quanta.q_cap(chips)"
			("LOCATION" "C480")
		)
		("@s9s_mb_2u_lib.s9s_mb_2u(sch_1):page616_i118@pure_quanta.q_cap(chips)"
			("LOCATION" "C483")
		)
		("@s9s_mb_2u_lib.s9s_mb_2u(sch_1):page616_i134@pure_quanta.q_cap(chips)"
			("LOCATION" "C488")
		)
		("@s9s_mb_2u_lib.s9s_mb_2u(sch_1):page616_i133@pure_quanta.q_cap(chips)"
			("LOCATION" "C489")
		)
		("@s9s_mb_2u_lib.s9s_mb_2u(sch_1):page616_i132@pure_quanta.q_cap(chips)"
			("LOCATION" "C490")
		)
		("@s9s_mb_2u_lib.s9s_mb_2u(sch_1):page616_i141@pure_quanta.q_cap(chips)"
			("LOCATION" "C1387")
		)
		("@s9s_mb_2u_lib.s9s_mb_2u(sch_1):page616_i139@pure_quanta.q_cap(chips)"
			("LOCATION" "C1388")
		)
		("@s9s_mb_2u_lib.s9s_mb_2u(sch_1):page616_i143@pure_quanta.q_cap(chips)"
			("LOCATION" "C1389")
		)
		("@s9s_mb_2u_lib.s9s_mb_2u(sch_1):page616_i140@pure_quanta.q_cap(chips)"
			("LOCATION" "C1390")
		)
		("@s9s_mb_2u_lib.s9s_mb_2u(sch_1):page616_i147@pure_quanta.q_cap(chips)"
			("LOCATION" "C1391")
		)
		("@s9s_mb_2u_lib.s9s_mb_2u(sch_1):page616_i145@pure_quanta.q_cap(chips)"
			("LOCATION" "C1392")
		)
		("@s9s_mb_2u_lib.s9s_mb_2u(sch_1):page616_i148@pure_quanta.q_cap(chips)"
			("LOCATION" "C1393")
		)
		("@s9s_mb_2u_lib.s9s_mb_2u(sch_1):page79_i115@pure_quanta.q_cap(chips)"
			("LOCATION" "C322")
		)
		("@s9s_mb_2u_lib.s9s_mb_2u(sch_1):page79_i114@pure_quanta.q_cap(chips)"
			("LOCATION" "C325")
		)
		("@s9s_mb_2u_lib.s9s_mb_2u(sch_1):page79_i112@pure_quanta.q_cap(chips)"
			("LOCATION" "C328")
		)
		("@s9s_mb_2u_lib.s9s_mb_2u(sch_1):page79_i125@pure_quanta.q_cap(chips)"
			("LOCATION" "C341")
		)
		("@s9s_mb_2u_lib.s9s_mb_2u(sch_1):page79_i109@pure_quanta.q_cap(chips)"
			("LOCATION" "C342")
		)
		("@s9s_mb_2u_lib.s9s_mb_2u(sch_1):page79_i124@pure_quanta.q_cap(chips)"
			("LOCATION" "C343")
		)
		("@s9s_mb_2u_lib.s9s_mb_2u(sch_1):page79_i110@pure_quanta.q_cap(chips)"
			("LOCATION" "C344")
		)
		("@s9s_mb_2u_lib.s9s_mb_2u(sch_1):page79_i123@pure_quanta.q_cap(chips)"
			("LOCATION" "C345")
		)
		("@s9s_mb_2u_lib.s9s_mb_2u(sch_1):page79_i111@pure_quanta.q_cap(chips)"
			("LOCATION" "C346")
		)
		("@s9s_mb_2u_lib.s9s_mb_2u(sch_1):page79_i122@pure_quanta.q_cap(chips)"
			("LOCATION" "C347")
		)
		("@s9s_mb_2u_lib.s9s_mb_2u(sch_1):page79_i119@pure_quanta.q_cap(chips)"
			("LOCATION" "C348")
		)
		("@s9s_mb_2u_lib.s9s_mb_2u(sch_1):page79_i118@pure_quanta.q_cap(chips)"
			("LOCATION" "C350")
		)
		("@s9s_mb_2u_lib.s9s_mb_2u(sch_1):page79_i117@pure_quanta.q_cap(chips)"
			("LOCATION" "C352")
		)
		("@s9s_mb_2u_lib.s9s_mb_2u(sch_1):page79_i116@pure_quanta.q_cap(chips)"
			("LOCATION" "C354")
		)
		("@s9s_mb_2u_lib.s9s_mb_2u(sch_1):page79_i1@pure_quanta.q_cap(chips)"
			("LOCATION" "C450")
		)
		("@s9s_mb_2u_lib.s9s_mb_2u(sch_1):page79_i3@pure_quanta.q_cap(chips)"
			("LOCATION" "C454")
		)
		("@s9s_mb_2u_lib.s9s_mb_2u(sch_1):page79_i129@pure_quanta.q_cap(chips)"
			("LOCATION" "C455")
		)
		("@s9s_mb_2u_lib.s9s_mb_2u(sch_1):page79_i136@pure_quanta.q_cap(chips)"
			("LOCATION" "C456")
		)
		("@s9s_mb_2u_lib.s9s_mb_2u(sch_1):page79_i4@pure_quanta.q_cap(chips)"
			("LOCATION" "C458")
		)
		("@s9s_mb_2u_lib.s9s_mb_2u(sch_1):page79_i128@pure_quanta.q_cap(chips)"
			("LOCATION" "C459")
		)
		("@s9s_mb_2u_lib.s9s_mb_2u(sch_1):page79_i135@pure_quanta.q_cap(chips)"
			("LOCATION" "C460")
		)
		("@s9s_mb_2u_lib.s9s_mb_2u(sch_1):page79_i5@pure_quanta.q_cap(chips)"
			("LOCATION" "C462")
		)
		("@s9s_mb_2u_lib.s9s_mb_2u(sch_1):page79_i127@pure_quanta.q_cap(chips)"
			("LOCATION" "C463")
		)
		("@s9s_mb_2u_lib.s9s_mb_2u(sch_1):page79_i134@pure_quanta.q_cap(chips)"
			("LOCATION" "C464")
		)
		("@s9s_mb_2u_lib.s9s_mb_2u(sch_1):page79_i6@pure_quanta.q_cap(chips)"
			("LOCATION" "C466")
		)
		("@s9s_mb_2u_lib.s9s_mb_2u(sch_1):page79_i126@pure_quanta.q_cap(chips)"
			("LOCATION" "C467")
		)
		("@s9s_mb_2u_lib.s9s_mb_2u(sch_1):page79_i133@pure_quanta.q_cap(chips)"
			("LOCATION" "C468")
		)
		("@s9s_mb_2u_lib.s9s_mb_2u(sch_1):page79_i7@pure_quanta.q_cap(chips)"
			("LOCATION" "C470")
		)
		("@s9s_mb_2u_lib.s9s_mb_2u(sch_1):page79_i132@pure_quanta.q_cap(chips)"
			("LOCATION" "C472")
		)
		("@s9s_mb_2u_lib.s9s_mb_2u(sch_1):page79_i8@pure_quanta.q_cap(chips)"
			("LOCATION" "C473")
		)
		("@s9s_mb_2u_lib.s9s_mb_2u(sch_1):page79_i131@pure_quanta.q_cap(chips)"
			("LOCATION" "C475")
		)
		("@s9s_mb_2u_lib.s9s_mb_2u(sch_1):page79_i9@pure_quanta.q_cap(chips)"
			("LOCATION" "C476")
		)
		("@s9s_mb_2u_lib.s9s_mb_2u(sch_1):page79_i10@pure_quanta.q_cap(chips)"
			("LOCATION" "C477")
		)
		("@s9s_mb_2u_lib.s9s_mb_2u(sch_1):page79_i11@pure_quanta.q_cap(chips)"
			("LOCATION" "C479")
		)
		("@s9s_mb_2u_lib.s9s_mb_2u(sch_1):page79_i77@pure_quanta.q_cap(chips)"
			("LOCATION" "C481")
		)
		("@s9s_mb_2u_lib.s9s_mb_2u(sch_1):page79_i74@pure_quanta.q_cap(chips)"
			("LOCATION" "C482")
		)
		("@s9s_mb_2u_lib.s9s_mb_2u(sch_1):page79_i78@pure_quanta.q_cap(chips)"
			("LOCATION" "C484")
		)
		("@s9s_mb_2u_lib.s9s_mb_2u(sch_1):page79_i76@pure_quanta.q_cap(chips)"
			("LOCATION" "C485")
		)
		("@s9s_mb_2u_lib.s9s_mb_2u(sch_1):page79_i79@pure_quanta.q_cap(chips)"
			("LOCATION" "C486")
		)
		("@s9s_mb_2u_lib.s9s_mb_2u(sch_1):page79_i80@pure_quanta.q_cap(chips)"
			("LOCATION" "C487")
		)
		("@s9s_mb_2u_lib.s9s_mb_2u(sch_1):page79_i149@pure_quanta.q_cap(chips)"
			("LOCATION" "C1353")
		)
		("@s9s_mb_2u_lib.s9s_mb_2u(sch_1):page79_i146@pure_quanta.q_cap(chips)"
			("LOCATION" "C1403")
		)
		("@s9s_mb_2u_lib.s9s_mb_2u(sch_1):page79_i147@pure_quanta.q_cap(chips)"
			("LOCATION" "C1404")
		)
		("@s9s_mb_2u_lib.s9s_mb_2u(sch_1):page365_i22@pure_quanta.q_cap(chips)"
			("LOCATION" "C355")
		)
		("@s9s_mb_2u_lib.s9s_mb_2u(sch_1):page365_i20@pure_quanta.q_cap(chips)"
			("LOCATION" "C356")
		)
		("@s9s_mb_2u_lib.s9s_mb_2u(sch_1):page365_i237@pure_quanta.q_cap(chips)"
			("LOCATION" "C357")
		)
		("@s9s_mb_2u_lib.s9s_mb_2u(sch_1):page365_i26@pure_quanta.q_cap(chips)"
			("LOCATION" "C358")
		)
		("@s9s_mb_2u_lib.s9s_mb_2u(sch_1):page365_i25@pure_quanta.q_cap(chips)"
			("LOCATION" "C359")
		)
		("@s9s_mb_2u_lib.s9s_mb_2u(sch_1):page365_i234@pure_quanta.q_cap(chips)"
			("LOCATION" "C360")
		)
		("@s9s_mb_2u_lib.s9s_mb_2u(sch_1):page365_i28@pure_quanta.q_cap(chips)"
			("LOCATION" "C361")
		)
		("@s9s_mb_2u_lib.s9s_mb_2u(sch_1):page365_i27@pure_quanta.q_cap(chips)"
			("LOCATION" "C362")
		)
		("@s9s_mb_2u_lib.s9s_mb_2u(sch_1):page365_i232@pure_quanta.q_cap(chips)"
			("LOCATION" "C363")
		)
		("@s9s_mb_2u_lib.s9s_mb_2u(sch_1):page365_i43@pure_quanta.q_cap(chips)"
			("LOCATION" "C364")
		)
		("@s9s_mb_2u_lib.s9s_mb_2u(sch_1):page365_i42@pure_quanta.q_cap(chips)"
			("LOCATION" "C365")
		)
		("@s9s_mb_2u_lib.s9s_mb_2u(sch_1):page365_i45@pure_quanta.q_cap(chips)"
			("LOCATION" "C367")
		)
		("@s9s_mb_2u_lib.s9s_mb_2u(sch_1):page365_i44@pure_quanta.q_cap(chips)"
			("LOCATION" "C368")
		)
		("@s9s_mb_2u_lib.s9s_mb_2u(sch_1):page365_i50@pure_quanta.q_cap(chips)"
			("LOCATION" "C370")
		)
		("@s9s_mb_2u_lib.s9s_mb_2u(sch_1):page365_i49@pure_quanta.q_cap(chips)"
			("LOCATION" "C371")
		)
		("@s9s_mb_2u_lib.s9s_mb_2u(sch_1):page365_i52@pure_quanta.q_cap(chips)"
			("LOCATION" "C373")
		)
		("@s9s_mb_2u_lib.s9s_mb_2u(sch_1):page365_i54@pure_quanta.q_cap(chips)"
			("LOCATION" "C376")
		)
		("@s9s_mb_2u_lib.s9s_mb_2u(sch_1):page365_i77@pure_quanta.q_cap(chips)"
			("LOCATION" "C379")
		)
		("@s9s_mb_2u_lib.s9s_mb_2u(sch_1):page365_i189@pure_quanta.q_cap(chips)"
			("LOCATION" "C381")
		)
		("@s9s_mb_2u_lib.s9s_mb_2u(sch_1):page365_i80@pure_quanta.q_cap(chips)"
			("LOCATION" "C382")
		)
		("@s9s_mb_2u_lib.s9s_mb_2u(sch_1):page365_i187@pure_quanta.q_cap(chips)"
			("LOCATION" "C384")
		)
		("@s9s_mb_2u_lib.s9s_mb_2u(sch_1):page365_i113@pure_quanta.q_cap(chips)"
			("LOCATION" "C385")
		)
		("@s9s_mb_2u_lib.s9s_mb_2u(sch_1):page365_i112@pure_quanta.q_cap(chips)"
			("LOCATION" "C387")
		)
		("@s9s_mb_2u_lib.s9s_mb_2u(sch_1):page365_i217@pure_quanta.q_cap(chips)"
			("LOCATION" "C389")
		)
		("@s9s_mb_2u_lib.s9s_mb_2u(sch_1):page365_i216@pure_quanta.q_cap(chips)"
			("LOCATION" "C391")
		)
		("@s9s_mb_2u_lib.s9s_mb_2u(sch_1):page365_i215@pure_quanta.q_cap(chips)"
			("LOCATION" "C393")
		)
		("@s9s_mb_2u_lib.s9s_mb_2u(sch_1):page365_i108@pure_quanta.q_cap(chips)"
			("LOCATION" "C395")
		)
		("@s9s_mb_2u_lib.s9s_mb_2u(sch_1):page365_i236@pure_quanta.q_cap(chips)"
			("LOCATION" "C397")
		)
		("@s9s_mb_2u_lib.s9s_mb_2u(sch_1):page365_i10@pure_quanta.q_cap(chips)"
			("LOCATION" "C491")
		)
		("@s9s_mb_2u_lib.s9s_mb_2u(sch_1):page365_i66@pure_quanta.q_cap(chips)"
			("LOCATION" "C492")
		)
		("@s9s_mb_2u_lib.s9s_mb_2u(sch_1):page365_i1@pure_quanta.q_cap(chips)"
			("LOCATION" "C493")
		)
		("@s9s_mb_2u_lib.s9s_mb_2u(sch_1):page365_i14@pure_quanta.q_cap(chips)"
			("LOCATION" "C495")
		)
		("@s9s_mb_2u_lib.s9s_mb_2u(sch_1):page365_i67@pure_quanta.q_cap(chips)"
			("LOCATION" "C496")
		)
		("@s9s_mb_2u_lib.s9s_mb_2u(sch_1):page365_i2@pure_quanta.q_cap(chips)"
			("LOCATION" "C497")
		)
		("@s9s_mb_2u_lib.s9s_mb_2u(sch_1):page365_i3@pure_quanta.q_cap(chips)"
			("LOCATION" "C501")
		)
		("@s9s_mb_2u_lib.s9s_mb_2u(sch_1):page365_i4@pure_quanta.q_cap(chips)"
			("LOCATION" "C505")
		)
		("@s9s_mb_2u_lib.s9s_mb_2u(sch_1):page365_i105@pure_quanta.q_cap(chips)"
			("LOCATION" "C509")
		)
		("@s9s_mb_2u_lib.s9s_mb_2u(sch_1):page365_i126@pure_quanta.q_cap(chips)"
			("LOCATION" "C515")
		)
		("@s9s_mb_2u_lib.s9s_mb_2u(sch_1):page365_i130@pure_quanta.q_cap(chips)"
			("LOCATION" "C518")
		)
		("@s9s_mb_2u_lib.s9s_mb_2u(sch_1):page365_i33@pure_quanta.q_cap(chips)"
			("LOCATION" "C522")
		)
		("@s9s_mb_2u_lib.s9s_mb_2u(sch_1):page365_i186@pure_quanta.q_cap(chips)"
			("LOCATION" "C524")
		)
		("@s9s_mb_2u_lib.s9s_mb_2u(sch_1):page365_i185@pure_quanta.q_cap(chips)"
			("LOCATION" "C527")
		)
		("@s9s_mb_2u_lib.s9s_mb_2u(sch_1):page365_i163@pure_quanta.q_cap(chips)"
			("LOCATION" "C532")
		)
		("@s9s_mb_2u_lib.s9s_mb_2u(sch_1):page365_i164@pure_quanta.q_cap(chips)"
			("LOCATION" "C533")
		)
		("@s9s_mb_2u_lib.s9s_mb_2u(sch_1):page365_i165@pure_quanta.q_cap(chips)"
			("LOCATION" "C534")
		)
		("@s9s_mb_2u_lib.s9s_mb_2u(sch_1):page365_i227@pure_quanta.q_cap(chips)"
			("LOCATION" "C1396")
		)
		("@s9s_mb_2u_lib.s9s_mb_2u(sch_1):page365_i229@pure_quanta.q_cap(chips)"
			("LOCATION" "C1397")
		)
		("@s9s_mb_2u_lib.s9s_mb_2u(sch_1):page365_i230@pure_quanta.q_cap(chips)"
			("LOCATION" "C1398")
		)
		("@s9s_mb_2u_lib.s9s_mb_2u(sch_1):page365_i238@pure_quanta.q_cap(chips)"
			("LOCATION" "C1405")
		)
		("@s9s_mb_2u_lib.s9s_mb_2u(sch_1):page365_i239@pure_quanta.q_cap(chips)"
			("LOCATION" "C1406")
		)
		("@s9s_mb_2u_lib.s9s_mb_2u(sch_1):page365_i240@pure_quanta.q_cap(chips)"
			("LOCATION" "C1407")
		)
		("@s9s_mb_2u_lib.s9s_mb_2u(sch_1):page614_i70@pure_quanta.q_cap(chips)"
			("LOCATION" "C366")
		)
		("@s9s_mb_2u_lib.s9s_mb_2u(sch_1):page614_i82@pure_quanta.q_cap(chips)"
			("LOCATION" "C369")
		)
		("@s9s_mb_2u_lib.s9s_mb_2u(sch_1):page614_i83@pure_quanta.q_cap(chips)"
			("LOCATION" "C372")
		)
		("@s9s_mb_2u_lib.s9s_mb_2u(sch_1):page614_i88@pure_quanta.q_cap(chips)"
			("LOCATION" "C374")
		)
		("@s9s_mb_2u_lib.s9s_mb_2u(sch_1):page614_i90@pure_quanta.q_cap(chips)"
			("LOCATION" "C377")
		)
		("@s9s_mb_2u_lib.s9s_mb_2u(sch_1):page614_i95@pure_quanta.q_cap(chips)"
			("LOCATION" "C380")
		)
		("@s9s_mb_2u_lib.s9s_mb_2u(sch_1):page614_i97@pure_quanta.q_cap(chips)"
			("LOCATION" "C383")
		)
		("@s9s_mb_2u_lib.s9s_mb_2u(sch_1):page614_i41@pure_quanta.q_cap(chips)"
			("LOCATION" "C386")
		)
		("@s9s_mb_2u_lib.s9s_mb_2u(sch_1):page614_i46@pure_quanta.q_cap(chips)"
			("LOCATION" "C388")
		)
		("@s9s_mb_2u_lib.s9s_mb_2u(sch_1):page614_i47@pure_quanta.q_cap(chips)"
			("LOCATION" "C390")
		)
		("@s9s_mb_2u_lib.s9s_mb_2u(sch_1):page614_i62@pure_quanta.q_cap(chips)"
			("LOCATION" "C392")
		)
		("@s9s_mb_2u_lib.s9s_mb_2u(sch_1):page614_i63@pure_quanta.q_cap(chips)"
			("LOCATION" "C394")
		)
		("@s9s_mb_2u_lib.s9s_mb_2u(sch_1):page614_i68@pure_quanta.q_cap(chips)"
			("LOCATION" "C396")
		)
		("@s9s_mb_2u_lib.s9s_mb_2u(sch_1):page614_i69@pure_quanta.q_cap(chips)"
			("LOCATION" "C398")
		)
		("@s9s_mb_2u_lib.s9s_mb_2u(sch_1):page614_i1@pure_quanta.q_cap(chips)"
			("LOCATION" "C494")
		)
		("@s9s_mb_2u_lib.s9s_mb_2u(sch_1):page614_i6@pure_quanta.q_cap(chips)"
			("LOCATION" "C498")
		)
		("@s9s_mb_2u_lib.s9s_mb_2u(sch_1):page614_i107@pure_quanta.q_cap(chips)"
			("LOCATION" "C499")
		)
		("@s9s_mb_2u_lib.s9s_mb_2u(sch_1):page614_i55@pure_quanta.q_cap(chips)"
			("LOCATION" "C500")
		)
		("@s9s_mb_2u_lib.s9s_mb_2u(sch_1):page614_i7@pure_quanta.q_cap(chips)"
			("LOCATION" "C502")
		)
		("@s9s_mb_2u_lib.s9s_mb_2u(sch_1):page614_i110@pure_quanta.q_cap(chips)"
			("LOCATION" "C503")
		)
		("@s9s_mb_2u_lib.s9s_mb_2u(sch_1):page614_i56@pure_quanta.q_cap(chips)"
			("LOCATION" "C504")
		)
		("@s9s_mb_2u_lib.s9s_mb_2u(sch_1):page614_i12@pure_quanta.q_cap(chips)"
			("LOCATION" "C506")
		)
		("@s9s_mb_2u_lib.s9s_mb_2u(sch_1):page614_i109@pure_quanta.q_cap(chips)"
			("LOCATION" "C507")
		)
		("@s9s_mb_2u_lib.s9s_mb_2u(sch_1):page614_i77@pure_quanta.q_cap(chips)"
			("LOCATION" "C508")
		)
		("@s9s_mb_2u_lib.s9s_mb_2u(sch_1):page614_i13@pure_quanta.q_cap(chips)"
			("LOCATION" "C510")
		)
		("@s9s_mb_2u_lib.s9s_mb_2u(sch_1):page614_i108@pure_quanta.q_cap(chips)"
			("LOCATION" "C511")
		)
		("@s9s_mb_2u_lib.s9s_mb_2u(sch_1):page614_i78@pure_quanta.q_cap(chips)"
			("LOCATION" "C512")
		)
		("@s9s_mb_2u_lib.s9s_mb_2u(sch_1):page614_i18@pure_quanta.q_cap(chips)"
			("LOCATION" "C514")
		)
		("@s9s_mb_2u_lib.s9s_mb_2u(sch_1):page614_i79@pure_quanta.q_cap(chips)"
			("LOCATION" "C516")
		)
		("@s9s_mb_2u_lib.s9s_mb_2u(sch_1):page614_i19@pure_quanta.q_cap(chips)"
			("LOCATION" "C517")
		)
		("@s9s_mb_2u_lib.s9s_mb_2u(sch_1):page614_i81@pure_quanta.q_cap(chips)"
			("LOCATION" "C519")
		)
		("@s9s_mb_2u_lib.s9s_mb_2u(sch_1):page614_i20@pure_quanta.q_cap(chips)"
			("LOCATION" "C520")
		)
		("@s9s_mb_2u_lib.s9s_mb_2u(sch_1):page614_i27@pure_quanta.q_cap(chips)"
			("LOCATION" "C521")
		)
		("@s9s_mb_2u_lib.s9s_mb_2u(sch_1):page614_i28@pure_quanta.q_cap(chips)"
			("LOCATION" "C523")
		)
		("@s9s_mb_2u_lib.s9s_mb_2u(sch_1):page614_i114@pure_quanta.q_cap(chips)"
			("LOCATION" "C525")
		)
		("@s9s_mb_2u_lib.s9s_mb_2u(sch_1):page614_i29@pure_quanta.q_cap(chips)"
			("LOCATION" "C526")
		)
		("@s9s_mb_2u_lib.s9s_mb_2u(sch_1):page614_i118@pure_quanta.q_cap(chips)"
			("LOCATION" "C528")
		)
		("@s9s_mb_2u_lib.s9s_mb_2u(sch_1):page614_i31@pure_quanta.q_cap(chips)"
			("LOCATION" "C529")
		)
		("@s9s_mb_2u_lib.s9s_mb_2u(sch_1):page614_i117@pure_quanta.q_cap(chips)"
			("LOCATION" "C530")
		)
		("@s9s_mb_2u_lib.s9s_mb_2u(sch_1):page614_i115@pure_quanta.q_cap(chips)"
			("LOCATION" "C531")
		)
		("@s9s_mb_2u_lib.s9s_mb_2u(sch_1):page614_i119@pure_quanta.q_cap(chips)"
			("LOCATION" "C1362")
		)
		("@s9s_mb_2u_lib.s9s_mb_2u(sch_1):page614_i111@pure_quanta.q_cap(chips)"
			("LOCATION" "C1399")
		)
		("@s9s_mb_2u_lib.s9s_mb_2u(sch_1):page614_i112@pure_quanta.q_cap(chips)"
			("LOCATION" "C1400")
		)
		("@s9s_mb_2u_lib.s9s_mb_2u(sch_1):page573_i14@pure_quanta.q_cap(chips)"
			("LOCATION" "C513")
		)
		("@s9s_mb_2u_lib.s9s_mb_2u(sch_1):page573_i15@pure_quanta.q_cap(chips)"
			("LOCATION" "C535")
		)
		("@s9s_mb_2u_lib.s9s_mb_2u(sch_1):page573_i17@pure_quanta.q_res(chips)"
			("LOCATION" "R1747")
		)
		("@s9s_mb_2u_lib.s9s_mb_2u(sch_1):page573_i12@pure_quanta.q_res(chips)"
			("LOCATION" "R1763")
		)
		("@s9s_mb_2u_lib.s9s_mb_2u(sch_1):page573_i13@pure_quanta.q_res(chips)"
			("LOCATION" "R1764")
		)
		("@s9s_mb_2u_lib.s9s_mb_2u(sch_1):page573_i18@pure_quanta.q_res(chips)"
			("LOCATION" "R1765")
		)
		("@s9s_mb_2u_lib.s9s_mb_2u(sch_1):page555_i14@pure_quanta.q_cap(chips)"
			("LOCATION" "C536")
		)
		("@s9s_mb_2u_lib.s9s_mb_2u(sch_1):page555_i54@pure_quanta.q_res(chips)"
			("LOCATION" "R641")
		)
		("@s9s_mb_2u_lib.s9s_mb_2u(sch_1):page555_i53@pure_quanta.q_res(chips)"
			("LOCATION" "R642")
		)
		("@s9s_mb_2u_lib.s9s_mb_2u(sch_1):page555_i58@pure_quanta.q_res(chips)"
			("LOCATION" "R643")
		)
		("@s9s_mb_2u_lib.s9s_mb_2u(sch_1):page555_i55@pure_quanta.q_res(chips)"
			("LOCATION" "R644")
		)
		("@s9s_mb_2u_lib.s9s_mb_2u(sch_1):page555_i57@pure_quanta.q_res(chips)"
			("LOCATION" "R645")
		)
		("@s9s_mb_2u_lib.s9s_mb_2u(sch_1):page555_i56@pure_quanta.q_res(chips)"
			("LOCATION" "R646")
		)
		("@s9s_mb_2u_lib.s9s_mb_2u(sch_1):page555_i84@pure_quanta.q_res(chips)"
			("LOCATION" "R647")
		)
		("@s9s_mb_2u_lib.s9s_mb_2u(sch_1):page555_i82@pure_quanta.q_res(chips)"
			("LOCATION" "R648")
		)
		("@s9s_mb_2u_lib.s9s_mb_2u(sch_1):page555_i77@pure_quanta.q_res(chips)"
			("LOCATION" "R651")
		)
		("@s9s_mb_2u_lib.s9s_mb_2u(sch_1):page555_i74@pure_quanta.q_res(chips)"
			("LOCATION" "R652")
		)
		("@s9s_mb_2u_lib.s9s_mb_2u(sch_1):page555_i62@pure_quanta.q_res(chips)"
			("LOCATION" "R653")
		)
		("@s9s_mb_2u_lib.s9s_mb_2u(sch_1):page555_i63@pure_quanta.q_res(chips)"
			("LOCATION" "R654")
		)
		("@s9s_mb_2u_lib.s9s_mb_2u(sch_1):page555_i66@pure_quanta.q_res(chips)"
			("LOCATION" "R655")
		)
		("@s9s_mb_2u_lib.s9s_mb_2u(sch_1):page555_i65@pure_quanta.q_res(chips)"
			("LOCATION" "R656")
		)
		("@s9s_mb_2u_lib.s9s_mb_2u(sch_1):page555_i71@pure_quanta.q_res(chips)"
			("LOCATION" "R657")
		)
		("@s9s_mb_2u_lib.s9s_mb_2u(sch_1):page555_i72@pure_quanta.q_res(chips)"
			("LOCATION" "R658")
		)
		("@s9s_mb_2u_lib.s9s_mb_2u(sch_1):page555_i91@pure_quanta.q_res(chips)"
			("LOCATION" "R659")
		)
		("@s9s_mb_2u_lib.s9s_mb_2u(sch_1):page555_i90@pure_quanta.q_res(chips)"
			("LOCATION" "R660")
		)
		("@s9s_mb_2u_lib.s9s_mb_2u(sch_1):page555_i162@pure_quanta.q_res(chips)"
			("LOCATION" "R914")
		)
		("@s9s_mb_2u_lib.s9s_mb_2u(sch_1):page555_i121@pure_quanta.q_res(chips)"
			("LOCATION" "R1051")
		)
		("@s9s_mb_2u_lib.s9s_mb_2u(sch_1):page555_i120@pure_quanta.q_res(chips)"
			("LOCATION" "R1052")
		)
		("@s9s_mb_2u_lib.s9s_mb_2u(sch_1):page555_i122@pure_quanta.q_res(chips)"
			("LOCATION" "R1053")
		)
		("@s9s_mb_2u_lib.s9s_mb_2u(sch_1):page555_i123@pure_quanta.q_res(chips)"
			("LOCATION" "R1054")
		)
		("@s9s_mb_2u_lib.s9s_mb_2u(sch_1):page555_i125@pure_quanta.q_res(chips)"
			("LOCATION" "R1055")
		)
		("@s9s_mb_2u_lib.s9s_mb_2u(sch_1):page555_i124@pure_quanta.q_res(chips)"
			("LOCATION" "R1056")
		)
		("@s9s_mb_2u_lib.s9s_mb_2u(sch_1):page555_i127@pure_quanta.q_res(chips)"
			("LOCATION" "R1057")
		)
		("@s9s_mb_2u_lib.s9s_mb_2u(sch_1):page555_i126@pure_quanta.q_res(chips)"
			("LOCATION" "R1058")
		)
		("@s9s_mb_2u_lib.s9s_mb_2u(sch_1):page555_i129@pure_quanta.q_res(chips)"
			("LOCATION" "R1059")
		)
		("@s9s_mb_2u_lib.s9s_mb_2u(sch_1):page555_i128@pure_quanta.q_res(chips)"
			("LOCATION" "R1060")
		)
		("@s9s_mb_2u_lib.s9s_mb_2u(sch_1):page555_i131@pure_quanta.q_res(chips)"
			("LOCATION" "R1061")
		)
		("@s9s_mb_2u_lib.s9s_mb_2u(sch_1):page555_i130@pure_quanta.q_res(chips)"
			("LOCATION" "R1062")
		)
		("@s9s_mb_2u_lib.s9s_mb_2u(sch_1):page555_i133@pure_quanta.q_res(chips)"
			("LOCATION" "R1063")
		)
		("@s9s_mb_2u_lib.s9s_mb_2u(sch_1):page555_i132@pure_quanta.q_res(chips)"
			("LOCATION" "R1064")
		)
		("@s9s_mb_2u_lib.s9s_mb_2u(sch_1):page555_i146@pure_quanta.q_res(chips)"
			("LOCATION" "R1065")
		)
		("@s9s_mb_2u_lib.s9s_mb_2u(sch_1):page555_i145@pure_quanta.q_res(chips)"
			("LOCATION" "R1066")
		)
		("@s9s_mb_2u_lib.s9s_mb_2u(sch_1):page555_i148@pure_quanta.q_res(chips)"
			("LOCATION" "R1067")
		)
		("@s9s_mb_2u_lib.s9s_mb_2u(sch_1):page555_i147@pure_quanta.q_res(chips)"
			("LOCATION" "R1068")
		)
		("@s9s_mb_2u_lib.s9s_mb_2u(sch_1):page555_i149@pure_quanta.q_res(chips)"
			("LOCATION" "R1069")
		)
		("@s9s_mb_2u_lib.s9s_mb_2u(sch_1):page555_i150@pure_quanta.q_res(chips)"
			("LOCATION" "R1070")
		)
		("@s9s_mb_2u_lib.s9s_mb_2u(sch_1):page555_i154@pure_quanta.q_res(chips)"
			("LOCATION" "R1071")
		)
		("@s9s_mb_2u_lib.s9s_mb_2u(sch_1):page555_i151@pure_quanta.q_res(chips)"
			("LOCATION" "R1072")
		)
		("@s9s_mb_2u_lib.s9s_mb_2u(sch_1):page555_i161@pure_quanta.q_res(chips)"
			("LOCATION" "R1314")
		)
		("@s9s_mb_2u_lib.s9s_mb_2u(sch_1):page555_i157@pure_quanta.q_res(chips)"
			("LOCATION" "R1667")
		)
		("@s9s_mb_2u_lib.s9s_mb_2u(sch_1):page555_i78@pure_quanta.pca9548apw(chips)"
			("LOCATION" "U10")
		)
		("@s9s_mb_2u_lib.s9s_mb_2u(sch_1):page554_i24@pure_quanta.q_cap(chips)"
			("LOCATION" "C537")
		)
		("@s9s_mb_2u_lib.s9s_mb_2u(sch_1):page554_i11@pure_quanta.q_res(chips)"
			("LOCATION" "R661")
		)
		("@s9s_mb_2u_lib.s9s_mb_2u(sch_1):page554_i49@pure_quanta.q_res(chips)"
			("LOCATION" "R662")
		)
		("@s9s_mb_2u_lib.s9s_mb_2u(sch_1):page554_i48@pure_quanta.q_res(chips)"
			("LOCATION" "R663")
		)
		("@s9s_mb_2u_lib.s9s_mb_2u(sch_1):page554_i47@pure_quanta.q_res(chips)"
			("LOCATION" "R664")
		)
		("@s9s_mb_2u_lib.s9s_mb_2u(sch_1):page554_i18@pure_quanta.q_res(chips)"
			("LOCATION" "R665")
		)
		("@s9s_mb_2u_lib.s9s_mb_2u(sch_1):page554_i16@pure_quanta.q_res(chips)"
			("LOCATION" "R666")
		)
		("@s9s_mb_2u_lib.s9s_mb_2u(sch_1):page554_i15@pure_quanta.q_res(chips)"
			("LOCATION" "R667")
		)
		("@s9s_mb_2u_lib.s9s_mb_2u(sch_1):page554_i14@pure_quanta.q_res(chips)"
			("LOCATION" "R668")
		)
		("@s9s_mb_2u_lib.s9s_mb_2u(sch_1):page554_i46@pure_quanta.q_res(chips)"
			("LOCATION" "R669")
		)
		("@s9s_mb_2u_lib.s9s_mb_2u(sch_1):page554_i27@pure_quanta.q_res(chips)"
			("LOCATION" "R670")
		)
		("@s9s_mb_2u_lib.s9s_mb_2u(sch_1):page554_i28@pure_quanta.q_res(chips)"
			("LOCATION" "R671")
		)
		("@s9s_mb_2u_lib.s9s_mb_2u(sch_1):page554_i21@pure_quanta.q_res(chips)"
			("LOCATION" "R672")
		)
		("@s9s_mb_2u_lib.s9s_mb_2u(sch_1):page554_i22@pure_quanta.q_res(chips)"
			("LOCATION" "R673")
		)
		("@s9s_mb_2u_lib.s9s_mb_2u(sch_1):page554_i31@pure_quanta.q_res(chips)"
			("LOCATION" "R674")
		)
		("@s9s_mb_2u_lib.s9s_mb_2u(sch_1):page554_i33@pure_quanta.q_res(chips)"
			("LOCATION" "R675")
		)
		("@s9s_mb_2u_lib.s9s_mb_2u(sch_1):page554_i32@pure_quanta.q_res(chips)"
			("LOCATION" "R676")
		)
		("@s9s_mb_2u_lib.s9s_mb_2u(sch_1):page554_i30@pure_quanta.q_res(chips)"
			("LOCATION" "R677")
		)
		("@s9s_mb_2u_lib.s9s_mb_2u(sch_1):page554_i17@pure_quanta.idtqs3vh257qg(chips)"
			("LOCATION" "U14")
		)
		("@s9s_mb_2u_lib.s9s_mb_2u(sch_1):page553_i84@pure_quanta.q_cap(chips)"
			("LOCATION" "C538")
		)
		("@s9s_mb_2u_lib.s9s_mb_2u(sch_1):page553_i79@pure_quanta.q_res(chips)"
			("LOCATION" "R87")
		)
		("@s9s_mb_2u_lib.s9s_mb_2u(sch_1):page553_i81@pure_quanta.q_res(chips)"
			("LOCATION" "R318")
		)
		("@s9s_mb_2u_lib.s9s_mb_2u(sch_1):page553_i63@pure_quanta.q_res(chips)"
			("LOCATION" "R678")
		)
		("@s9s_mb_2u_lib.s9s_mb_2u(sch_1):page553_i85@pure_quanta.q_res(chips)"
			("LOCATION" "R679")
		)
		("@s9s_mb_2u_lib.s9s_mb_2u(sch_1):page553_i89@pure_quanta.q_res(chips)"
			("LOCATION" "R680")
		)
		("@s9s_mb_2u_lib.s9s_mb_2u(sch_1):page553_i87@pure_quanta.q_res(chips)"
			("LOCATION" "R681")
		)
		("@s9s_mb_2u_lib.s9s_mb_2u(sch_1):page553_i65@pure_quanta.q_res(chips)"
			("LOCATION" "R682")
		)
		("@s9s_mb_2u_lib.s9s_mb_2u(sch_1):page553_i66@pure_quanta.q_res(chips)"
			("LOCATION" "R683")
		)
		("@s9s_mb_2u_lib.s9s_mb_2u(sch_1):page553_i67@pure_quanta.q_res(chips)"
			("LOCATION" "R684")
		)
		("@s9s_mb_2u_lib.s9s_mb_2u(sch_1):page553_i68@pure_quanta.q_res(chips)"
			("LOCATION" "R685")
		)
		("@s9s_mb_2u_lib.s9s_mb_2u(sch_1):page553_i86@pure_quanta.q_res(chips)"
			("LOCATION" "R686")
		)
		("@s9s_mb_2u_lib.s9s_mb_2u(sch_1):page553_i27@pure_quanta.q_res(chips)"
			("LOCATION" "R687")
		)
		("@s9s_mb_2u_lib.s9s_mb_2u(sch_1):page553_i28@pure_quanta.q_res(chips)"
			("LOCATION" "R688")
		)
		("@s9s_mb_2u_lib.s9s_mb_2u(sch_1):page553_i30@pure_quanta.q_res(chips)"
			("LOCATION" "R689")
		)
		("@s9s_mb_2u_lib.s9s_mb_2u(sch_1):page553_i29@pure_quanta.q_res(chips)"
			("LOCATION" "R690")
		)
		("@s9s_mb_2u_lib.s9s_mb_2u(sch_1):page553_i74@pure_quanta.q_res(chips)"
			("LOCATION" "R691")
		)
		("@s9s_mb_2u_lib.s9s_mb_2u(sch_1):page553_i73@pure_quanta.q_res(chips)"
			("LOCATION" "R692")
		)
		("@s9s_mb_2u_lib.s9s_mb_2u(sch_1):page553_i75@pure_quanta.q_res(chips)"
			("LOCATION" "R693")
		)
		("@s9s_mb_2u_lib.s9s_mb_2u(sch_1):page553_i76@pure_quanta.q_res(chips)"
			("LOCATION" "R694")
		)
		("@s9s_mb_2u_lib.s9s_mb_2u(sch_1):page553_i90@pure_quanta.q_res(chips)"
			("LOCATION" "R1821")
		)
		("@s9s_mb_2u_lib.s9s_mb_2u(sch_1):page553_i25@pure_quanta.idtqs3vh257qg(chips)"
			("LOCATION" "U15")
		)
		("@s9s_mb_2u_lib.s9s_mb_2u(sch_1):page468_i70@pure_quanta.q_cap(chips)"
			("LOCATION" "C539")
		)
		("@s9s_mb_2u_lib.s9s_mb_2u(sch_1):page468_i81@pure_quanta.q_cap(chips)"
			("LOCATION" "C540")
		)
		("@s9s_mb_2u_lib.s9s_mb_2u(sch_1):page468_i61@pure_quanta.q_cap(chips)"
			("LOCATION" "C541")
		)
		("@s9s_mb_2u_lib.s9s_mb_2u(sch_1):page468_i80@pure_quanta.q_cap(chips)"
			("LOCATION" "C542")
		)
		("@s9s_mb_2u_lib.s9s_mb_2u(sch_1):page468_i100@pure_quanta.q_cap(chips)"
			("LOCATION" "C543")
		)
		("@s9s_mb_2u_lib.s9s_mb_2u(sch_1):page468_i94@pure_quanta.q_cap(chips)"
			("LOCATION" "C544")
		)
		("@s9s_mb_2u_lib.s9s_mb_2u(sch_1):page468_i106@pure_quanta.q_res(chips)"
			("LOCATION" "R737")
		)
		("@s9s_mb_2u_lib.s9s_mb_2u(sch_1):page468_i110@pure_quanta.q_res(chips)"
			("LOCATION" "R738")
		)
		("@s9s_mb_2u_lib.s9s_mb_2u(sch_1):page468_i109@pure_quanta.q_res(chips)"
			("LOCATION" "R739")
		)
		("@s9s_mb_2u_lib.s9s_mb_2u(sch_1):page468_i107@pure_quanta.q_res(chips)"
			("LOCATION" "R740")
		)
		("@s9s_mb_2u_lib.s9s_mb_2u(sch_1):page468_i66@pure_quanta.q_res(chips)"
			("LOCATION" "R741")
		)
		("@s9s_mb_2u_lib.s9s_mb_2u(sch_1):page468_i78@pure_quanta.q_res(chips)"
			("LOCATION" "R742")
		)
		("@s9s_mb_2u_lib.s9s_mb_2u(sch_1):page468_i65@pure_quanta.q_res(chips)"
			("LOCATION" "R743")
		)
		("@s9s_mb_2u_lib.s9s_mb_2u(sch_1):page468_i77@pure_quanta.q_res(chips)"
			("LOCATION" "R744")
		)
		("@s9s_mb_2u_lib.s9s_mb_2u(sch_1):page468_i97@pure_quanta.q_res(chips)"
			("LOCATION" "R745")
		)
		("@s9s_mb_2u_lib.s9s_mb_2u(sch_1):page468_i88@pure_quanta.nc7sz66m5x(chips)"
			("LOCATION" "U16")
		)
		("@s9s_mb_2u_lib.s9s_mb_2u(sch_1):page468_i58@pure_quanta.nc7sb3157(chips)"
			("LOCATION" "U21")
		)
		("@s9s_mb_2u_lib.s9s_mb_2u(sch_1):page468_i71@pure_quanta.nc7sb3157(chips)"
			("LOCATION" "U22")
		)
		("@s9s_mb_2u_lib.s9s_mb_2u(sch_1):page468_i96@pure_quanta.\\74lvc1g02gw\\(chips)"
			("LOCATION" "U23")
		)
		("@s9s_mb_2u_lib.s9s_mb_2u(sch_1):page469_i93@pure_quanta.q_cap(chips)"
			("LOCATION" "C545")
		)
		("@s9s_mb_2u_lib.s9s_mb_2u(sch_1):page469_i135@pure_quanta.q_cap(chips)"
			("LOCATION" "C546")
		)
		("@s9s_mb_2u_lib.s9s_mb_2u(sch_1):page469_i90@pure_quanta.q_res(chips)"
			("LOCATION" "R746")
		)
		("@s9s_mb_2u_lib.s9s_mb_2u(sch_1):page469_i176@pure_quanta.q_res(chips)"
			("LOCATION" "R747")
		)
		("@s9s_mb_2u_lib.s9s_mb_2u(sch_1):page469_i180@pure_quanta.q_res(chips)"
			("LOCATION" "R748")
		)
		("@s9s_mb_2u_lib.s9s_mb_2u(sch_1):page469_i179@pure_quanta.q_res(chips)"
			("LOCATION" "R749")
		)
		("@s9s_mb_2u_lib.s9s_mb_2u(sch_1):page469_i178@pure_quanta.q_res(chips)"
			("LOCATION" "R750")
		)
		("@s9s_mb_2u_lib.s9s_mb_2u(sch_1):page469_i177@pure_quanta.q_res(chips)"
			("LOCATION" "R751")
		)
		("@s9s_mb_2u_lib.s9s_mb_2u(sch_1):page469_i127@pure_quanta.q_res(chips)"
			("LOCATION" "R752")
		)
		("@s9s_mb_2u_lib.s9s_mb_2u(sch_1):page469_i128@pure_quanta.q_res(chips)"
			("LOCATION" "R753")
		)
		("@s9s_mb_2u_lib.s9s_mb_2u(sch_1):page469_i126@pure_quanta.q_res(chips)"
			("LOCATION" "R754")
		)
		("@s9s_mb_2u_lib.s9s_mb_2u(sch_1):page469_i147@pure_quanta.q_res(chips)"
			("LOCATION" "R755")
		)
		("@s9s_mb_2u_lib.s9s_mb_2u(sch_1):page469_i148@pure_quanta.q_res(chips)"
			("LOCATION" "R756")
		)
		("@s9s_mb_2u_lib.s9s_mb_2u(sch_1):page469_i166@pure_quanta.q_res(chips)"
			("LOCATION" "R757")
		)
		("@s9s_mb_2u_lib.s9s_mb_2u(sch_1):page469_i168@pure_quanta.q_res(chips)"
			("LOCATION" "R758")
		)
		("@s9s_mb_2u_lib.s9s_mb_2u(sch_1):page469_i169@pure_quanta.q_res(chips)"
			("LOCATION" "R759")
		)
		("@s9s_mb_2u_lib.s9s_mb_2u(sch_1):page469_i174@pure_quanta.q_res(chips)"
			("LOCATION" "R760")
		)
		("@s9s_mb_2u_lib.s9s_mb_2u(sch_1):page469_i175@pure_quanta.q_res(chips)"
			("LOCATION" "R761")
		)
		("@s9s_mb_2u_lib.s9s_mb_2u(sch_1):page469_i80@pure_quanta.\\74cbtlv3126pw\\(chips)"
			("LOCATION" "U17")
		)
		("@s9s_mb_2u_lib.s9s_mb_2u(sch_1):page469_i129@pure_quanta.\\74cbtlv3126pw\\(chips)"
			("LOCATION" "U18")
		)
		("@s9s_mb_2u_lib.s9s_mb_2u(sch_1):page470_i100@pure_quanta.q_cap(chips)"
			("LOCATION" "C547")
		)
		("@s9s_mb_2u_lib.s9s_mb_2u(sch_1):page470_i130@pure_quanta.q_cap(chips)"
			("LOCATION" "C548")
		)
		("@s9s_mb_2u_lib.s9s_mb_2u(sch_1):page470_i129@pure_quanta.q_cap(chips)"
			("LOCATION" "C549")
		)
		("@s9s_mb_2u_lib.s9s_mb_2u(sch_1):page470_i99@pure_quanta.q_cap(chips)"
			("LOCATION" "C550")
		)
		("@s9s_mb_2u_lib.s9s_mb_2u(sch_1):page470_i105@pure_quanta.q_cap(chips)"
			("LOCATION" "C551")
		)
		("@s9s_mb_2u_lib.s9s_mb_2u(sch_1):page470_i96@pure_quanta.q_cap(chips)"
			("LOCATION" "C552")
		)
		("@s9s_mb_2u_lib.s9s_mb_2u(sch_1):page470_i44@pure_quanta.sconn60_qsh03001ldaktr(chips)"
			("LOCATION" "J42")
		)
		("@s9s_mb_2u_lib.s9s_mb_2u(sch_1):page470_i71@pure_quanta.q_res(chips)"
			("LOCATION" "R762")
		)
		("@s9s_mb_2u_lib.s9s_mb_2u(sch_1):page470_i70@pure_quanta.q_res(chips)"
			("LOCATION" "R763")
		)
		("@s9s_mb_2u_lib.s9s_mb_2u(sch_1):page470_i83@pure_quanta.q_res(chips)"
			("LOCATION" "R764")
		)
		("@s9s_mb_2u_lib.s9s_mb_2u(sch_1):page470_i74@pure_quanta.q_res(chips)"
			("LOCATION" "R765")
		)
		("@s9s_mb_2u_lib.s9s_mb_2u(sch_1):page470_i111@pure_quanta.q_res(chips)"
			("LOCATION" "R766")
		)
		("@s9s_mb_2u_lib.s9s_mb_2u(sch_1):page470_i113@pure_quanta.q_res(chips)"
			("LOCATION" "R767")
		)
		("@s9s_mb_2u_lib.s9s_mb_2u(sch_1):page470_i112@pure_quanta.q_res(chips)"
			("LOCATION" "R768")
		)
		("@s9s_mb_2u_lib.s9s_mb_2u(sch_1):page470_i102@pure_quanta.q_res(chips)"
			("LOCATION" "R769")
		)
		("@s9s_mb_2u_lib.s9s_mb_2u(sch_1):page470_i120@pure_quanta.q_res(chips)"
			("LOCATION" "R771")
		)
		("@s9s_mb_2u_lib.s9s_mb_2u(sch_1):page470_i118@pure_quanta.q_res(chips)"
			("LOCATION" "R772")
		)
		("@s9s_mb_2u_lib.s9s_mb_2u(sch_1):page470_i124@pure_quanta.q_res(chips)"
			("LOCATION" "R773")
		)
		("@s9s_mb_2u_lib.s9s_mb_2u(sch_1):page470_i132@pure_quanta.q_res(chips)"
			("LOCATION" "R774")
		)
		("@s9s_mb_2u_lib.s9s_mb_2u(sch_1):page470_i5@pure_quanta.q_res(chips)"
			("LOCATION" "R775")
		)
		("@s9s_mb_2u_lib.s9s_mb_2u(sch_1):page470_i7@pure_quanta.q_res(chips)"
			("LOCATION" "R776")
		)
		("@s9s_mb_2u_lib.s9s_mb_2u(sch_1):page470_i10@pure_quanta.q_res(chips)"
			("LOCATION" "R777")
		)
		("@s9s_mb_2u_lib.s9s_mb_2u(sch_1):page470_i15@pure_quanta.q_res(chips)"
			("LOCATION" "R778")
		)
		("@s9s_mb_2u_lib.s9s_mb_2u(sch_1):page470_i95@pure_quanta.q_res(chips)"
			("LOCATION" "R779")
		)
		("@s9s_mb_2u_lib.s9s_mb_2u(sch_1):page470_i92@pure_quanta.q_res(chips)"
			("LOCATION" "R780")
		)
		("@s9s_mb_2u_lib.s9s_mb_2u(sch_1):page470_i144@pure_quanta.q_res(chips)"
			("LOCATION" "R1472")
		)
		("@s9s_mb_2u_lib.s9s_mb_2u(sch_1):page556_i40@pure_quanta.q_cap(chips)"
			("LOCATION" "C553")
		)
		("@s9s_mb_2u_lib.s9s_mb_2u(sch_1):page556_i9@pure_quanta.q_res(chips)"
			("LOCATION" "R781")
		)
		("@s9s_mb_2u_lib.s9s_mb_2u(sch_1):page556_i6@pure_quanta.q_res(chips)"
			("LOCATION" "R782")
		)
		("@s9s_mb_2u_lib.s9s_mb_2u(sch_1):page556_i10@pure_quanta.q_res(chips)"
			("LOCATION" "R783")
		)
		("@s9s_mb_2u_lib.s9s_mb_2u(sch_1):page556_i8@pure_quanta.q_res(chips)"
			("LOCATION" "R784")
		)
		("@s9s_mb_2u_lib.s9s_mb_2u(sch_1):page556_i13@pure_quanta.q_res(chips)"
			("LOCATION" "R785")
		)
		("@s9s_mb_2u_lib.s9s_mb_2u(sch_1):page556_i12@pure_quanta.q_res(chips)"
			("LOCATION" "R786")
		)
		("@s9s_mb_2u_lib.s9s_mb_2u(sch_1):page556_i21@pure_quanta.q_res(chips)"
			("LOCATION" "R787")
		)
		("@s9s_mb_2u_lib.s9s_mb_2u(sch_1):page556_i20@pure_quanta.q_res(chips)"
			("LOCATION" "R788")
		)
		("@s9s_mb_2u_lib.s9s_mb_2u(sch_1):page556_i19@pure_quanta.q_res(chips)"
			("LOCATION" "R789")
		)
		("@s9s_mb_2u_lib.s9s_mb_2u(sch_1):page556_i18@pure_quanta.q_res(chips)"
			("LOCATION" "R790")
		)
		("@s9s_mb_2u_lib.s9s_mb_2u(sch_1):page556_i33@pure_quanta.q_res(chips)"
			("LOCATION" "R791")
		)
		("@s9s_mb_2u_lib.s9s_mb_2u(sch_1):page556_i32@pure_quanta.q_res(chips)"
			("LOCATION" "R792")
		)
		("@s9s_mb_2u_lib.s9s_mb_2u(sch_1):page556_i31@pure_quanta.q_res(chips)"
			("LOCATION" "R793")
		)
		("@s9s_mb_2u_lib.s9s_mb_2u(sch_1):page556_i30@pure_quanta.q_res(chips)"
			("LOCATION" "R794")
		)
		("@s9s_mb_2u_lib.s9s_mb_2u(sch_1):page556_i29@pure_quanta.q_res(chips)"
			("LOCATION" "R795")
		)
		("@s9s_mb_2u_lib.s9s_mb_2u(sch_1):page556_i28@pure_quanta.q_res(chips)"
			("LOCATION" "R796")
		)
		("@s9s_mb_2u_lib.s9s_mb_2u(sch_1):page556_i27@pure_quanta.q_res(chips)"
			("LOCATION" "R797")
		)
		("@s9s_mb_2u_lib.s9s_mb_2u(sch_1):page556_i26@pure_quanta.q_res(chips)"
			("LOCATION" "R798")
		)
		("@s9s_mb_2u_lib.s9s_mb_2u(sch_1):page556_i56@pure_quanta.q_res(chips)"
			("LOCATION" "R799")
		)
		("@s9s_mb_2u_lib.s9s_mb_2u(sch_1):page556_i57@pure_quanta.q_res(chips)"
			("LOCATION" "R800")
		)
		("@s9s_mb_2u_lib.s9s_mb_2u(sch_1):page556_i51@pure_quanta.q_res(chips)"
			("LOCATION" "R801")
		)
		("@s9s_mb_2u_lib.s9s_mb_2u(sch_1):page556_i50@pure_quanta.q_res(chips)"
			("LOCATION" "R802")
		)
		("@s9s_mb_2u_lib.s9s_mb_2u(sch_1):page556_i58@pure_quanta.q_res(chips)"
			("LOCATION" "R1522")
		)
		("@s9s_mb_2u_lib.s9s_mb_2u(sch_1):page556_i35@pure_quanta.pca9546apw(chips)"
			("LOCATION" "U24")
		)
		("@s9s_mb_2u_lib.s9s_mb_2u(sch_1):page548_i52@pure_quanta.q_cap(chips)"
			("LOCATION" "C554")
		)
		("@s9s_mb_2u_lib.s9s_mb_2u(sch_1):page548_i50@pure_quanta.q_cap(chips)"
			("LOCATION" "C563")
		)
		("@s9s_mb_2u_lib.s9s_mb_2u(sch_1):page548_i42@pure_quanta.conn10_g2100ht0038071(chips)"
			("LOCATION" "J43")
		)
		("@s9s_mb_2u_lib.s9s_mb_2u(sch_1):page548_i19@pure_quanta.q_res(chips)"
			("LOCATION" "R803")
		)
		("@s9s_mb_2u_lib.s9s_mb_2u(sch_1):page548_i20@pure_quanta.q_res(chips)"
			("LOCATION" "R804")
		)
		("@s9s_mb_2u_lib.s9s_mb_2u(sch_1):page548_i25@pure_quanta.q_res(chips)"
			("LOCATION" "R805")
		)
		("@s9s_mb_2u_lib.s9s_mb_2u(sch_1):page548_i54@pure_quanta.q_res(chips)"
			("LOCATION" "R806")
		)
		("@s9s_mb_2u_lib.s9s_mb_2u(sch_1):page548_i75@pure_quanta.q_res(chips)"
			("LOCATION" "R919")
		)
		("@s9s_mb_2u_lib.s9s_mb_2u(sch_1):page548_i76@pure_quanta.q_res(chips)"
			("LOCATION" "R920")
		)
		("@s9s_mb_2u_lib.s9s_mb_2u(sch_1):page548_i61@pure_quanta.q_res(chips)"
			("LOCATION" "R927")
		)
		("@s9s_mb_2u_lib.s9s_mb_2u(sch_1):page548_i60@pure_quanta.q_res(chips)"
			("LOCATION" "R928")
		)
		("@s9s_mb_2u_lib.s9s_mb_2u(sch_1):page548_i59@pure_quanta.q_res(chips)"
			("LOCATION" "R929")
		)
		("@s9s_mb_2u_lib.s9s_mb_2u(sch_1):page548_i63@pure_quanta.q_res(chips)"
			("LOCATION" "R930")
		)
		("@s9s_mb_2u_lib.s9s_mb_2u(sch_1):page548_i48@pure_quanta.q_res(chips)"
			("LOCATION" "R931")
		)
		("@s9s_mb_2u_lib.s9s_mb_2u(sch_1):page548_i81@pure_quanta.q_res(chips)"
			("LOCATION" "R1743")
		)
		("@s9s_mb_2u_lib.s9s_mb_2u(sch_1):page475_i36@pure_quanta.q_cap(chips)"
			("LOCATION" "C555")
		)
		("@s9s_mb_2u_lib.s9s_mb_2u(sch_1):page475_i73@pure_quanta.q_cap(chips)"
			("LOCATION" "C556")
		)
		("@s9s_mb_2u_lib.s9s_mb_2u(sch_1):page475_i42@pure_quanta.q_cap(chips)"
			("LOCATION" "C557")
		)
		("@s9s_mb_2u_lib.s9s_mb_2u(sch_1):page475_i67@pure_quanta.q_cap(chips)"
			("LOCATION" "C558")
		)
		("@s9s_mb_2u_lib.s9s_mb_2u(sch_1):page475_i16@pure_quanta.q_res(chips)"
			("LOCATION" "R847")
		)
		("@s9s_mb_2u_lib.s9s_mb_2u(sch_1):page475_i15@pure_quanta.q_res(chips)"
			("LOCATION" "R848")
		)
		("@s9s_mb_2u_lib.s9s_mb_2u(sch_1):page475_i14@pure_quanta.q_res(chips)"
			("LOCATION" "R849")
		)
		("@s9s_mb_2u_lib.s9s_mb_2u(sch_1):page475_i13@pure_quanta.q_res(chips)"
			("LOCATION" "R850")
		)
		("@s9s_mb_2u_lib.s9s_mb_2u(sch_1):page475_i12@pure_quanta.q_res(chips)"
			("LOCATION" "R851")
		)
		("@s9s_mb_2u_lib.s9s_mb_2u(sch_1):page475_i11@pure_quanta.q_res(chips)"
			("LOCATION" "R852")
		)
		("@s9s_mb_2u_lib.s9s_mb_2u(sch_1):page475_i10@pure_quanta.q_res(chips)"
			("LOCATION" "R853")
		)
		("@s9s_mb_2u_lib.s9s_mb_2u(sch_1):page475_i9@pure_quanta.q_res(chips)"
			("LOCATION" "R854")
		)
		("@s9s_mb_2u_lib.s9s_mb_2u(sch_1):page475_i55@pure_quanta.q_res(chips)"
			("LOCATION" "R855")
		)
		("@s9s_mb_2u_lib.s9s_mb_2u(sch_1):page475_i54@pure_quanta.q_res(chips)"
			("LOCATION" "R856")
		)
		("@s9s_mb_2u_lib.s9s_mb_2u(sch_1):page475_i53@pure_quanta.q_res(chips)"
			("LOCATION" "R857")
		)
		("@s9s_mb_2u_lib.s9s_mb_2u(sch_1):page475_i52@pure_quanta.q_res(chips)"
			("LOCATION" "R858")
		)
		("@s9s_mb_2u_lib.s9s_mb_2u(sch_1):page475_i50@pure_quanta.q_res(chips)"
			("LOCATION" "R859")
		)
		("@s9s_mb_2u_lib.s9s_mb_2u(sch_1):page475_i51@pure_quanta.q_res(chips)"
			("LOCATION" "R860")
		)
		("@s9s_mb_2u_lib.s9s_mb_2u(sch_1):page475_i48@pure_quanta.q_res(chips)"
			("LOCATION" "R861")
		)
		("@s9s_mb_2u_lib.s9s_mb_2u(sch_1):page475_i49@pure_quanta.q_res(chips)"
			("LOCATION" "R862")
		)
		("@s9s_mb_2u_lib.s9s_mb_2u(sch_1):page475_i40@pure_quanta.q_res(chips)"
			("LOCATION" "R863")
		)
		("@s9s_mb_2u_lib.s9s_mb_2u(sch_1):page475_i38@pure_quanta.q_res(chips)"
			("LOCATION" "R864")
		)
		("@s9s_mb_2u_lib.s9s_mb_2u(sch_1):page475_i74@pure_quanta.q_res(chips)"
			("LOCATION" "R865")
		)
		("@s9s_mb_2u_lib.s9s_mb_2u(sch_1):page475_i62@pure_quanta.q_res(chips)"
			("LOCATION" "R866")
		)
		("@s9s_mb_2u_lib.s9s_mb_2u(sch_1):page475_i28@pure_quanta.q_res(chips)"
			("LOCATION" "R867")
		)
		("@s9s_mb_2u_lib.s9s_mb_2u(sch_1):page475_i27@pure_quanta.q_res(chips)"
			("LOCATION" "R868")
		)
		("@s9s_mb_2u_lib.s9s_mb_2u(sch_1):page475_i26@pure_quanta.q_res(chips)"
			("LOCATION" "R869")
		)
		("@s9s_mb_2u_lib.s9s_mb_2u(sch_1):page475_i25@pure_quanta.q_res(chips)"
			("LOCATION" "R870")
		)
		("@s9s_mb_2u_lib.s9s_mb_2u(sch_1):page475_i61@pure_quanta.q_res(chips)"
			("LOCATION" "R871")
		)
		("@s9s_mb_2u_lib.s9s_mb_2u(sch_1):page475_i60@pure_quanta.q_res(chips)"
			("LOCATION" "R872")
		)
		("@s9s_mb_2u_lib.s9s_mb_2u(sch_1):page475_i59@pure_quanta.q_res(chips)"
			("LOCATION" "R873")
		)
		("@s9s_mb_2u_lib.s9s_mb_2u(sch_1):page475_i58@pure_quanta.q_res(chips)"
			("LOCATION" "R874")
		)
		("@s9s_mb_2u_lib.s9s_mb_2u(sch_1):page475_i39@pure_quanta.q_res(chips)"
			("LOCATION" "R875")
		)
		("@s9s_mb_2u_lib.s9s_mb_2u(sch_1):page475_i64@pure_quanta.q_res(chips)"
			("LOCATION" "R876")
		)
		("@s9s_mb_2u_lib.s9s_mb_2u(sch_1):page475_i80@pure_quanta.q_res(chips)"
			("LOCATION" "R932")
		)
		("@s9s_mb_2u_lib.s9s_mb_2u(sch_1):page475_i82@pure_quanta.q_res(chips)"
			("LOCATION" "R933")
		)
		("@s9s_mb_2u_lib.s9s_mb_2u(sch_1):page475_i79@pure_quanta.q_res(chips)"
			("LOCATION" "R934")
		)
		("@s9s_mb_2u_lib.s9s_mb_2u(sch_1):page475_i86@pure_quanta.q_res(chips)"
			("LOCATION" "R935")
		)
		("@s9s_mb_2u_lib.s9s_mb_2u(sch_1):page475_i78@pure_quanta.q_res(chips)"
			("LOCATION" "R936")
		)
		("@s9s_mb_2u_lib.s9s_mb_2u(sch_1):page475_i85@pure_quanta.q_res(chips)"
			("LOCATION" "R937")
		)
		("@s9s_mb_2u_lib.s9s_mb_2u(sch_1):page475_i77@pure_quanta.q_res(chips)"
			("LOCATION" "R938")
		)
		("@s9s_mb_2u_lib.s9s_mb_2u(sch_1):page475_i83@pure_quanta.q_res(chips)"
			("LOCATION" "R939")
		)
		("@s9s_mb_2u_lib.s9s_mb_2u(sch_1):page475_i24@pure_quanta.gtl2014pw(chips)"
			("LOCATION" "U25")
		)
		("@s9s_mb_2u_lib.s9s_mb_2u(sch_1):page475_i76@pure_quanta.gtl2014pw(chips)"
			("LOCATION" "U26")
		)
		("@s9s_mb_2u_lib.s9s_mb_2u(sch_1):page557_i8@pure_quanta.q_cap(chips)"
			("LOCATION" "C559")
		)
		("@s9s_mb_2u_lib.s9s_mb_2u(sch_1):page557_i39@pure_quanta.q_cap(chips)"
			("LOCATION" "C560")
		)
		("@s9s_mb_2u_lib.s9s_mb_2u(sch_1):page557_i13@pure_quanta.q_cap(chips)"
			("LOCATION" "C561")
		)
		("@s9s_mb_2u_lib.s9s_mb_2u(sch_1):page557_i35@pure_quanta.q_cap(chips)"
			("LOCATION" "C562")
		)
		("@s9s_mb_2u_lib.s9s_mb_2u(sch_1):page557_i3@pure_quanta.q_res(chips)"
			("LOCATION" "R909")
		)
		("@s9s_mb_2u_lib.s9s_mb_2u(sch_1):page557_i20@pure_quanta.q_res(chips)"
			("LOCATION" "R910")
		)
		("@s9s_mb_2u_lib.s9s_mb_2u(sch_1):page557_i21@pure_quanta.q_res(chips)"
			("LOCATION" "R911")
		)
		("@s9s_mb_2u_lib.s9s_mb_2u(sch_1):page557_i4@pure_quanta.q_res(chips)"
			("LOCATION" "R960")
		)
		("@s9s_mb_2u_lib.s9s_mb_2u(sch_1):page557_i43@pure_quanta.q_res(chips)"
			("LOCATION" "R961")
		)
		("@s9s_mb_2u_lib.s9s_mb_2u(sch_1):page557_i44@pure_quanta.q_res(chips)"
			("LOCATION" "R962")
		)
		("@s9s_mb_2u_lib.s9s_mb_2u(sch_1):page557_i42@pure_quanta.q_res(chips)"
			("LOCATION" "R963")
		)
		("@s9s_mb_2u_lib.s9s_mb_2u(sch_1):page557_i40@pure_quanta.q_res(chips)"
			("LOCATION" "R964")
		)
		("@s9s_mb_2u_lib.s9s_mb_2u(sch_1):page557_i24@pure_quanta.q_res(chips)"
			("LOCATION" "R965")
		)
		("@s9s_mb_2u_lib.s9s_mb_2u(sch_1):page557_i33@pure_quanta.q_res(chips)"
			("LOCATION" "R966")
		)
		("@s9s_mb_2u_lib.s9s_mb_2u(sch_1):page557_i23@pure_quanta.q_res(chips)"
			("LOCATION" "R967")
		)
		("@s9s_mb_2u_lib.s9s_mb_2u(sch_1):page557_i32@pure_quanta.q_res(chips)"
			("LOCATION" "R968")
		)
		("@s9s_mb_2u_lib.s9s_mb_2u(sch_1):page557_i1@pure_quanta.pca9617adp(chips)"
			("LOCATION" "U28")
		)
		("@s9s_mb_2u_lib.s9s_mb_2u(sch_1):page557_i26@pure_quanta.pca9617adp(chips)"
			("LOCATION" "U29")
		)
		("@s9s_mb_2u_lib.s9s_mb_2u(sch_1):page618_i6@pure_quanta.q_cap(chips)"
			("LOCATION" "C564")
		)
		("@s9s_mb_2u_lib.s9s_mb_2u(sch_1):page618_i16@pure_quanta.q_cap(chips)"
			("LOCATION" "C565")
		)
		("@s9s_mb_2u_lib.s9s_mb_2u(sch_1):page618_i18@pure_quanta.q_cap(chips)"
			("LOCATION" "C566")
		)
		("@s9s_mb_2u_lib.s9s_mb_2u(sch_1):page618_i59@pure_quanta.q_cap(chips)"
			("LOCATION" "C1337")
		)
		("@s9s_mb_2u_lib.s9s_mb_2u(sch_1):page618_i60@pure_quanta.q_cap(chips)"
			("LOCATION" "C1341")
		)
		("@s9s_mb_2u_lib.s9s_mb_2u(sch_1):page618_i56@pure_quanta.q_cap(chips)"
			("LOCATION" "C1342")
		)
		("@s9s_mb_2u_lib.s9s_mb_2u(sch_1):page618_i55@pure_quanta.q_cap(chips)"
			("LOCATION" "C1343")
		)
		("@s9s_mb_2u_lib.s9s_mb_2u(sch_1):page618_i1@pure_quanta.conn9_2ub3903013101f(chips)"
			("LOCATION" "J48")
		)
		("@s9s_mb_2u_lib.s9s_mb_2u(sch_1):page618_i15@pure_quanta.q_inductor4p_12(chips)"
			("LOCATION" "L5")
		)
		("@s9s_mb_2u_lib.s9s_mb_2u(sch_1):page618_i24@pure_quanta.q_inductor4p_12(chips)"
			("LOCATION" "L6")
		)
		("@s9s_mb_2u_lib.s9s_mb_2u(sch_1):page618_i48@pure_quanta.q_inductor4p_12(chips)"
			("LOCATION" "L9")
		)
		("@s9s_mb_2u_lib.s9s_mb_2u(sch_1):page618_i4@pure_quanta.q_res(chips)"
			("LOCATION" "R461")
		)
		("@s9s_mb_2u_lib.s9s_mb_2u(sch_1):page618_i8@pure_quanta.q_res(chips)"
			("LOCATION" "R462")
		)
		("@s9s_mb_2u_lib.s9s_mb_2u(sch_1):page618_i11@pure_quanta.q_res(chips)"
			("LOCATION" "R463")
		)
		("@s9s_mb_2u_lib.s9s_mb_2u(sch_1):page618_i20@pure_quanta.q_res(chips)"
			("LOCATION" "R464")
		)
		("@s9s_mb_2u_lib.s9s_mb_2u(sch_1):page618_i21@pure_quanta.q_res(chips)"
			("LOCATION" "R465")
		)
		("@s9s_mb_2u_lib.s9s_mb_2u(sch_1):page618_i27@pure_quanta.q_res(chips)"
			("LOCATION" "R466")
		)
		("@s9s_mb_2u_lib.s9s_mb_2u(sch_1):page618_i28@pure_quanta.q_res(chips)"
			("LOCATION" "R468")
		)
		("@s9s_mb_2u_lib.s9s_mb_2u(sch_1):page618_i51@pure_quanta.q_res(chips)"
			("LOCATION" "R469")
		)
		("@s9s_mb_2u_lib.s9s_mb_2u(sch_1):page618_i52@pure_quanta.q_res(chips)"
			("LOCATION" "R470")
		)
		("@s9s_mb_2u_lib.s9s_mb_2u(sch_1):page618_i13@pure_quanta.q_res(chips)"
			("LOCATION" "R471")
		)
		("@s9s_mb_2u_lib.s9s_mb_2u(sch_1):page618_i2@pure_quanta.tps2553dbvr1(chips)"
			("LOCATION" "U27")
		)
		("@s9s_mb_2u_lib.s9s_mb_2u(sch_1):page558_i29@pure_quanta.q_cap(chips)"
			("LOCATION" "C567")
		)
		("@s9s_mb_2u_lib.s9s_mb_2u(sch_1):page558_i57@pure_quanta.q_cap(chips)"
			("LOCATION" "C568")
		)
		("@s9s_mb_2u_lib.s9s_mb_2u(sch_1):page558_i31@pure_quanta.q_cap(chips)"
			("LOCATION" "C569")
		)
		("@s9s_mb_2u_lib.s9s_mb_2u(sch_1):page558_i53@pure_quanta.q_cap(chips)"
			("LOCATION" "C570")
		)
		("@s9s_mb_2u_lib.s9s_mb_2u(sch_1):page558_i69@pure_quanta.q_res(chips)"
			("LOCATION" "R448")
		)
		("@s9s_mb_2u_lib.s9s_mb_2u(sch_1):page558_i25@pure_quanta.q_res(chips)"
			("LOCATION" "R969")
		)
		("@s9s_mb_2u_lib.s9s_mb_2u(sch_1):page558_i63@pure_quanta.q_res(chips)"
			("LOCATION" "R970")
		)
		("@s9s_mb_2u_lib.s9s_mb_2u(sch_1):page558_i27@pure_quanta.q_res(chips)"
			("LOCATION" "R971")
		)
		("@s9s_mb_2u_lib.s9s_mb_2u(sch_1):page558_i62@pure_quanta.q_res(chips)"
			("LOCATION" "R972")
		)
		("@s9s_mb_2u_lib.s9s_mb_2u(sch_1):page558_i43@pure_quanta.q_res(chips)"
			("LOCATION" "R973")
		)
		("@s9s_mb_2u_lib.s9s_mb_2u(sch_1):page558_i42@pure_quanta.q_res(chips)"
			("LOCATION" "R974")
		)
		("@s9s_mb_2u_lib.s9s_mb_2u(sch_1):page558_i58@pure_quanta.q_res(chips)"
			("LOCATION" "R975")
		)
		("@s9s_mb_2u_lib.s9s_mb_2u(sch_1):page558_i60@pure_quanta.q_res(chips)"
			("LOCATION" "R976")
		)
		("@s9s_mb_2u_lib.s9s_mb_2u(sch_1):page558_i41@pure_quanta.q_res(chips)"
			("LOCATION" "R977")
		)
		("@s9s_mb_2u_lib.s9s_mb_2u(sch_1):page558_i51@pure_quanta.q_res(chips)"
			("LOCATION" "R978")
		)
		("@s9s_mb_2u_lib.s9s_mb_2u(sch_1):page558_i35@pure_quanta.q_res(chips)"
			("LOCATION" "R979")
		)
		("@s9s_mb_2u_lib.s9s_mb_2u(sch_1):page558_i49@pure_quanta.q_res(chips)"
			("LOCATION" "R980")
		)
		("@s9s_mb_2u_lib.s9s_mb_2u(sch_1):page558_i45@pure_quanta.q_res(chips)"
			("LOCATION" "R993")
		)
		("@s9s_mb_2u_lib.s9s_mb_2u(sch_1):page558_i44@pure_quanta.q_res(chips)"
			("LOCATION" "R994")
		)
		("@s9s_mb_2u_lib.s9s_mb_2u(sch_1):page558_i64@pure_quanta.q_res(chips)"
			("LOCATION" "R995")
		)
		("@s9s_mb_2u_lib.s9s_mb_2u(sch_1):page558_i65@pure_quanta.q_res(chips)"
			("LOCATION" "R996")
		)
		("@s9s_mb_2u_lib.s9s_mb_2u(sch_1):page558_i68@pure_quanta.q_res(chips)"
			("LOCATION" "R1648")
		)
		("@s9s_mb_2u_lib.s9s_mb_2u(sch_1):page558_i75@pure_quanta.q_res(chips)"
			("LOCATION" "R1759")
		)
		("@s9s_mb_2u_lib.s9s_mb_2u(sch_1):page558_i74@pure_quanta.q_res(chips)"
			("LOCATION" "R1760")
		)
		("@s9s_mb_2u_lib.s9s_mb_2u(sch_1):page558_i76@pure_quanta.q_res(chips)"
			("LOCATION" "R1829")
		)
		("@s9s_mb_2u_lib.s9s_mb_2u(sch_1):page558_i77@pure_quanta.q_res(chips)"
			("LOCATION" "R1830")
		)
		("@s9s_mb_2u_lib.s9s_mb_2u(sch_1):page558_i16@pure_quanta.pca9617adp(chips)"
			("LOCATION" "U30")
		)
		("@s9s_mb_2u_lib.s9s_mb_2u(sch_1):page558_i46@pure_quanta.pca9617adp(chips)"
			("LOCATION" "U31")
		)
		("@s9s_mb_2u_lib.s9s_mb_2u(sch_1):page456_i77@pure_quanta.q_cap(chips)"
			("LOCATION" "C574")
		)
		("@s9s_mb_2u_lib.s9s_mb_2u(sch_1):page456_i19@pure_quanta.q_cap(chips)"
			("LOCATION" "C575")
		)
		("@s9s_mb_2u_lib.s9s_mb_2u(sch_1):page456_i28@pure_quanta.q_cap(chips)"
			("LOCATION" "C576")
		)
		("@s9s_mb_2u_lib.s9s_mb_2u(sch_1):page456_i11@pure_quanta.q_cap(chips)"
			("LOCATION" "C577")
		)
		("@s9s_mb_2u_lib.s9s_mb_2u(sch_1):page456_i36@pure_quanta.\\2n7002a7\\(chips)"
			("LOCATION" "Q21")
		)
		("@s9s_mb_2u_lib.s9s_mb_2u(sch_1):page456_i33@pure_quanta.\\2n7002a7\\(chips)"
			("LOCATION" "Q22")
		)
		("@s9s_mb_2u_lib.s9s_mb_2u(sch_1):page456_i48@pure_quanta.q_res(chips)"
			("LOCATION" "R1112")
		)
		("@s9s_mb_2u_lib.s9s_mb_2u(sch_1):page456_i50@pure_quanta.q_res(chips)"
			("LOCATION" "R1113")
		)
		("@s9s_mb_2u_lib.s9s_mb_2u(sch_1):page456_i47@pure_quanta.q_res(chips)"
			("LOCATION" "R1114")
		)
		("@s9s_mb_2u_lib.s9s_mb_2u(sch_1):page456_i49@pure_quanta.q_res(chips)"
			("LOCATION" "R1115")
		)
		("@s9s_mb_2u_lib.s9s_mb_2u(sch_1):page456_i45@pure_quanta.q_res(chips)"
			("LOCATION" "R1116")
		)
		("@s9s_mb_2u_lib.s9s_mb_2u(sch_1):page456_i46@pure_quanta.q_res(chips)"
			("LOCATION" "R1117")
		)
		("@s9s_mb_2u_lib.s9s_mb_2u(sch_1):page456_i79@pure_quanta.q_res(chips)"
			("LOCATION" "R1118")
		)
		("@s9s_mb_2u_lib.s9s_mb_2u(sch_1):page456_i23@pure_quanta.q_res(chips)"
			("LOCATION" "R1119")
		)
		("@s9s_mb_2u_lib.s9s_mb_2u(sch_1):page456_i22@pure_quanta.q_res(chips)"
			("LOCATION" "R1120")
		)
		("@s9s_mb_2u_lib.s9s_mb_2u(sch_1):page456_i16@pure_quanta.q_res(chips)"
			("LOCATION" "R1121")
		)
		("@s9s_mb_2u_lib.s9s_mb_2u(sch_1):page456_i35@pure_quanta.q_res(chips)"
			("LOCATION" "R1122")
		)
		("@s9s_mb_2u_lib.s9s_mb_2u(sch_1):page456_i62@pure_quanta.q_res(chips)"
			("LOCATION" "R1920")
		)
		("@s9s_mb_2u_lib.s9s_mb_2u(sch_1):page456_i82@pure_quanta.mosfet_n(chips)"
			("LOCATION" "U44")
		)
		("@s9s_mb_2u_lib.s9s_mb_2u(sch_1):page456_i73@pure_quanta.sn74lvc1g08dbvr(chips)"
			("LOCATION" "U45")
		)
		("@s9s_mb_2u_lib.s9s_mb_2u(sch_1):page456_i21@pure_quanta.pca9555pw(chips)"
			("LOCATION" "U46")
		)
		("@s9s_mb_2u_lib.s9s_mb_2u(sch_1):page456_i26@pure_quanta.apx80929sag7(chips)"
			("LOCATION" "U47")
		)
		("@s9s_mb_2u_lib.s9s_mb_2u(sch_1):page456_i14@pure_quanta.sn74lvc1g08dbvr(chips)"
			("LOCATION" "U48")
		)
		("@s9s_mb_2u_lib.s9s_mb_2u(sch_1):page508_i68@pure_quanta.q_cap(chips)"
			("LOCATION" "C578")
		)
		("@s9s_mb_2u_lib.s9s_mb_2u(sch_1):page508_i26@pure_quanta.q_cap(chips)"
			("LOCATION" "C579")
		)
		("@s9s_mb_2u_lib.s9s_mb_2u(sch_1):page508_i48@pure_quanta.q_cap(chips)"
			("LOCATION" "C580")
		)
		("@s9s_mb_2u_lib.s9s_mb_2u(sch_1):page508_i10@pure_quanta.q_cap(chips)"
			("LOCATION" "C581")
		)
		("@s9s_mb_2u_lib.s9s_mb_2u(sch_1):page508_i23@pure_quanta.\\2n7002a7\\(chips)"
			("LOCATION" "Q23")
		)
		("@s9s_mb_2u_lib.s9s_mb_2u(sch_1):page508_i15@pure_quanta.\\2n7002a7\\(chips)"
			("LOCATION" "Q24")
		)
		("@s9s_mb_2u_lib.s9s_mb_2u(sch_1):page508_i39@pure_quanta.q_res(chips)"
			("LOCATION" "R1123")
		)
		("@s9s_mb_2u_lib.s9s_mb_2u(sch_1):page508_i45@pure_quanta.q_res(chips)"
			("LOCATION" "R1124")
		)
		("@s9s_mb_2u_lib.s9s_mb_2u(sch_1):page508_i37@pure_quanta.q_res(chips)"
			("LOCATION" "R1125")
		)
		("@s9s_mb_2u_lib.s9s_mb_2u(sch_1):page508_i42@pure_quanta.q_res(chips)"
			("LOCATION" "R1126")
		)
		("@s9s_mb_2u_lib.s9s_mb_2u(sch_1):page508_i36@pure_quanta.q_res(chips)"
			("LOCATION" "R1127")
		)
		("@s9s_mb_2u_lib.s9s_mb_2u(sch_1):page508_i40@pure_quanta.q_res(chips)"
			("LOCATION" "R1128")
		)
		("@s9s_mb_2u_lib.s9s_mb_2u(sch_1):page508_i72@pure_quanta.q_res(chips)"
			("LOCATION" "R1129")
		)
		("@s9s_mb_2u_lib.s9s_mb_2u(sch_1):page508_i30@pure_quanta.q_res(chips)"
			("LOCATION" "R1130")
		)
		("@s9s_mb_2u_lib.s9s_mb_2u(sch_1):page508_i31@pure_quanta.q_res(chips)"
			("LOCATION" "R1131")
		)
		("@s9s_mb_2u_lib.s9s_mb_2u(sch_1):page508_i18@pure_quanta.q_res(chips)"
			("LOCATION" "R1132")
		)
		("@s9s_mb_2u_lib.s9s_mb_2u(sch_1):page508_i21@pure_quanta.q_res(chips)"
			("LOCATION" "R1133")
		)
		("@s9s_mb_2u_lib.s9s_mb_2u(sch_1):page508_i64@pure_quanta.q_res(chips)"
			("LOCATION" "R1921")
		)
		("@s9s_mb_2u_lib.s9s_mb_2u(sch_1):page508_i76@pure_quanta.mosfet_n(chips)"
			("LOCATION" "U49")
		)
		("@s9s_mb_2u_lib.s9s_mb_2u(sch_1):page508_i73@pure_quanta.sn74lvc1g08dbvr(chips)"
			("LOCATION" "U50")
		)
		("@s9s_mb_2u_lib.s9s_mb_2u(sch_1):page508_i28@pure_quanta.pca9555pw(chips)"
			("LOCATION" "U51")
		)
		("@s9s_mb_2u_lib.s9s_mb_2u(sch_1):page508_i46@pure_quanta.apx80929sag7(chips)"
			("LOCATION" "U52")
		)
		("@s9s_mb_2u_lib.s9s_mb_2u(sch_1):page508_i12@pure_quanta.sn74lvc1g08dbvr(chips)"
			("LOCATION" "U53")
		)
		("@s9s_mb_2u_lib.s9s_mb_2u(sch_1):page505_i38@pure_quanta.q_cap(chips)"
			("LOCATION" "C584")
		)
		("@s9s_mb_2u_lib.s9s_mb_2u(sch_1):page505_i3@pure_quanta.q_cap(chips)"
			("LOCATION" "C1174")
		)
		("@s9s_mb_2u_lib.s9s_mb_2u(sch_1):page505_i32@pure_quanta.q_cap(chips)"
			("LOCATION" "C1176")
		)
		("@s9s_mb_2u_lib.s9s_mb_2u(sch_1):page505_i51@pure_quanta.q_cap(chips)"
			("LOCATION" "C1298")
		)
		("@s9s_mb_2u_lib.s9s_mb_2u(sch_1):page505_i60@pure_quanta.q_cap(chips)"
			("LOCATION" "C1299")
		)
		("@s9s_mb_2u_lib.s9s_mb_2u(sch_1):page505_i64@pure_quanta.q_res(chips)"
			("LOCATION" "R1501")
		)
		("@s9s_mb_2u_lib.s9s_mb_2u(sch_1):page505_i9@pure_quanta.q_res(chips)"
			("LOCATION" "R1506")
		)
		("@s9s_mb_2u_lib.s9s_mb_2u(sch_1):page505_i8@pure_quanta.q_res(chips)"
			("LOCATION" "R1507")
		)
		("@s9s_mb_2u_lib.s9s_mb_2u(sch_1):page505_i7@pure_quanta.q_res(chips)"
			("LOCATION" "R1508")
		)
		("@s9s_mb_2u_lib.s9s_mb_2u(sch_1):page505_i4@pure_quanta.q_res(chips)"
			("LOCATION" "R1509")
		)
		("@s9s_mb_2u_lib.s9s_mb_2u(sch_1):page505_i15@pure_quanta.q_res(chips)"
			("LOCATION" "R1510")
		)
		("@s9s_mb_2u_lib.s9s_mb_2u(sch_1):page505_i18@pure_quanta.q_res(chips)"
			("LOCATION" "R1511")
		)
		("@s9s_mb_2u_lib.s9s_mb_2u(sch_1):page505_i27@pure_quanta.q_res(chips)"
			("LOCATION" "R1596")
		)
		("@s9s_mb_2u_lib.s9s_mb_2u(sch_1):page505_i21@pure_quanta.q_res(chips)"
			("LOCATION" "R1597")
		)
		("@s9s_mb_2u_lib.s9s_mb_2u(sch_1):page505_i33@pure_quanta.q_res(chips)"
			("LOCATION" "R1598")
		)
		("@s9s_mb_2u_lib.s9s_mb_2u(sch_1):page505_i23@pure_quanta.q_res(chips)"
			("LOCATION" "R1599")
		)
		("@s9s_mb_2u_lib.s9s_mb_2u(sch_1):page505_i67@pure_quanta.q_res(chips)"
			("LOCATION" "R1699")
		)
		("@s9s_mb_2u_lib.s9s_mb_2u(sch_1):page505_i68@pure_quanta.q_res(chips)"
			("LOCATION" "R1825")
		)
		("@s9s_mb_2u_lib.s9s_mb_2u(sch_1):page505_i70@pure_quanta.q_res(chips)"
			("LOCATION" "R1899")
		)
		("@s9s_mb_2u_lib.s9s_mb_2u(sch_1):page505_i71@pure_quanta.q_res(chips)"
			("LOCATION" "R1900")
		)
		("@s9s_mb_2u_lib.s9s_mb_2u(sch_1):page505_i72@pure_quanta.q_res(chips)"
			("LOCATION" "R1901")
		)
		("@s9s_mb_2u_lib.s9s_mb_2u(sch_1):page505_i75@pure_quanta.q_res(chips)"
			("LOCATION" "R1902")
		)
		("@s9s_mb_2u_lib.s9s_mb_2u(sch_1):page505_i76@pure_quanta.q_res(chips)"
			("LOCATION" "R1903")
		)
		("@s9s_mb_2u_lib.s9s_mb_2u(sch_1):page505_i74@pure_quanta.q_res(chips)"
			("LOCATION" "R1904")
		)
		("@s9s_mb_2u_lib.s9s_mb_2u(sch_1):page505_i5@pure_quanta.sn74lvc1g17dckr(chips)"
			("LOCATION" "U76")
		)
		("@s9s_mb_2u_lib.s9s_mb_2u(sch_1):page505_i69@pure_quanta.\\74lvc1g07gv\\(chips)"
			("LOCATION" "U78")
		)
		("@s9s_mb_2u_lib.s9s_mb_2u(sch_1):page505_i29@pure_quanta.\\74lvc1g126gw\\(chips)"
			("LOCATION" "U88")
		)
		("@s9s_mb_2u_lib.s9s_mb_2u(sch_1):page505_i50@pure_quanta.\\74cbtlv3126pw\\(chips)"
			("LOCATION" "U91")
		)
		("@s9s_mb_2u_lib.s9s_mb_2u(sch_1):page505_i63@pure_quanta.\\74cbtlv3126pw\\(chips)"
			("LOCATION" "U92")
		)
		("@s9s_mb_2u_lib.s9s_mb_2u(sch_1):page465_i37@pure_quanta.q_cap(chips)"
			("LOCATION" "C605")
		)
		("@s9s_mb_2u_lib.s9s_mb_2u(sch_1):page465_i45@pure_quanta.q_cap(chips)"
			("LOCATION" "C606")
		)
		("@s9s_mb_2u_lib.s9s_mb_2u(sch_1):page465_i36@pure_quanta.q_cap(chips)"
			("LOCATION" "C607")
		)
		("@s9s_mb_2u_lib.s9s_mb_2u(sch_1):page465_i43@pure_quanta.q_cap(chips)"
			("LOCATION" "C608")
		)
		("@s9s_mb_2u_lib.s9s_mb_2u(sch_1):page465_i16@pure_quanta.q_res(chips)"
			("LOCATION" "R1208")
		)
		("@s9s_mb_2u_lib.s9s_mb_2u(sch_1):page465_i2@pure_quanta.q_res(chips)"
			("LOCATION" "R1209")
		)
		("@s9s_mb_2u_lib.s9s_mb_2u(sch_1):page465_i1@pure_quanta.q_res(chips)"
			("LOCATION" "R1210")
		)
		("@s9s_mb_2u_lib.s9s_mb_2u(sch_1):page465_i3@pure_quanta.q_res(chips)"
			("LOCATION" "R1211")
		)
		("@s9s_mb_2u_lib.s9s_mb_2u(sch_1):page465_i4@pure_quanta.q_res(chips)"
			("LOCATION" "R1212")
		)
		("@s9s_mb_2u_lib.s9s_mb_2u(sch_1):page465_i13@pure_quanta.q_res(chips)"
			("LOCATION" "R1213")
		)
		("@s9s_mb_2u_lib.s9s_mb_2u(sch_1):page465_i33@pure_quanta.q_res(chips)"
			("LOCATION" "R1214")
		)
		("@s9s_mb_2u_lib.s9s_mb_2u(sch_1):page465_i38@pure_quanta.q_res(chips)"
			("LOCATION" "R1215")
		)
		("@s9s_mb_2u_lib.s9s_mb_2u(sch_1):page465_i52@pure_quanta.q_res(chips)"
			("LOCATION" "R1479")
		)
		("@s9s_mb_2u_lib.s9s_mb_2u(sch_1):page465_i54@pure_quanta.q_res(chips)"
			("LOCATION" "R1748")
		)
		("@s9s_mb_2u_lib.s9s_mb_2u(sch_1):page465_i58@pure_quanta.q_res(chips)"
			("LOCATION" "R1749")
		)
		("@s9s_mb_2u_lib.s9s_mb_2u(sch_1):page465_i59@pure_quanta.q_res(chips)"
			("LOCATION" "R1750")
		)
		("@s9s_mb_2u_lib.s9s_mb_2u(sch_1):page465_i61@pure_quanta.q_res(chips)"
			("LOCATION" "R1868")
		)
		("@s9s_mb_2u_lib.s9s_mb_2u(sch_1):page465_i62@pure_quanta.q_res(chips)"
			("LOCATION" "R1869")
		)
		("@s9s_mb_2u_lib.s9s_mb_2u(sch_1):page465_i63@pure_quanta.q_res(chips)"
			("LOCATION" "R1870")
		)
		("@s9s_mb_2u_lib.s9s_mb_2u(sch_1):page465_i64@pure_quanta.q_res(chips)"
			("LOCATION" "R1871")
		)
		("@s9s_mb_2u_lib.s9s_mb_2u(sch_1):page465_i65@pure_quanta.q_res(chips)"
			("LOCATION" "R1872")
		)
		("@s9s_mb_2u_lib.s9s_mb_2u(sch_1):page465_i68@pure_quanta.q_res(chips)"
			("LOCATION" "R1873")
		)
		("@s9s_mb_2u_lib.s9s_mb_2u(sch_1):page465_i69@pure_quanta.q_res(chips)"
			("LOCATION" "R1874")
		)
		("@s9s_mb_2u_lib.s9s_mb_2u(sch_1):page465_i67@pure_quanta.q_res(chips)"
			("LOCATION" "R1875")
		)
		("@s9s_mb_2u_lib.s9s_mb_2u(sch_1):page465_i66@pure_quanta.q_res(chips)"
			("LOCATION" "R1876")
		)
		("@s9s_mb_2u_lib.s9s_mb_2u(sch_1):page465_i34@pure_quanta.nc7sb3157(chips)"
			("LOCATION" "U60")
		)
		("@s9s_mb_2u_lib.s9s_mb_2u(sch_1):page465_i39@pure_quanta.nc7sb3157(chips)"
			("LOCATION" "U61")
		)
		("@s9s_mb_2u_lib.s9s_mb_2u(sch_1):page473_i68@pure_quanta.q_cap(chips)"
			("LOCATION" "C613")
		)
		("@s9s_mb_2u_lib.s9s_mb_2u(sch_1):page473_i65@pure_quanta.q_cap(chips)"
			("LOCATION" "C614")
		)
		("@s9s_mb_2u_lib.s9s_mb_2u(sch_1):page473_i62@pure_quanta.q_cap(chips)"
			("LOCATION" "C615")
		)
		("@s9s_mb_2u_lib.s9s_mb_2u(sch_1):page473_i59@pure_quanta.q_cap(chips)"
			("LOCATION" "C616")
		)
		("@s9s_mb_2u_lib.s9s_mb_2u(sch_1):page473_i77@pure_quanta.q_cap(chips)"
			("LOCATION" "C617")
		)
		("@s9s_mb_2u_lib.s9s_mb_2u(sch_1):page473_i70@pure_quanta.q_cap(chips)"
			("LOCATION" "C618")
		)
		("@s9s_mb_2u_lib.s9s_mb_2u(sch_1):page473_i71@pure_quanta.q_cap(chips)"
			("LOCATION" "C619")
		)
		("@s9s_mb_2u_lib.s9s_mb_2u(sch_1):page473_i74@pure_quanta.q_cap(chips)"
			("LOCATION" "C620")
		)
		("@s9s_mb_2u_lib.s9s_mb_2u(sch_1):page473_i82@pure_quanta.mosfet_nch_dual(chips)"
			("LOCATION" "Q1")
		)
		("@s9s_mb_2u_lib.s9s_mb_2u(sch_1):page473_i40@pure_quanta.mosfet_nch_dual(chips)"
			("LOCATION" "Q1")
		)
		("@s9s_mb_2u_lib.s9s_mb_2u(sch_1):page473_i83@pure_quanta.mosfet_nch_dual(chips)"
			("LOCATION" "Q2")
		)
		("@s9s_mb_2u_lib.s9s_mb_2u(sch_1):page473_i12@pure_quanta.mosfet_nch_dual(chips)"
			("LOCATION" "Q2")
		)
		("@s9s_mb_2u_lib.s9s_mb_2u(sch_1):page473_i80@pure_quanta.mosfet_nch_dual(chips)"
			("LOCATION" "Q13")
		)
		("@s9s_mb_2u_lib.s9s_mb_2u(sch_1):page473_i23@pure_quanta.mosfet_nch_dual(chips)"
			("LOCATION" "Q13")
		)
		("@s9s_mb_2u_lib.s9s_mb_2u(sch_1):page473_i81@pure_quanta.mosfet_nch_dual(chips)"
			("LOCATION" "Q14")
		)
		("@s9s_mb_2u_lib.s9s_mb_2u(sch_1):page473_i28@pure_quanta.mosfet_nch_dual(chips)"
			("LOCATION" "Q14")
		)
		("@s9s_mb_2u_lib.s9s_mb_2u(sch_1):page473_i63@pure_quanta.q_res(chips)"
			("LOCATION" "R701")
		)
		("@s9s_mb_2u_lib.s9s_mb_2u(sch_1):page473_i76@pure_quanta.q_res(chips)"
			("LOCATION" "R702")
		)
		("@s9s_mb_2u_lib.s9s_mb_2u(sch_1):page473_i79@pure_quanta.q_res(chips)"
			("LOCATION" "R703")
		)
		("@s9s_mb_2u_lib.s9s_mb_2u(sch_1):page473_i75@pure_quanta.q_res(chips)"
			("LOCATION" "R704")
		)
		("@s9s_mb_2u_lib.s9s_mb_2u(sch_1):page473_i2@pure_quanta.q_res(chips)"
			("LOCATION" "R807")
		)
		("@s9s_mb_2u_lib.s9s_mb_2u(sch_1):page473_i31@pure_quanta.q_res(chips)"
			("LOCATION" "R808")
		)
		("@s9s_mb_2u_lib.s9s_mb_2u(sch_1):page473_i6@pure_quanta.q_res(chips)"
			("LOCATION" "R809")
		)
		("@s9s_mb_2u_lib.s9s_mb_2u(sch_1):page473_i5@pure_quanta.q_res(chips)"
			("LOCATION" "R810")
		)
		("@s9s_mb_2u_lib.s9s_mb_2u(sch_1):page473_i9@pure_quanta.q_res(chips)"
			("LOCATION" "R811")
		)
		("@s9s_mb_2u_lib.s9s_mb_2u(sch_1):page473_i36@pure_quanta.q_res(chips)"
			("LOCATION" "R812")
		)
		("@s9s_mb_2u_lib.s9s_mb_2u(sch_1):page473_i32@pure_quanta.q_res(chips)"
			("LOCATION" "R813")
		)
		("@s9s_mb_2u_lib.s9s_mb_2u(sch_1):page473_i18@pure_quanta.q_res(chips)"
			("LOCATION" "R814")
		)
		("@s9s_mb_2u_lib.s9s_mb_2u(sch_1):page473_i11@pure_quanta.q_res(chips)"
			("LOCATION" "R815")
		)
		("@s9s_mb_2u_lib.s9s_mb_2u(sch_1):page473_i37@pure_quanta.q_res(chips)"
			("LOCATION" "R816")
		)
		("@s9s_mb_2u_lib.s9s_mb_2u(sch_1):page473_i26@pure_quanta.q_res(chips)"
			("LOCATION" "R817")
		)
		("@s9s_mb_2u_lib.s9s_mb_2u(sch_1):page473_i22@pure_quanta.q_res(chips)"
			("LOCATION" "R818")
		)
		("@s9s_mb_2u_lib.s9s_mb_2u(sch_1):page473_i14@pure_quanta.q_res(chips)"
			("LOCATION" "R819")
		)
		("@s9s_mb_2u_lib.s9s_mb_2u(sch_1):page473_i42@pure_quanta.q_res(chips)"
			("LOCATION" "R820")
		)
		("@s9s_mb_2u_lib.s9s_mb_2u(sch_1):page473_i38@pure_quanta.q_res(chips)"
			("LOCATION" "R821")
		)
		("@s9s_mb_2u_lib.s9s_mb_2u(sch_1):page473_i25@pure_quanta.q_res(chips)"
			("LOCATION" "R822")
		)
		("@s9s_mb_2u_lib.s9s_mb_2u(sch_1):page473_i45@pure_quanta.q_res(chips)"
			("LOCATION" "R823")
		)
		("@s9s_mb_2u_lib.s9s_mb_2u(sch_1):page473_i50@pure_quanta.q_res(chips)"
			("LOCATION" "R824")
		)
		("@s9s_mb_2u_lib.s9s_mb_2u(sch_1):page473_i49@pure_quanta.q_res(chips)"
			("LOCATION" "R825")
		)
		("@s9s_mb_2u_lib.s9s_mb_2u(sch_1):page473_i47@pure_quanta.q_res(chips)"
			("LOCATION" "R826")
		)
		("@s9s_mb_2u_lib.s9s_mb_2u(sch_1):page474_i102@pure_quanta.q_cap(chips)"
			("LOCATION" "C621")
		)
		("@s9s_mb_2u_lib.s9s_mb_2u(sch_1):page474_i91@pure_quanta.q_cap(chips)"
			("LOCATION" "C622")
		)
		("@s9s_mb_2u_lib.s9s_mb_2u(sch_1):page474_i94@pure_quanta.q_cap(chips)"
			("LOCATION" "C623")
		)
		("@s9s_mb_2u_lib.s9s_mb_2u(sch_1):page474_i99@pure_quanta.q_cap(chips)"
			("LOCATION" "C624")
		)
		("@s9s_mb_2u_lib.s9s_mb_2u(sch_1):page474_i113@pure_quanta.q_cap(chips)"
			("LOCATION" "C625")
		)
		("@s9s_mb_2u_lib.s9s_mb_2u(sch_1):page474_i104@pure_quanta.q_cap(chips)"
			("LOCATION" "C626")
		)
		("@s9s_mb_2u_lib.s9s_mb_2u(sch_1):page474_i107@pure_quanta.q_cap(chips)"
			("LOCATION" "C627")
		)
		("@s9s_mb_2u_lib.s9s_mb_2u(sch_1):page474_i110@pure_quanta.q_cap(chips)"
			("LOCATION" "C628")
		)
		("@s9s_mb_2u_lib.s9s_mb_2u(sch_1):page474_i118@pure_quanta.mosfet_nch_dual(chips)"
			("LOCATION" "Q9")
		)
		("@s9s_mb_2u_lib.s9s_mb_2u(sch_1):page474_i73@pure_quanta.mosfet_nch_dual(chips)"
			("LOCATION" "Q9")
		)
		("@s9s_mb_2u_lib.s9s_mb_2u(sch_1):page474_i117@pure_quanta.mosfet_nch_dual(chips)"
			("LOCATION" "Q10")
		)
		("@s9s_mb_2u_lib.s9s_mb_2u(sch_1):page474_i58@pure_quanta.mosfet_nch_dual(chips)"
			("LOCATION" "Q10")
		)
		("@s9s_mb_2u_lib.s9s_mb_2u(sch_1):page474_i116@pure_quanta.mosfet_nch_dual(chips)"
			("LOCATION" "Q11")
		)
		("@s9s_mb_2u_lib.s9s_mb_2u(sch_1):page474_i46@pure_quanta.mosfet_nch_dual(chips)"
			("LOCATION" "Q11")
		)
		("@s9s_mb_2u_lib.s9s_mb_2u(sch_1):page474_i115@pure_quanta.mosfet_nch_dual(chips)"
			("LOCATION" "Q12")
		)
		("@s9s_mb_2u_lib.s9s_mb_2u(sch_1):page474_i85@pure_quanta.mosfet_nch_dual(chips)"
			("LOCATION" "Q12")
		)
		("@s9s_mb_2u_lib.s9s_mb_2u(sch_1):page474_i112@pure_quanta.q_res(chips)"
			("LOCATION" "R705")
		)
		("@s9s_mb_2u_lib.s9s_mb_2u(sch_1):page474_i103@pure_quanta.q_res(chips)"
			("LOCATION" "R706")
		)
		("@s9s_mb_2u_lib.s9s_mb_2u(sch_1):page474_i106@pure_quanta.q_res(chips)"
			("LOCATION" "R707")
		)
		("@s9s_mb_2u_lib.s9s_mb_2u(sch_1):page474_i109@pure_quanta.q_res(chips)"
			("LOCATION" "R708")
		)
		("@s9s_mb_2u_lib.s9s_mb_2u(sch_1):page474_i89@pure_quanta.q_res(chips)"
			("LOCATION" "R827")
		)
		("@s9s_mb_2u_lib.s9s_mb_2u(sch_1):page474_i23@pure_quanta.q_res(chips)"
			("LOCATION" "R828")
		)
		("@s9s_mb_2u_lib.s9s_mb_2u(sch_1):page474_i63@pure_quanta.q_res(chips)"
			("LOCATION" "R829")
		)
		("@s9s_mb_2u_lib.s9s_mb_2u(sch_1):page474_i82@pure_quanta.q_res(chips)"
			("LOCATION" "R830")
		)
		("@s9s_mb_2u_lib.s9s_mb_2u(sch_1):page474_i81@pure_quanta.q_res(chips)"
			("LOCATION" "R831")
		)
		("@s9s_mb_2u_lib.s9s_mb_2u(sch_1):page474_i27@pure_quanta.q_res(chips)"
			("LOCATION" "R832")
		)
		("@s9s_mb_2u_lib.s9s_mb_2u(sch_1):page474_i60@pure_quanta.q_res(chips)"
			("LOCATION" "R833")
		)
		("@s9s_mb_2u_lib.s9s_mb_2u(sch_1):page474_i77@pure_quanta.q_res(chips)"
			("LOCATION" "R834")
		)
		("@s9s_mb_2u_lib.s9s_mb_2u(sch_1):page474_i86@pure_quanta.q_res(chips)"
			("LOCATION" "R835")
		)
		("@s9s_mb_2u_lib.s9s_mb_2u(sch_1):page474_i26@pure_quanta.q_res(chips)"
			("LOCATION" "R836")
		)
		("@s9s_mb_2u_lib.s9s_mb_2u(sch_1):page474_i59@pure_quanta.q_res(chips)"
			("LOCATION" "R837")
		)
		("@s9s_mb_2u_lib.s9s_mb_2u(sch_1):page474_i76@pure_quanta.q_res(chips)"
			("LOCATION" "R838")
		)
		("@s9s_mb_2u_lib.s9s_mb_2u(sch_1):page474_i75@pure_quanta.q_res(chips)"
			("LOCATION" "R839")
		)
		("@s9s_mb_2u_lib.s9s_mb_2u(sch_1):page474_i49@pure_quanta.q_res(chips)"
			("LOCATION" "R840")
		)
		("@s9s_mb_2u_lib.s9s_mb_2u(sch_1):page474_i56@pure_quanta.q_res(chips)"
			("LOCATION" "R841")
		)
		("@s9s_mb_2u_lib.s9s_mb_2u(sch_1):page474_i71@pure_quanta.q_res(chips)"
			("LOCATION" "R842")
		)
		("@s9s_mb_2u_lib.s9s_mb_2u(sch_1):page474_i68@pure_quanta.q_res(chips)"
			("LOCATION" "R843")
		)
		("@s9s_mb_2u_lib.s9s_mb_2u(sch_1):page474_i50@pure_quanta.q_res(chips)"
			("LOCATION" "R844")
		)
		("@s9s_mb_2u_lib.s9s_mb_2u(sch_1):page474_i53@pure_quanta.q_res(chips)"
			("LOCATION" "R845")
		)
		("@s9s_mb_2u_lib.s9s_mb_2u(sch_1):page474_i67@pure_quanta.q_res(chips)"
			("LOCATION" "R846")
		)
		("@s9s_mb_2u_lib.s9s_mb_2u(sch_1):page566_i55@pure_quanta.q_cap(chips)"
			("LOCATION" "C629")
		)
		("@s9s_mb_2u_lib.s9s_mb_2u(sch_1):page566_i10@pure_quanta.q_cap(chips)"
			("LOCATION" "C630")
		)
		("@s9s_mb_2u_lib.s9s_mb_2u(sch_1):page566_i75@pure_quanta.q_cap(chips)"
			("LOCATION" "C631")
		)
		("@s9s_mb_2u_lib.s9s_mb_2u(sch_1):page566_i15@pure_quanta.q_res(chips)"
			("LOCATION" "R459")
		)
		("@s9s_mb_2u_lib.s9s_mb_2u(sch_1):page566_i14@pure_quanta.q_res(chips)"
			("LOCATION" "R460")
		)
		("@s9s_mb_2u_lib.s9s_mb_2u(sch_1):page566_i39@pure_quanta.q_res(chips)"
			("LOCATION" "R475")
		)
		("@s9s_mb_2u_lib.s9s_mb_2u(sch_1):page566_i37@pure_quanta.q_res(chips)"
			("LOCATION" "R709")
		)
		("@s9s_mb_2u_lib.s9s_mb_2u(sch_1):page566_i57@pure_quanta.q_res(chips)"
			("LOCATION" "R710")
		)
		("@s9s_mb_2u_lib.s9s_mb_2u(sch_1):page566_i27@pure_quanta.q_res(chips)"
			("LOCATION" "R711")
		)
		("@s9s_mb_2u_lib.s9s_mb_2u(sch_1):page566_i30@pure_quanta.q_res(chips)"
			("LOCATION" "R712")
		)
		("@s9s_mb_2u_lib.s9s_mb_2u(sch_1):page566_i47@pure_quanta.q_res(chips)"
			("LOCATION" "R713")
		)
		("@s9s_mb_2u_lib.s9s_mb_2u(sch_1):page566_i52@pure_quanta.q_res(chips)"
			("LOCATION" "R714")
		)
		("@s9s_mb_2u_lib.s9s_mb_2u(sch_1):page566_i28@pure_quanta.q_res(chips)"
			("LOCATION" "R715")
		)
		("@s9s_mb_2u_lib.s9s_mb_2u(sch_1):page566_i31@pure_quanta.q_res(chips)"
			("LOCATION" "R716")
		)
		("@s9s_mb_2u_lib.s9s_mb_2u(sch_1):page566_i45@pure_quanta.q_res(chips)"
			("LOCATION" "R717")
		)
		("@s9s_mb_2u_lib.s9s_mb_2u(sch_1):page566_i50@pure_quanta.q_res(chips)"
			("LOCATION" "R718")
		)
		("@s9s_mb_2u_lib.s9s_mb_2u(sch_1):page566_i29@pure_quanta.q_res(chips)"
			("LOCATION" "R719")
		)
		("@s9s_mb_2u_lib.s9s_mb_2u(sch_1):page566_i32@pure_quanta.q_res(chips)"
			("LOCATION" "R720")
		)
		("@s9s_mb_2u_lib.s9s_mb_2u(sch_1):page566_i62@pure_quanta.q_res(chips)"
			("LOCATION" "R721")
		)
		("@s9s_mb_2u_lib.s9s_mb_2u(sch_1):page566_i61@pure_quanta.q_res(chips)"
			("LOCATION" "R722")
		)
		("@s9s_mb_2u_lib.s9s_mb_2u(sch_1):page566_i92@pure_quanta.q_res(chips)"
			("LOCATION" "R725")
		)
		("@s9s_mb_2u_lib.s9s_mb_2u(sch_1):page566_i91@pure_quanta.q_res(chips)"
			("LOCATION" "R726")
		)
		("@s9s_mb_2u_lib.s9s_mb_2u(sch_1):page566_i87@pure_quanta.q_res(chips)"
			("LOCATION" "R728")
		)
		("@s9s_mb_2u_lib.s9s_mb_2u(sch_1):page566_i90@pure_quanta.q_res(chips)"
			("LOCATION" "R729")
		)
		("@s9s_mb_2u_lib.s9s_mb_2u(sch_1):page566_i86@pure_quanta.q_res(chips)"
			("LOCATION" "R730")
		)
		("@s9s_mb_2u_lib.s9s_mb_2u(sch_1):page566_i89@pure_quanta.q_res(chips)"
			("LOCATION" "R731")
		)
		("@s9s_mb_2u_lib.s9s_mb_2u(sch_1):page566_i85@pure_quanta.q_res(chips)"
			("LOCATION" "R732")
		)
		("@s9s_mb_2u_lib.s9s_mb_2u(sch_1):page566_i88@pure_quanta.q_res(chips)"
			("LOCATION" "R733")
		)
		("@s9s_mb_2u_lib.s9s_mb_2u(sch_1):page566_i95@pure_quanta.q_res(chips)"
			("LOCATION" "R1331")
		)
		("@s9s_mb_2u_lib.s9s_mb_2u(sch_1):page566_i93@pure_quanta.q_res(chips)"
			("LOCATION" "R1332")
		)
		("@s9s_mb_2u_lib.s9s_mb_2u(sch_1):page566_i1@pure_quanta.tmp75aidr(chips)"
			("LOCATION" "U63")
		)
		("@s9s_mb_2u_lib.s9s_mb_2u(sch_1):page566_i35@pure_quanta.m24128bwdw6tp(chips)"
			("LOCATION" "U64")
		)
		("@s9s_mb_2u_lib.s9s_mb_2u(sch_1):page566_i84@pure_quanta.tmp75aidr(chips)"
			("LOCATION" "U65")
		)
		("@s9s_mb_2u_lib.s9s_mb_2u(sch_1):page527_i20@pure_quanta.q_cap(chips)"
			("LOCATION" "C632")
		)
		("@s9s_mb_2u_lib.s9s_mb_2u(sch_1):page527_i24@pure_quanta.q_cap(chips)"
			("LOCATION" "C633")
		)
		("@s9s_mb_2u_lib.s9s_mb_2u(sch_1):page527_i10@pure_quanta.q_cap_sata6g(chips)"
			("LOCATION" "C634")
		)
		("@s9s_mb_2u_lib.s9s_mb_2u(sch_1):page527_i11@pure_quanta.q_cap_sata6g(chips)"
			("LOCATION" "C635")
		)
		("@s9s_mb_2u_lib.s9s_mb_2u(sch_1):page527_i12@pure_quanta.q_cap_sata6g(chips)"
			("LOCATION" "C636")
		)
		("@s9s_mb_2u_lib.s9s_mb_2u(sch_1):page527_i13@pure_quanta.q_cap_sata6g(chips)"
			("LOCATION" "C637")
		)
		("@s9s_mb_2u_lib.s9s_mb_2u(sch_1):page527_i25@pure_quanta.q_cap(chips)"
			("LOCATION" "C638")
		)
		("@s9s_mb_2u_lib.s9s_mb_2u(sch_1):page527_i36@pure_quanta.q_cap(chips)"
			("LOCATION" "C1305")
		)
		("@s9s_mb_2u_lib.s9s_mb_2u(sch_1):page527_i28@pure_quanta.q_cap(chips)"
			("LOCATION" "C1323")
		)
		("@s9s_mb_2u_lib.s9s_mb_2u(sch_1):page527_i8@pure_quanta.conn7_abasat054ka1(chips)"
			("LOCATION" "J54")
		)
		("@s9s_mb_2u_lib.s9s_mb_2u(sch_1):page527_i18@pure_quanta.conn3_hfk1030g000laf(chips)"
			("LOCATION" "JP5")
		)
		("@s9s_mb_2u_lib.s9s_mb_2u(sch_1):page527_i5@pure_quanta.q_res(chips)"
			("LOCATION" "R1271")
		)
		("@s9s_mb_2u_lib.s9s_mb_2u(sch_1):page527_i6@pure_quanta.q_res(chips)"
			("LOCATION" "R1272")
		)
		("@s9s_mb_2u_lib.s9s_mb_2u(sch_1):page527_i48@pure_quanta.q_res(chips)"
			("LOCATION" "R1700")
		)
		("@s9s_mb_2u_lib.s9s_mb_2u(sch_1):page527_i49@pure_quanta.q_res(chips)"
			("LOCATION" "R1701")
		)
		("@s9s_mb_2u_lib.s9s_mb_2u(sch_1):page527_i43@pure_quanta.q_res(chips)"
			("LOCATION" "R1702")
		)
		("@s9s_mb_2u_lib.s9s_mb_2u(sch_1):page527_i45@pure_quanta.q_res(chips)"
			("LOCATION" "R1703")
		)
		("@s9s_mb_2u_lib.s9s_mb_2u(sch_1):page527_i46@pure_quanta.q_res(chips)"
			("LOCATION" "R1704")
		)
		("@s9s_mb_2u_lib.s9s_mb_2u(sch_1):page527_i44@pure_quanta.q_res(chips)"
			("LOCATION" "R1705")
		)
		("@s9s_mb_2u_lib.s9s_mb_2u(sch_1):page527_i27@pure_quanta.txs0104epwr(chips)"
			("LOCATION" "U98")
		)
		("@s9s_mb_2u_lib.s9s_mb_2u(sch_1):page501_i59@pure_quanta.q_cap(chips)"
			("LOCATION" "C639")
		)
		("@s9s_mb_2u_lib.s9s_mb_2u(sch_1):page501_i47@pure_quanta.q_cap(chips)"
			("LOCATION" "C640")
		)
		("@s9s_mb_2u_lib.s9s_mb_2u(sch_1):page501_i16@pure_quanta.q_cap(chips)"
			("LOCATION" "C641")
		)
		("@s9s_mb_2u_lib.s9s_mb_2u(sch_1):page501_i115@pure_quanta.q_cap(chips)"
			("LOCATION" "C1241")
		)
		("@s9s_mb_2u_lib.s9s_mb_2u(sch_1):page501_i118@pure_quanta.q_res(chips)"
			("LOCATION" "R923")
		)
		("@s9s_mb_2u_lib.s9s_mb_2u(sch_1):page501_i56@pure_quanta.q_res(chips)"
			("LOCATION" "R1289")
		)
		("@s9s_mb_2u_lib.s9s_mb_2u(sch_1):page501_i98@pure_quanta.q_res(chips)"
			("LOCATION" "R1290")
		)
		("@s9s_mb_2u_lib.s9s_mb_2u(sch_1):page501_i99@pure_quanta.q_res(chips)"
			("LOCATION" "R1291")
		)
		("@s9s_mb_2u_lib.s9s_mb_2u(sch_1):page501_i100@pure_quanta.q_res(chips)"
			("LOCATION" "R1292")
		)
		("@s9s_mb_2u_lib.s9s_mb_2u(sch_1):page501_i101@pure_quanta.q_res(chips)"
			("LOCATION" "R1293")
		)
		("@s9s_mb_2u_lib.s9s_mb_2u(sch_1):page501_i102@pure_quanta.q_res(chips)"
			("LOCATION" "R1294")
		)
		("@s9s_mb_2u_lib.s9s_mb_2u(sch_1):page501_i103@pure_quanta.q_res(chips)"
			("LOCATION" "R1295")
		)
		("@s9s_mb_2u_lib.s9s_mb_2u(sch_1):page501_i104@pure_quanta.q_res(chips)"
			("LOCATION" "R1296")
		)
		("@s9s_mb_2u_lib.s9s_mb_2u(sch_1):page501_i82@pure_quanta.q_res(chips)"
			("LOCATION" "R1350")
		)
		("@s9s_mb_2u_lib.s9s_mb_2u(sch_1):page501_i86@pure_quanta.q_res(chips)"
			("LOCATION" "R1351")
		)
		("@s9s_mb_2u_lib.s9s_mb_2u(sch_1):page501_i87@pure_quanta.q_res(chips)"
			("LOCATION" "R1352")
		)
		("@s9s_mb_2u_lib.s9s_mb_2u(sch_1):page501_i92@pure_quanta.q_res(chips)"
			("LOCATION" "R1353")
		)
		("@s9s_mb_2u_lib.s9s_mb_2u(sch_1):page501_i91@pure_quanta.q_res(chips)"
			("LOCATION" "R1354")
		)
		("@s9s_mb_2u_lib.s9s_mb_2u(sch_1):page501_i93@pure_quanta.q_res(chips)"
			("LOCATION" "R1355")
		)
		("@s9s_mb_2u_lib.s9s_mb_2u(sch_1):page501_i96@pure_quanta.q_res(chips)"
			("LOCATION" "R1356")
		)
		("@s9s_mb_2u_lib.s9s_mb_2u(sch_1):page501_i119@pure_quanta.q_res(chips)"
			("LOCATION" "R1719")
		)
		("@s9s_mb_2u_lib.s9s_mb_2u(sch_1):page501_i123@pure_quanta.q_res(chips)"
			("LOCATION" "R1896")
		)
		("@s9s_mb_2u_lib.s9s_mb_2u(sch_1):page501_i124@pure_quanta.q_res(chips)"
			("LOCATION" "R1897")
		)
		("@s9s_mb_2u_lib.s9s_mb_2u(sch_1):page501_i122@pure_quanta.q_res(chips)"
			("LOCATION" "R1898")
		)
		("@s9s_mb_2u_lib.s9s_mb_2u(sch_1):page501_i53@pure_quanta.\\74hc1g126gw\\(chips)"
			("LOCATION" "U66")
		)
		("@s9s_mb_2u_lib.s9s_mb_2u(sch_1):page501_i1@pure_quanta.\\74cbtlv3126pw\\(chips)"
			("LOCATION" "U67")
		)
		("@s9s_mb_2u_lib.s9s_mb_2u(sch_1):page501_i2@pure_quanta.\\74cbtlv3126pw\\(chips)"
			("LOCATION" "U68")
		)
		("@s9s_mb_2u_lib.s9s_mb_2u(sch_1):page501_i105@pure_quanta.\\74cbtlv3126pw\\(chips)"
			("LOCATION" "U77")
		)
		("@s9s_mb_2u_lib.s9s_mb_2u(sch_1):page517_i195@pure_quanta.q_cap_diffbus(chips)"
			("LOCATION" "C643")
		)
		("@s9s_mb_2u_lib.s9s_mb_2u(sch_1):page517_i194@pure_quanta.q_cap_diffbus(chips)"
			("LOCATION" "C644")
		)
		("@s9s_mb_2u_lib.s9s_mb_2u(sch_1):page517_i155@pure_quanta.q_cap_diffbus(chips)"
			("LOCATION" "C1090")
		)
		("@s9s_mb_2u_lib.s9s_mb_2u(sch_1):page517_i154@pure_quanta.q_cap_diffbus(chips)"
			("LOCATION" "C1091")
		)
		("@s9s_mb_2u_lib.s9s_mb_2u(sch_1):page517_i157@pure_quanta.q_cap_diffbus(chips)"
			("LOCATION" "C1092")
		)
		("@s9s_mb_2u_lib.s9s_mb_2u(sch_1):page517_i156@pure_quanta.q_cap_diffbus(chips)"
			("LOCATION" "C1093")
		)
		("@s9s_mb_2u_lib.s9s_mb_2u(sch_1):page517_i158@pure_quanta.q_cap_diffbus(chips)"
			("LOCATION" "C1094")
		)
		("@s9s_mb_2u_lib.s9s_mb_2u(sch_1):page517_i160@pure_quanta.q_cap_diffbus(chips)"
			("LOCATION" "C1095")
		)
		("@s9s_mb_2u_lib.s9s_mb_2u(sch_1):page517_i159@pure_quanta.q_cap_diffbus(chips)"
			("LOCATION" "C1096")
		)
		("@s9s_mb_2u_lib.s9s_mb_2u(sch_1):page517_i161@pure_quanta.q_cap_diffbus(chips)"
			("LOCATION" "C1097")
		)
		("@s9s_mb_2u_lib.s9s_mb_2u(sch_1):page517_i162@pure_quanta.q_cap_diffbus(chips)"
			("LOCATION" "C1098")
		)
		("@s9s_mb_2u_lib.s9s_mb_2u(sch_1):page517_i163@pure_quanta.q_cap_diffbus(chips)"
			("LOCATION" "C1099")
		)
		("@s9s_mb_2u_lib.s9s_mb_2u(sch_1):page517_i165@pure_quanta.q_cap_diffbus(chips)"
			("LOCATION" "C1100")
		)
		("@s9s_mb_2u_lib.s9s_mb_2u(sch_1):page517_i164@pure_quanta.q_cap_diffbus(chips)"
			("LOCATION" "C1101")
		)
		("@s9s_mb_2u_lib.s9s_mb_2u(sch_1):page517_i168@pure_quanta.q_cap_diffbus(chips)"
			("LOCATION" "C1102")
		)
		("@s9s_mb_2u_lib.s9s_mb_2u(sch_1):page517_i166@pure_quanta.q_cap_diffbus(chips)"
			("LOCATION" "C1103")
		)
		("@s9s_mb_2u_lib.s9s_mb_2u(sch_1):page517_i167@pure_quanta.q_cap_diffbus(chips)"
			("LOCATION" "C1104")
		)
		("@s9s_mb_2u_lib.s9s_mb_2u(sch_1):page517_i169@pure_quanta.q_cap_diffbus(chips)"
			("LOCATION" "C1105")
		)
		("@s9s_mb_2u_lib.s9s_mb_2u(sch_1):page517_i118@pure_quanta.q_res(chips)"
			("LOCATION" "R495")
		)
		("@s9s_mb_2u_lib.s9s_mb_2u(sch_1):page517_i119@pure_quanta.emmitsburg_rev0p9(chips)"
			("LOCATION" "U4")
		)
		("@s9s_mb_2u_lib.s9s_mb_2u(sch_1):page457_i94@pure_quanta.q_cap_diffbus(chips)"
			("LOCATION" "C646")
		)
		("@s9s_mb_2u_lib.s9s_mb_2u(sch_1):page457_i93@pure_quanta.q_cap_diffbus(chips)"
			("LOCATION" "C647")
		)
		("@s9s_mb_2u_lib.s9s_mb_2u(sch_1):page457_i92@pure_quanta.q_cap_diffbus(chips)"
			("LOCATION" "C648")
		)
		("@s9s_mb_2u_lib.s9s_mb_2u(sch_1):page457_i91@pure_quanta.q_cap_diffbus(chips)"
			("LOCATION" "C649")
		)
		("@s9s_mb_2u_lib.s9s_mb_2u(sch_1):page457_i90@pure_quanta.q_cap_diffbus(chips)"
			("LOCATION" "C650")
		)
		("@s9s_mb_2u_lib.s9s_mb_2u(sch_1):page457_i89@pure_quanta.q_cap_diffbus(chips)"
			("LOCATION" "C651")
		)
		("@s9s_mb_2u_lib.s9s_mb_2u(sch_1):page457_i77@pure_quanta.q_cap_diffbus(chips)"
			("LOCATION" "C652")
		)
		("@s9s_mb_2u_lib.s9s_mb_2u(sch_1):page457_i78@pure_quanta.q_cap_diffbus(chips)"
			("LOCATION" "C653")
		)
		("@s9s_mb_2u_lib.s9s_mb_2u(sch_1):page457_i76@pure_quanta.q_cap_diffbus(chips)"
			("LOCATION" "C654")
		)
		("@s9s_mb_2u_lib.s9s_mb_2u(sch_1):page457_i75@pure_quanta.q_cap_diffbus(chips)"
			("LOCATION" "C655")
		)
		("@s9s_mb_2u_lib.s9s_mb_2u(sch_1):page457_i74@pure_quanta.q_cap_diffbus(chips)"
			("LOCATION" "C656")
		)
		("@s9s_mb_2u_lib.s9s_mb_2u(sch_1):page457_i73@pure_quanta.q_cap_diffbus(chips)"
			("LOCATION" "C657")
		)
		("@s9s_mb_2u_lib.s9s_mb_2u(sch_1):page457_i72@pure_quanta.q_cap_diffbus(chips)"
			("LOCATION" "C658")
		)
		("@s9s_mb_2u_lib.s9s_mb_2u(sch_1):page457_i71@pure_quanta.q_cap_diffbus(chips)"
			("LOCATION" "C659")
		)
		("@s9s_mb_2u_lib.s9s_mb_2u(sch_1):page457_i70@pure_quanta.q_cap_diffbus(chips)"
			("LOCATION" "C660")
		)
		("@s9s_mb_2u_lib.s9s_mb_2u(sch_1):page457_i69@pure_quanta.q_cap_diffbus(chips)"
			("LOCATION" "C661")
		)
		("@s9s_mb_2u_lib.s9s_mb_2u(sch_1):page457_i45@pure_quanta.q_cap_diffbus(chips)"
			("LOCATION" "C662")
		)
		("@s9s_mb_2u_lib.s9s_mb_2u(sch_1):page457_i44@pure_quanta.q_cap_diffbus(chips)"
			("LOCATION" "C663")
		)
		("@s9s_mb_2u_lib.s9s_mb_2u(sch_1):page457_i43@pure_quanta.q_cap_diffbus(chips)"
			("LOCATION" "C664")
		)
		("@s9s_mb_2u_lib.s9s_mb_2u(sch_1):page457_i42@pure_quanta.q_cap_diffbus(chips)"
			("LOCATION" "C665")
		)
		("@s9s_mb_2u_lib.s9s_mb_2u(sch_1):page457_i40@pure_quanta.q_cap_diffbus(chips)"
			("LOCATION" "C666")
		)
		("@s9s_mb_2u_lib.s9s_mb_2u(sch_1):page457_i41@pure_quanta.q_cap_diffbus(chips)"
			("LOCATION" "C667")
		)
		("@s9s_mb_2u_lib.s9s_mb_2u(sch_1):page457_i39@pure_quanta.q_cap_diffbus(chips)"
			("LOCATION" "C668")
		)
		("@s9s_mb_2u_lib.s9s_mb_2u(sch_1):page457_i29@pure_quanta.q_cap_diffbus(chips)"
			("LOCATION" "C669")
		)
		("@s9s_mb_2u_lib.s9s_mb_2u(sch_1):page457_i28@pure_quanta.q_cap_diffbus(chips)"
			("LOCATION" "C670")
		)
		("@s9s_mb_2u_lib.s9s_mb_2u(sch_1):page457_i27@pure_quanta.q_cap_diffbus(chips)"
			("LOCATION" "C671")
		)
		("@s9s_mb_2u_lib.s9s_mb_2u(sch_1):page457_i26@pure_quanta.q_cap_diffbus(chips)"
			("LOCATION" "C672")
		)
		("@s9s_mb_2u_lib.s9s_mb_2u(sch_1):page457_i25@pure_quanta.q_cap_diffbus(chips)"
			("LOCATION" "C673")
		)
		("@s9s_mb_2u_lib.s9s_mb_2u(sch_1):page457_i24@pure_quanta.q_cap_diffbus(chips)"
			("LOCATION" "C674")
		)
		("@s9s_mb_2u_lib.s9s_mb_2u(sch_1):page457_i23@pure_quanta.q_cap_diffbus(chips)"
			("LOCATION" "C675")
		)
		("@s9s_mb_2u_lib.s9s_mb_2u(sch_1):page457_i22@pure_quanta.q_cap_diffbus(chips)"
			("LOCATION" "C676")
		)
		("@s9s_mb_2u_lib.s9s_mb_2u(sch_1):page457_i21@pure_quanta.q_cap_diffbus(chips)"
			("LOCATION" "C677")
		)
		("@s9s_mb_2u_lib.s9s_mb_2u(sch_1):page457_i172@pure_quanta.q_cap_diffbus(chips)"
			("LOCATION" "C678")
		)
		("@s9s_mb_2u_lib.s9s_mb_2u(sch_1):page457_i169@pure_quanta.q_cap_diffbus(chips)"
			("LOCATION" "C679")
		)
		("@s9s_mb_2u_lib.s9s_mb_2u(sch_1):page457_i170@pure_quanta.q_cap_diffbus(chips)"
			("LOCATION" "C680")
		)
		("@s9s_mb_2u_lib.s9s_mb_2u(sch_1):page457_i171@pure_quanta.q_cap_diffbus(chips)"
			("LOCATION" "C681")
		)
		("@s9s_mb_2u_lib.s9s_mb_2u(sch_1):page457_i167@pure_quanta.q_cap_diffbus(chips)"
			("LOCATION" "C682")
		)
		("@s9s_mb_2u_lib.s9s_mb_2u(sch_1):page457_i168@pure_quanta.q_cap_diffbus(chips)"
			("LOCATION" "C683")
		)
		("@s9s_mb_2u_lib.s9s_mb_2u(sch_1):page457_i166@pure_quanta.q_cap_diffbus(chips)"
			("LOCATION" "C684")
		)
		("@s9s_mb_2u_lib.s9s_mb_2u(sch_1):page457_i165@pure_quanta.q_cap_diffbus(chips)"
			("LOCATION" "C685")
		)
		("@s9s_mb_2u_lib.s9s_mb_2u(sch_1):page457_i164@pure_quanta.q_cap_diffbus(chips)"
			("LOCATION" "C686")
		)
		("@s9s_mb_2u_lib.s9s_mb_2u(sch_1):page457_i161@pure_quanta.q_cap_diffbus(chips)"
			("LOCATION" "C687")
		)
		("@s9s_mb_2u_lib.s9s_mb_2u(sch_1):page457_i162@pure_quanta.q_cap_diffbus(chips)"
			("LOCATION" "C688")
		)
		("@s9s_mb_2u_lib.s9s_mb_2u(sch_1):page457_i163@pure_quanta.q_cap_diffbus(chips)"
			("LOCATION" "C689")
		)
		("@s9s_mb_2u_lib.s9s_mb_2u(sch_1):page457_i159@pure_quanta.q_cap_diffbus(chips)"
			("LOCATION" "C690")
		)
		("@s9s_mb_2u_lib.s9s_mb_2u(sch_1):page457_i160@pure_quanta.q_cap_diffbus(chips)"
			("LOCATION" "C691")
		)
		("@s9s_mb_2u_lib.s9s_mb_2u(sch_1):page457_i158@pure_quanta.q_cap_diffbus(chips)"
			("LOCATION" "C692")
		)
		("@s9s_mb_2u_lib.s9s_mb_2u(sch_1):page457_i157@pure_quanta.q_cap_diffbus(chips)"
			("LOCATION" "C693")
		)
		("@s9s_mb_2u_lib.s9s_mb_2u(sch_1):page457_i140@pure_quanta.q_cap_diffbus(chips)"
			("LOCATION" "C694")
		)
		("@s9s_mb_2u_lib.s9s_mb_2u(sch_1):page457_i139@pure_quanta.q_cap_diffbus(chips)"
			("LOCATION" "C695")
		)
		("@s9s_mb_2u_lib.s9s_mb_2u(sch_1):page457_i137@pure_quanta.q_cap_diffbus(chips)"
			("LOCATION" "C696")
		)
		("@s9s_mb_2u_lib.s9s_mb_2u(sch_1):page457_i138@pure_quanta.q_cap_diffbus(chips)"
			("LOCATION" "C697")
		)
		("@s9s_mb_2u_lib.s9s_mb_2u(sch_1):page457_i135@pure_quanta.q_cap_diffbus(chips)"
			("LOCATION" "C698")
		)
		("@s9s_mb_2u_lib.s9s_mb_2u(sch_1):page457_i136@pure_quanta.q_cap_diffbus(chips)"
			("LOCATION" "C699")
		)
		("@s9s_mb_2u_lib.s9s_mb_2u(sch_1):page457_i134@pure_quanta.q_cap_diffbus(chips)"
			("LOCATION" "C700")
		)
		("@s9s_mb_2u_lib.s9s_mb_2u(sch_1):page457_i131@pure_quanta.q_cap_diffbus(chips)"
			("LOCATION" "C701")
		)
		("@s9s_mb_2u_lib.s9s_mb_2u(sch_1):page457_i132@pure_quanta.q_cap_diffbus(chips)"
			("LOCATION" "C702")
		)
		("@s9s_mb_2u_lib.s9s_mb_2u(sch_1):page457_i133@pure_quanta.q_cap_diffbus(chips)"
			("LOCATION" "C703")
		)
		("@s9s_mb_2u_lib.s9s_mb_2u(sch_1):page457_i129@pure_quanta.q_cap_diffbus(chips)"
			("LOCATION" "C704")
		)
		("@s9s_mb_2u_lib.s9s_mb_2u(sch_1):page457_i130@pure_quanta.q_cap_diffbus(chips)"
			("LOCATION" "C705")
		)
		("@s9s_mb_2u_lib.s9s_mb_2u(sch_1):page457_i127@pure_quanta.q_cap_diffbus(chips)"
			("LOCATION" "C706")
		)
		("@s9s_mb_2u_lib.s9s_mb_2u(sch_1):page457_i128@pure_quanta.q_cap_diffbus(chips)"
			("LOCATION" "C707")
		)
		("@s9s_mb_2u_lib.s9s_mb_2u(sch_1):page457_i125@pure_quanta.q_cap_diffbus(chips)"
			("LOCATION" "C708")
		)
		("@s9s_mb_2u_lib.s9s_mb_2u(sch_1):page457_i126@pure_quanta.q_cap_diffbus(chips)"
			("LOCATION" "C709")
		)
		("@s9s_mb_2u_lib.s9s_mb_2u(sch_1):page458_i80@pure_quanta.q_cap_diffbus(chips)"
			("LOCATION" "C710")
		)
		("@s9s_mb_2u_lib.s9s_mb_2u(sch_1):page458_i79@pure_quanta.q_cap_diffbus(chips)"
			("LOCATION" "C711")
		)
		("@s9s_mb_2u_lib.s9s_mb_2u(sch_1):page458_i81@pure_quanta.q_cap_diffbus(chips)"
			("LOCATION" "C712")
		)
		("@s9s_mb_2u_lib.s9s_mb_2u(sch_1):page458_i77@pure_quanta.q_cap_diffbus(chips)"
			("LOCATION" "C713")
		)
		("@s9s_mb_2u_lib.s9s_mb_2u(sch_1):page458_i78@pure_quanta.q_cap_diffbus(chips)"
			("LOCATION" "C714")
		)
		("@s9s_mb_2u_lib.s9s_mb_2u(sch_1):page458_i76@pure_quanta.q_cap_diffbus(chips)"
			("LOCATION" "C715")
		)
		("@s9s_mb_2u_lib.s9s_mb_2u(sch_1):page458_i69@pure_quanta.q_cap_diffbus(chips)"
			("LOCATION" "C716")
		)
		("@s9s_mb_2u_lib.s9s_mb_2u(sch_1):page458_i70@pure_quanta.q_cap_diffbus(chips)"
			("LOCATION" "C717")
		)
		("@s9s_mb_2u_lib.s9s_mb_2u(sch_1):page458_i67@pure_quanta.q_cap_diffbus(chips)"
			("LOCATION" "C718")
		)
		("@s9s_mb_2u_lib.s9s_mb_2u(sch_1):page458_i68@pure_quanta.q_cap_diffbus(chips)"
			("LOCATION" "C719")
		)
		("@s9s_mb_2u_lib.s9s_mb_2u(sch_1):page458_i66@pure_quanta.q_cap_diffbus(chips)"
			("LOCATION" "C720")
		)
		("@s9s_mb_2u_lib.s9s_mb_2u(sch_1):page458_i64@pure_quanta.q_cap_diffbus(chips)"
			("LOCATION" "C721")
		)
		("@s9s_mb_2u_lib.s9s_mb_2u(sch_1):page458_i65@pure_quanta.q_cap_diffbus(chips)"
			("LOCATION" "C722")
		)
		("@s9s_mb_2u_lib.s9s_mb_2u(sch_1):page458_i63@pure_quanta.q_cap_diffbus(chips)"
			("LOCATION" "C723")
		)
		("@s9s_mb_2u_lib.s9s_mb_2u(sch_1):page458_i62@pure_quanta.q_cap_diffbus(chips)"
			("LOCATION" "C724")
		)
		("@s9s_mb_2u_lib.s9s_mb_2u(sch_1):page458_i61@pure_quanta.q_cap_diffbus(chips)"
			("LOCATION" "C725")
		)
		("@s9s_mb_2u_lib.s9s_mb_2u(sch_1):page458_i41@pure_quanta.q_cap_diffbus(chips)"
			("LOCATION" "C726")
		)
		("@s9s_mb_2u_lib.s9s_mb_2u(sch_1):page458_i40@pure_quanta.q_cap_diffbus(chips)"
			("LOCATION" "C727")
		)
		("@s9s_mb_2u_lib.s9s_mb_2u(sch_1):page458_i38@pure_quanta.q_cap_diffbus(chips)"
			("LOCATION" "C728")
		)
		("@s9s_mb_2u_lib.s9s_mb_2u(sch_1):page458_i39@pure_quanta.q_cap_diffbus(chips)"
			("LOCATION" "C729")
		)
		("@s9s_mb_2u_lib.s9s_mb_2u(sch_1):page458_i36@pure_quanta.q_cap_diffbus(chips)"
			("LOCATION" "C730")
		)
		("@s9s_mb_2u_lib.s9s_mb_2u(sch_1):page458_i37@pure_quanta.q_cap_diffbus(chips)"
			("LOCATION" "C731")
		)
		("@s9s_mb_2u_lib.s9s_mb_2u(sch_1):page458_i28@pure_quanta.q_cap_diffbus(chips)"
			("LOCATION" "C732")
		)
		("@s9s_mb_2u_lib.s9s_mb_2u(sch_1):page458_i29@pure_quanta.q_cap_diffbus(chips)"
			("LOCATION" "C733")
		)
		("@s9s_mb_2u_lib.s9s_mb_2u(sch_1):page458_i30@pure_quanta.q_cap_diffbus(chips)"
			("LOCATION" "C734")
		)
		("@s9s_mb_2u_lib.s9s_mb_2u(sch_1):page458_i26@pure_quanta.q_cap_diffbus(chips)"
			("LOCATION" "C735")
		)
		("@s9s_mb_2u_lib.s9s_mb_2u(sch_1):page458_i27@pure_quanta.q_cap_diffbus(chips)"
			("LOCATION" "C736")
		)
		("@s9s_mb_2u_lib.s9s_mb_2u(sch_1):page458_i25@pure_quanta.q_cap_diffbus(chips)"
			("LOCATION" "C737")
		)
		("@s9s_mb_2u_lib.s9s_mb_2u(sch_1):page458_i23@pure_quanta.q_cap_diffbus(chips)"
			("LOCATION" "C738")
		)
		("@s9s_mb_2u_lib.s9s_mb_2u(sch_1):page458_i24@pure_quanta.q_cap_diffbus(chips)"
			("LOCATION" "C739")
		)
		("@s9s_mb_2u_lib.s9s_mb_2u(sch_1):page458_i22@pure_quanta.q_cap_diffbus(chips)"
			("LOCATION" "C740")
		)
		("@s9s_mb_2u_lib.s9s_mb_2u(sch_1):page458_i21@pure_quanta.q_cap_diffbus(chips)"
			("LOCATION" "C741")
		)
		("@s9s_mb_2u_lib.s9s_mb_2u(sch_1):page458_i172@pure_quanta.q_cap_diffbus(chips)"
			("LOCATION" "C742")
		)
		("@s9s_mb_2u_lib.s9s_mb_2u(sch_1):page458_i171@pure_quanta.q_cap_diffbus(chips)"
			("LOCATION" "C743")
		)
		("@s9s_mb_2u_lib.s9s_mb_2u(sch_1):page458_i170@pure_quanta.q_cap_diffbus(chips)"
			("LOCATION" "C744")
		)
		("@s9s_mb_2u_lib.s9s_mb_2u(sch_1):page458_i169@pure_quanta.q_cap_diffbus(chips)"
			("LOCATION" "C745")
		)
		("@s9s_mb_2u_lib.s9s_mb_2u(sch_1):page458_i168@pure_quanta.q_cap_diffbus(chips)"
			("LOCATION" "C746")
		)
		("@s9s_mb_2u_lib.s9s_mb_2u(sch_1):page458_i167@pure_quanta.q_cap_diffbus(chips)"
			("LOCATION" "C747")
		)
		("@s9s_mb_2u_lib.s9s_mb_2u(sch_1):page458_i163@pure_quanta.q_cap_diffbus(chips)"
			("LOCATION" "C748")
		)
		("@s9s_mb_2u_lib.s9s_mb_2u(sch_1):page458_i162@pure_quanta.q_cap_diffbus(chips)"
			("LOCATION" "C749")
		)
		("@s9s_mb_2u_lib.s9s_mb_2u(sch_1):page458_i160@pure_quanta.q_cap_diffbus(chips)"
			("LOCATION" "C750")
		)
		("@s9s_mb_2u_lib.s9s_mb_2u(sch_1):page458_i161@pure_quanta.q_cap_diffbus(chips)"
			("LOCATION" "C751")
		)
		("@s9s_mb_2u_lib.s9s_mb_2u(sch_1):page458_i159@pure_quanta.q_cap_diffbus(chips)"
			("LOCATION" "C752")
		)
		("@s9s_mb_2u_lib.s9s_mb_2u(sch_1):page458_i158@pure_quanta.q_cap_diffbus(chips)"
			("LOCATION" "C753")
		)
		("@s9s_mb_2u_lib.s9s_mb_2u(sch_1):page458_i157@pure_quanta.q_cap_diffbus(chips)"
			("LOCATION" "C754")
		)
		("@s9s_mb_2u_lib.s9s_mb_2u(sch_1):page458_i156@pure_quanta.q_cap_diffbus(chips)"
			("LOCATION" "C755")
		)
		("@s9s_mb_2u_lib.s9s_mb_2u(sch_1):page458_i154@pure_quanta.q_cap_diffbus(chips)"
			("LOCATION" "C756")
		)
		("@s9s_mb_2u_lib.s9s_mb_2u(sch_1):page458_i155@pure_quanta.q_cap_diffbus(chips)"
			("LOCATION" "C757")
		)
		("@s9s_mb_2u_lib.s9s_mb_2u(sch_1):page458_i140@pure_quanta.q_cap_diffbus(chips)"
			("LOCATION" "C758")
		)
		("@s9s_mb_2u_lib.s9s_mb_2u(sch_1):page458_i139@pure_quanta.q_cap_diffbus(chips)"
			("LOCATION" "C759")
		)
		("@s9s_mb_2u_lib.s9s_mb_2u(sch_1):page458_i138@pure_quanta.q_cap_diffbus(chips)"
			("LOCATION" "C760")
		)
		("@s9s_mb_2u_lib.s9s_mb_2u(sch_1):page458_i137@pure_quanta.q_cap_diffbus(chips)"
			("LOCATION" "C761")
		)
		("@s9s_mb_2u_lib.s9s_mb_2u(sch_1):page458_i136@pure_quanta.q_cap_diffbus(chips)"
			("LOCATION" "C762")
		)
		("@s9s_mb_2u_lib.s9s_mb_2u(sch_1):page458_i135@pure_quanta.q_cap_diffbus(chips)"
			("LOCATION" "C763")
		)
		("@s9s_mb_2u_lib.s9s_mb_2u(sch_1):page458_i130@pure_quanta.q_cap_diffbus(chips)"
			("LOCATION" "C764")
		)
		("@s9s_mb_2u_lib.s9s_mb_2u(sch_1):page458_i131@pure_quanta.q_cap_diffbus(chips)"
			("LOCATION" "C765")
		)
		("@s9s_mb_2u_lib.s9s_mb_2u(sch_1):page458_i129@pure_quanta.q_cap_diffbus(chips)"
			("LOCATION" "C766")
		)
		("@s9s_mb_2u_lib.s9s_mb_2u(sch_1):page458_i128@pure_quanta.q_cap_diffbus(chips)"
			("LOCATION" "C767")
		)
		("@s9s_mb_2u_lib.s9s_mb_2u(sch_1):page458_i127@pure_quanta.q_cap_diffbus(chips)"
			("LOCATION" "C768")
		)
		("@s9s_mb_2u_lib.s9s_mb_2u(sch_1):page458_i126@pure_quanta.q_cap_diffbus(chips)"
			("LOCATION" "C769")
		)
		("@s9s_mb_2u_lib.s9s_mb_2u(sch_1):page458_i125@pure_quanta.q_cap_diffbus(chips)"
			("LOCATION" "C770")
		)
		("@s9s_mb_2u_lib.s9s_mb_2u(sch_1):page458_i124@pure_quanta.q_cap_diffbus(chips)"
			("LOCATION" "C771")
		)
		("@s9s_mb_2u_lib.s9s_mb_2u(sch_1):page458_i123@pure_quanta.q_cap_diffbus(chips)"
			("LOCATION" "C772")
		)
		("@s9s_mb_2u_lib.s9s_mb_2u(sch_1):page458_i122@pure_quanta.q_cap_diffbus(chips)"
			("LOCATION" "C773")
		)
		("@s9s_mb_2u_lib.s9s_mb_2u(sch_1):page459_i81@pure_quanta.q_cap_diffbus(chips)"
			("LOCATION" "C774")
		)
		("@s9s_mb_2u_lib.s9s_mb_2u(sch_1):page459_i80@pure_quanta.q_cap_diffbus(chips)"
			("LOCATION" "C775")
		)
		("@s9s_mb_2u_lib.s9s_mb_2u(sch_1):page459_i79@pure_quanta.q_cap_diffbus(chips)"
			("LOCATION" "C776")
		)
		("@s9s_mb_2u_lib.s9s_mb_2u(sch_1):page459_i78@pure_quanta.q_cap_diffbus(chips)"
			("LOCATION" "C777")
		)
		("@s9s_mb_2u_lib.s9s_mb_2u(sch_1):page459_i76@pure_quanta.q_cap_diffbus(chips)"
			("LOCATION" "C778")
		)
		("@s9s_mb_2u_lib.s9s_mb_2u(sch_1):page459_i77@pure_quanta.q_cap_diffbus(chips)"
			("LOCATION" "C779")
		)
		("@s9s_mb_2u_lib.s9s_mb_2u(sch_1):page459_i70@pure_quanta.q_cap_diffbus(chips)"
			("LOCATION" "C780")
		)
		("@s9s_mb_2u_lib.s9s_mb_2u(sch_1):page459_i69@pure_quanta.q_cap_diffbus(chips)"
			("LOCATION" "C781")
		)
		("@s9s_mb_2u_lib.s9s_mb_2u(sch_1):page459_i68@pure_quanta.q_cap_diffbus(chips)"
			("LOCATION" "C782")
		)
		("@s9s_mb_2u_lib.s9s_mb_2u(sch_1):page459_i67@pure_quanta.q_cap_diffbus(chips)"
			("LOCATION" "C783")
		)
		("@s9s_mb_2u_lib.s9s_mb_2u(sch_1):page459_i66@pure_quanta.q_cap_diffbus(chips)"
			("LOCATION" "C784")
		)
		("@s9s_mb_2u_lib.s9s_mb_2u(sch_1):page459_i65@pure_quanta.q_cap_diffbus(chips)"
			("LOCATION" "C785")
		)
		("@s9s_mb_2u_lib.s9s_mb_2u(sch_1):page459_i64@pure_quanta.q_cap_diffbus(chips)"
			("LOCATION" "C786")
		)
		("@s9s_mb_2u_lib.s9s_mb_2u(sch_1):page459_i63@pure_quanta.q_cap_diffbus(chips)"
			("LOCATION" "C787")
		)
		("@s9s_mb_2u_lib.s9s_mb_2u(sch_1):page459_i61@pure_quanta.q_cap_diffbus(chips)"
			("LOCATION" "C788")
		)
		("@s9s_mb_2u_lib.s9s_mb_2u(sch_1):page459_i62@pure_quanta.q_cap_diffbus(chips)"
			("LOCATION" "C789")
		)
		("@s9s_mb_2u_lib.s9s_mb_2u(sch_1):page459_i41@pure_quanta.q_cap_diffbus(chips)"
			("LOCATION" "C790")
		)
		("@s9s_mb_2u_lib.s9s_mb_2u(sch_1):page459_i40@pure_quanta.q_cap_diffbus(chips)"
			("LOCATION" "C791")
		)
		("@s9s_mb_2u_lib.s9s_mb_2u(sch_1):page459_i39@pure_quanta.q_cap_diffbus(chips)"
			("LOCATION" "C792")
		)
		("@s9s_mb_2u_lib.s9s_mb_2u(sch_1):page459_i38@pure_quanta.q_cap_diffbus(chips)"
			("LOCATION" "C793")
		)
		("@s9s_mb_2u_lib.s9s_mb_2u(sch_1):page459_i37@pure_quanta.q_cap_diffbus(chips)"
			("LOCATION" "C794")
		)
		("@s9s_mb_2u_lib.s9s_mb_2u(sch_1):page459_i36@pure_quanta.q_cap_diffbus(chips)"
			("LOCATION" "C795")
		)
		("@s9s_mb_2u_lib.s9s_mb_2u(sch_1):page459_i30@pure_quanta.q_cap_diffbus(chips)"
			("LOCATION" "C796")
		)
		("@s9s_mb_2u_lib.s9s_mb_2u(sch_1):page459_i29@pure_quanta.q_cap_diffbus(chips)"
			("LOCATION" "C797")
		)
		("@s9s_mb_2u_lib.s9s_mb_2u(sch_1):page459_i28@pure_quanta.q_cap_diffbus(chips)"
			("LOCATION" "C798")
		)
		("@s9s_mb_2u_lib.s9s_mb_2u(sch_1):page459_i27@pure_quanta.q_cap_diffbus(chips)"
			("LOCATION" "C799")
		)
		("@s9s_mb_2u_lib.s9s_mb_2u(sch_1):page459_i25@pure_quanta.q_cap_diffbus(chips)"
			("LOCATION" "C800")
		)
		("@s9s_mb_2u_lib.s9s_mb_2u(sch_1):page459_i26@pure_quanta.q_cap_diffbus(chips)"
			("LOCATION" "C801")
		)
		("@s9s_mb_2u_lib.s9s_mb_2u(sch_1):page459_i24@pure_quanta.q_cap_diffbus(chips)"
			("LOCATION" "C802")
		)
		("@s9s_mb_2u_lib.s9s_mb_2u(sch_1):page459_i23@pure_quanta.q_cap_diffbus(chips)"
			("LOCATION" "C803")
		)
		("@s9s_mb_2u_lib.s9s_mb_2u(sch_1):page459_i21@pure_quanta.q_cap_diffbus(chips)"
			("LOCATION" "C804")
		)
		("@s9s_mb_2u_lib.s9s_mb_2u(sch_1):page459_i22@pure_quanta.q_cap_diffbus(chips)"
			("LOCATION" "C805")
		)
		("@s9s_mb_2u_lib.s9s_mb_2u(sch_1):page459_i171@pure_quanta.q_cap_diffbus(chips)"
			("LOCATION" "C806")
		)
		("@s9s_mb_2u_lib.s9s_mb_2u(sch_1):page459_i172@pure_quanta.q_cap_diffbus(chips)"
			("LOCATION" "C807")
		)
		("@s9s_mb_2u_lib.s9s_mb_2u(sch_1):page459_i170@pure_quanta.q_cap_diffbus(chips)"
			("LOCATION" "C808")
		)
		("@s9s_mb_2u_lib.s9s_mb_2u(sch_1):page459_i169@pure_quanta.q_cap_diffbus(chips)"
			("LOCATION" "C809")
		)
		("@s9s_mb_2u_lib.s9s_mb_2u(sch_1):page459_i168@pure_quanta.q_cap_diffbus(chips)"
			("LOCATION" "C810")
		)
		("@s9s_mb_2u_lib.s9s_mb_2u(sch_1):page459_i167@pure_quanta.q_cap_diffbus(chips)"
			("LOCATION" "C811")
		)
		("@s9s_mb_2u_lib.s9s_mb_2u(sch_1):page459_i163@pure_quanta.q_cap_diffbus(chips)"
			("LOCATION" "C812")
		)
		("@s9s_mb_2u_lib.s9s_mb_2u(sch_1):page459_i162@pure_quanta.q_cap_diffbus(chips)"
			("LOCATION" "C813")
		)
		("@s9s_mb_2u_lib.s9s_mb_2u(sch_1):page459_i160@pure_quanta.q_cap_diffbus(chips)"
			("LOCATION" "C814")
		)
		("@s9s_mb_2u_lib.s9s_mb_2u(sch_1):page459_i161@pure_quanta.q_cap_diffbus(chips)"
			("LOCATION" "C815")
		)
		("@s9s_mb_2u_lib.s9s_mb_2u(sch_1):page459_i159@pure_quanta.q_cap_diffbus(chips)"
			("LOCATION" "C816")
		)
		("@s9s_mb_2u_lib.s9s_mb_2u(sch_1):page459_i158@pure_quanta.q_cap_diffbus(chips)"
			("LOCATION" "C817")
		)
		("@s9s_mb_2u_lib.s9s_mb_2u(sch_1):page459_i157@pure_quanta.q_cap_diffbus(chips)"
			("LOCATION" "C818")
		)
		("@s9s_mb_2u_lib.s9s_mb_2u(sch_1):page459_i156@pure_quanta.q_cap_diffbus(chips)"
			("LOCATION" "C819")
		)
		("@s9s_mb_2u_lib.s9s_mb_2u(sch_1):page459_i155@pure_quanta.q_cap_diffbus(chips)"
			("LOCATION" "C820")
		)
		("@s9s_mb_2u_lib.s9s_mb_2u(sch_1):page459_i154@pure_quanta.q_cap_diffbus(chips)"
			("LOCATION" "C821")
		)
		("@s9s_mb_2u_lib.s9s_mb_2u(sch_1):page459_i140@pure_quanta.q_cap_diffbus(chips)"
			("LOCATION" "C822")
		)
		("@s9s_mb_2u_lib.s9s_mb_2u(sch_1):page459_i139@pure_quanta.q_cap_diffbus(chips)"
			("LOCATION" "C823")
		)
		("@s9s_mb_2u_lib.s9s_mb_2u(sch_1):page459_i138@pure_quanta.q_cap_diffbus(chips)"
			("LOCATION" "C824")
		)
		("@s9s_mb_2u_lib.s9s_mb_2u(sch_1):page459_i137@pure_quanta.q_cap_diffbus(chips)"
			("LOCATION" "C825")
		)
		("@s9s_mb_2u_lib.s9s_mb_2u(sch_1):page459_i136@pure_quanta.q_cap_diffbus(chips)"
			("LOCATION" "C826")
		)
		("@s9s_mb_2u_lib.s9s_mb_2u(sch_1):page459_i135@pure_quanta.q_cap_diffbus(chips)"
			("LOCATION" "C827")
		)
		("@s9s_mb_2u_lib.s9s_mb_2u(sch_1):page459_i130@pure_quanta.q_cap_diffbus(chips)"
			("LOCATION" "C828")
		)
		("@s9s_mb_2u_lib.s9s_mb_2u(sch_1):page459_i131@pure_quanta.q_cap_diffbus(chips)"
			("LOCATION" "C829")
		)
		("@s9s_mb_2u_lib.s9s_mb_2u(sch_1):page459_i129@pure_quanta.q_cap_diffbus(chips)"
			("LOCATION" "C830")
		)
		("@s9s_mb_2u_lib.s9s_mb_2u(sch_1):page459_i128@pure_quanta.q_cap_diffbus(chips)"
			("LOCATION" "C831")
		)
		("@s9s_mb_2u_lib.s9s_mb_2u(sch_1):page459_i127@pure_quanta.q_cap_diffbus(chips)"
			("LOCATION" "C832")
		)
		("@s9s_mb_2u_lib.s9s_mb_2u(sch_1):page459_i126@pure_quanta.q_cap_diffbus(chips)"
			("LOCATION" "C833")
		)
		("@s9s_mb_2u_lib.s9s_mb_2u(sch_1):page459_i125@pure_quanta.q_cap_diffbus(chips)"
			("LOCATION" "C834")
		)
		("@s9s_mb_2u_lib.s9s_mb_2u(sch_1):page459_i124@pure_quanta.q_cap_diffbus(chips)"
			("LOCATION" "C835")
		)
		("@s9s_mb_2u_lib.s9s_mb_2u(sch_1):page459_i123@pure_quanta.q_cap_diffbus(chips)"
			("LOCATION" "C836")
		)
		("@s9s_mb_2u_lib.s9s_mb_2u(sch_1):page459_i122@pure_quanta.q_cap_diffbus(chips)"
			("LOCATION" "C837")
		)
		("@s9s_mb_2u_lib.s9s_mb_2u(sch_1):page460_i67@pure_quanta.q_cap_diffbus(chips)"
			("LOCATION" "C838")
		)
		("@s9s_mb_2u_lib.s9s_mb_2u(sch_1):page460_i66@pure_quanta.q_cap_diffbus(chips)"
			("LOCATION" "C839")
		)
		("@s9s_mb_2u_lib.s9s_mb_2u(sch_1):page460_i65@pure_quanta.q_cap_diffbus(chips)"
			("LOCATION" "C840")
		)
		("@s9s_mb_2u_lib.s9s_mb_2u(sch_1):page460_i64@pure_quanta.q_cap_diffbus(chips)"
			("LOCATION" "C841")
		)
		("@s9s_mb_2u_lib.s9s_mb_2u(sch_1):page460_i62@pure_quanta.q_cap_diffbus(chips)"
			("LOCATION" "C842")
		)
		("@s9s_mb_2u_lib.s9s_mb_2u(sch_1):page460_i63@pure_quanta.q_cap_diffbus(chips)"
			("LOCATION" "C843")
		)
		("@s9s_mb_2u_lib.s9s_mb_2u(sch_1):page460_i61@pure_quanta.q_cap_diffbus(chips)"
			("LOCATION" "C844")
		)
		("@s9s_mb_2u_lib.s9s_mb_2u(sch_1):page460_i60@pure_quanta.q_cap_diffbus(chips)"
			("LOCATION" "C845")
		)
		("@s9s_mb_2u_lib.s9s_mb_2u(sch_1):page460_i59@pure_quanta.q_cap_diffbus(chips)"
			("LOCATION" "C846")
		)
		("@s9s_mb_2u_lib.s9s_mb_2u(sch_1):page460_i58@pure_quanta.q_cap_diffbus(chips)"
			("LOCATION" "C847")
		)
		("@s9s_mb_2u_lib.s9s_mb_2u(sch_1):page460_i57@pure_quanta.q_cap_diffbus(chips)"
			("LOCATION" "C848")
		)
		("@s9s_mb_2u_lib.s9s_mb_2u(sch_1):page460_i56@pure_quanta.q_cap_diffbus(chips)"
			("LOCATION" "C849")
		)
		("@s9s_mb_2u_lib.s9s_mb_2u(sch_1):page460_i55@pure_quanta.q_cap_diffbus(chips)"
			("LOCATION" "C850")
		)
		("@s9s_mb_2u_lib.s9s_mb_2u(sch_1):page460_i54@pure_quanta.q_cap_diffbus(chips)"
			("LOCATION" "C851")
		)
		("@s9s_mb_2u_lib.s9s_mb_2u(sch_1):page460_i52@pure_quanta.q_cap_diffbus(chips)"
			("LOCATION" "C852")
		)
		("@s9s_mb_2u_lib.s9s_mb_2u(sch_1):page460_i53@pure_quanta.q_cap_diffbus(chips)"
			("LOCATION" "C853")
		)
		("@s9s_mb_2u_lib.s9s_mb_2u(sch_1):page460_i35@pure_quanta.q_cap_diffbus(chips)"
			("LOCATION" "C854")
		)
		("@s9s_mb_2u_lib.s9s_mb_2u(sch_1):page460_i36@pure_quanta.q_cap_diffbus(chips)"
			("LOCATION" "C855")
		)
		("@s9s_mb_2u_lib.s9s_mb_2u(sch_1):page460_i34@pure_quanta.q_cap_diffbus(chips)"
			("LOCATION" "C856")
		)
		("@s9s_mb_2u_lib.s9s_mb_2u(sch_1):page460_i33@pure_quanta.q_cap_diffbus(chips)"
			("LOCATION" "C857")
		)
		("@s9s_mb_2u_lib.s9s_mb_2u(sch_1):page460_i32@pure_quanta.q_cap_diffbus(chips)"
			("LOCATION" "C858")
		)
		("@s9s_mb_2u_lib.s9s_mb_2u(sch_1):page460_i31@pure_quanta.q_cap_diffbus(chips)"
			("LOCATION" "C859")
		)
		("@s9s_mb_2u_lib.s9s_mb_2u(sch_1):page460_i30@pure_quanta.q_cap_diffbus(chips)"
			("LOCATION" "C860")
		)
		("@s9s_mb_2u_lib.s9s_mb_2u(sch_1):page460_i29@pure_quanta.q_cap_diffbus(chips)"
			("LOCATION" "C861")
		)
		("@s9s_mb_2u_lib.s9s_mb_2u(sch_1):page460_i28@pure_quanta.q_cap_diffbus(chips)"
			("LOCATION" "C862")
		)
		("@s9s_mb_2u_lib.s9s_mb_2u(sch_1):page460_i27@pure_quanta.q_cap_diffbus(chips)"
			("LOCATION" "C863")
		)
		("@s9s_mb_2u_lib.s9s_mb_2u(sch_1):page460_i25@pure_quanta.q_cap_diffbus(chips)"
			("LOCATION" "C864")
		)
		("@s9s_mb_2u_lib.s9s_mb_2u(sch_1):page460_i26@pure_quanta.q_cap_diffbus(chips)"
			("LOCATION" "C865")
		)
		("@s9s_mb_2u_lib.s9s_mb_2u(sch_1):page460_i24@pure_quanta.q_cap_diffbus(chips)"
			("LOCATION" "C866")
		)
		("@s9s_mb_2u_lib.s9s_mb_2u(sch_1):page460_i23@pure_quanta.q_cap_diffbus(chips)"
			("LOCATION" "C867")
		)
		("@s9s_mb_2u_lib.s9s_mb_2u(sch_1):page460_i21@pure_quanta.q_cap_diffbus(chips)"
			("LOCATION" "C868")
		)
		("@s9s_mb_2u_lib.s9s_mb_2u(sch_1):page460_i22@pure_quanta.q_cap_diffbus(chips)"
			("LOCATION" "C869")
		)
		("@s9s_mb_2u_lib.s9s_mb_2u(sch_1):page460_i170@pure_quanta.q_cap_diffbus(chips)"
			("LOCATION" "C870")
		)
		("@s9s_mb_2u_lib.s9s_mb_2u(sch_1):page460_i169@pure_quanta.q_cap_diffbus(chips)"
			("LOCATION" "C871")
		)
		("@s9s_mb_2u_lib.s9s_mb_2u(sch_1):page460_i168@pure_quanta.q_cap_diffbus(chips)"
			("LOCATION" "C872")
		)
		("@s9s_mb_2u_lib.s9s_mb_2u(sch_1):page460_i167@pure_quanta.q_cap_diffbus(chips)"
			("LOCATION" "C873")
		)
		("@s9s_mb_2u_lib.s9s_mb_2u(sch_1):page460_i166@pure_quanta.q_cap_diffbus(chips)"
			("LOCATION" "C874")
		)
		("@s9s_mb_2u_lib.s9s_mb_2u(sch_1):page460_i165@pure_quanta.q_cap_diffbus(chips)"
			("LOCATION" "C875")
		)
		("@s9s_mb_2u_lib.s9s_mb_2u(sch_1):page460_i161@pure_quanta.q_cap_diffbus(chips)"
			("LOCATION" "C876")
		)
		("@s9s_mb_2u_lib.s9s_mb_2u(sch_1):page460_i160@pure_quanta.q_cap_diffbus(chips)"
			("LOCATION" "C877")
		)
		("@s9s_mb_2u_lib.s9s_mb_2u(sch_1):page460_i159@pure_quanta.q_cap_diffbus(chips)"
			("LOCATION" "C878")
		)
		("@s9s_mb_2u_lib.s9s_mb_2u(sch_1):page460_i158@pure_quanta.q_cap_diffbus(chips)"
			("LOCATION" "C879")
		)
		("@s9s_mb_2u_lib.s9s_mb_2u(sch_1):page460_i157@pure_quanta.q_cap_diffbus(chips)"
			("LOCATION" "C880")
		)
		("@s9s_mb_2u_lib.s9s_mb_2u(sch_1):page460_i156@pure_quanta.q_cap_diffbus(chips)"
			("LOCATION" "C881")
		)
		("@s9s_mb_2u_lib.s9s_mb_2u(sch_1):page460_i155@pure_quanta.q_cap_diffbus(chips)"
			("LOCATION" "C882")
		)
		("@s9s_mb_2u_lib.s9s_mb_2u(sch_1):page460_i154@pure_quanta.q_cap_diffbus(chips)"
			("LOCATION" "C883")
		)
		("@s9s_mb_2u_lib.s9s_mb_2u(sch_1):page460_i153@pure_quanta.q_cap_diffbus(chips)"
			("LOCATION" "C884")
		)
		("@s9s_mb_2u_lib.s9s_mb_2u(sch_1):page460_i152@pure_quanta.q_cap_diffbus(chips)"
			("LOCATION" "C885")
		)
		("@s9s_mb_2u_lib.s9s_mb_2u(sch_1):page460_i139@pure_quanta.q_cap_diffbus(chips)"
			("LOCATION" "C886")
		)
		("@s9s_mb_2u_lib.s9s_mb_2u(sch_1):page460_i138@pure_quanta.q_cap_diffbus(chips)"
			("LOCATION" "C887")
		)
		("@s9s_mb_2u_lib.s9s_mb_2u(sch_1):page460_i137@pure_quanta.q_cap_diffbus(chips)"
			("LOCATION" "C888")
		)
		("@s9s_mb_2u_lib.s9s_mb_2u(sch_1):page460_i136@pure_quanta.q_cap_diffbus(chips)"
			("LOCATION" "C889")
		)
		("@s9s_mb_2u_lib.s9s_mb_2u(sch_1):page460_i135@pure_quanta.q_cap_diffbus(chips)"
			("LOCATION" "C890")
		)
		("@s9s_mb_2u_lib.s9s_mb_2u(sch_1):page460_i134@pure_quanta.q_cap_diffbus(chips)"
			("LOCATION" "C891")
		)
		("@s9s_mb_2u_lib.s9s_mb_2u(sch_1):page460_i129@pure_quanta.q_cap_diffbus(chips)"
			("LOCATION" "C892")
		)
		("@s9s_mb_2u_lib.s9s_mb_2u(sch_1):page460_i128@pure_quanta.q_cap_diffbus(chips)"
			("LOCATION" "C893")
		)
		("@s9s_mb_2u_lib.s9s_mb_2u(sch_1):page460_i127@pure_quanta.q_cap_diffbus(chips)"
			("LOCATION" "C894")
		)
		("@s9s_mb_2u_lib.s9s_mb_2u(sch_1):page460_i126@pure_quanta.q_cap_diffbus(chips)"
			("LOCATION" "C895")
		)
		("@s9s_mb_2u_lib.s9s_mb_2u(sch_1):page460_i125@pure_quanta.q_cap_diffbus(chips)"
			("LOCATION" "C896")
		)
		("@s9s_mb_2u_lib.s9s_mb_2u(sch_1):page460_i124@pure_quanta.q_cap_diffbus(chips)"
			("LOCATION" "C897")
		)
		("@s9s_mb_2u_lib.s9s_mb_2u(sch_1):page460_i123@pure_quanta.q_cap_diffbus(chips)"
			("LOCATION" "C898")
		)
		("@s9s_mb_2u_lib.s9s_mb_2u(sch_1):page460_i122@pure_quanta.q_cap_diffbus(chips)"
			("LOCATION" "C899")
		)
		("@s9s_mb_2u_lib.s9s_mb_2u(sch_1):page460_i121@pure_quanta.q_cap_diffbus(chips)"
			("LOCATION" "C900")
		)
		("@s9s_mb_2u_lib.s9s_mb_2u(sch_1):page460_i120@pure_quanta.q_cap_diffbus(chips)"
			("LOCATION" "C901")
		)
		("@s9s_mb_2u_lib.s9s_mb_2u(sch_1):page461_i77@pure_quanta.q_cap_diffbus(chips)"
			("LOCATION" "C902")
		)
		("@s9s_mb_2u_lib.s9s_mb_2u(sch_1):page461_i78@pure_quanta.q_cap_diffbus(chips)"
			("LOCATION" "C903")
		)
		("@s9s_mb_2u_lib.s9s_mb_2u(sch_1):page461_i76@pure_quanta.q_cap_diffbus(chips)"
			("LOCATION" "C904")
		)
		("@s9s_mb_2u_lib.s9s_mb_2u(sch_1):page461_i75@pure_quanta.q_cap_diffbus(chips)"
			("LOCATION" "C905")
		)
		("@s9s_mb_2u_lib.s9s_mb_2u(sch_1):page461_i69@pure_quanta.q_cap_diffbus(chips)"
			("LOCATION" "C906")
		)
		("@s9s_mb_2u_lib.s9s_mb_2u(sch_1):page461_i70@pure_quanta.q_cap_diffbus(chips)"
			("LOCATION" "C907")
		)
		("@s9s_mb_2u_lib.s9s_mb_2u(sch_1):page461_i68@pure_quanta.q_cap_diffbus(chips)"
			("LOCATION" "C908")
		)
		("@s9s_mb_2u_lib.s9s_mb_2u(sch_1):page461_i67@pure_quanta.q_cap_diffbus(chips)"
			("LOCATION" "C909")
		)
		("@s9s_mb_2u_lib.s9s_mb_2u(sch_1):page461_i66@pure_quanta.q_cap_diffbus(chips)"
			("LOCATION" "C910")
		)
		("@s9s_mb_2u_lib.s9s_mb_2u(sch_1):page461_i65@pure_quanta.q_cap_diffbus(chips)"
			("LOCATION" "C911")
		)
		("@s9s_mb_2u_lib.s9s_mb_2u(sch_1):page461_i64@pure_quanta.q_cap_diffbus(chips)"
			("LOCATION" "C912")
		)
		("@s9s_mb_2u_lib.s9s_mb_2u(sch_1):page461_i63@pure_quanta.q_cap_diffbus(chips)"
			("LOCATION" "C913")
		)
		("@s9s_mb_2u_lib.s9s_mb_2u(sch_1):page461_i62@pure_quanta.q_cap_diffbus(chips)"
			("LOCATION" "C914")
		)
		("@s9s_mb_2u_lib.s9s_mb_2u(sch_1):page461_i61@pure_quanta.q_cap_diffbus(chips)"
			("LOCATION" "C915")
		)
		("@s9s_mb_2u_lib.s9s_mb_2u(sch_1):page461_i59@pure_quanta.q_cap_diffbus(chips)"
			("LOCATION" "C916")
		)
		("@s9s_mb_2u_lib.s9s_mb_2u(sch_1):page461_i58@pure_quanta.q_cap_diffbus(chips)"
			("LOCATION" "C917")
		)
		("@s9s_mb_2u_lib.s9s_mb_2u(sch_1):page461_i57@pure_quanta.q_cap_diffbus(chips)"
			("LOCATION" "C918")
		)
		("@s9s_mb_2u_lib.s9s_mb_2u(sch_1):page461_i56@pure_quanta.q_cap_diffbus(chips)"
			("LOCATION" "C919")
		)
		("@s9s_mb_2u_lib.s9s_mb_2u(sch_1):page461_i54@pure_quanta.q_cap_diffbus(chips)"
			("LOCATION" "C920")
		)
		("@s9s_mb_2u_lib.s9s_mb_2u(sch_1):page461_i55@pure_quanta.q_cap_diffbus(chips)"
			("LOCATION" "C921")
		)
		("@s9s_mb_2u_lib.s9s_mb_2u(sch_1):page461_i53@pure_quanta.q_cap_diffbus(chips)"
			("LOCATION" "C922")
		)
		("@s9s_mb_2u_lib.s9s_mb_2u(sch_1):page461_i25@pure_quanta.q_cap_diffbus(chips)"
			("LOCATION" "C923")
		)
		("@s9s_mb_2u_lib.s9s_mb_2u(sch_1):page461_i24@pure_quanta.q_cap_diffbus(chips)"
			("LOCATION" "C924")
		)
		("@s9s_mb_2u_lib.s9s_mb_2u(sch_1):page461_i23@pure_quanta.q_cap_diffbus(chips)"
			("LOCATION" "C925")
		)
		("@s9s_mb_2u_lib.s9s_mb_2u(sch_1):page461_i22@pure_quanta.q_cap_diffbus(chips)"
			("LOCATION" "C926")
		)
		("@s9s_mb_2u_lib.s9s_mb_2u(sch_1):page461_i21@pure_quanta.q_cap_diffbus(chips)"
			("LOCATION" "C927")
		)
		("@s9s_mb_2u_lib.s9s_mb_2u(sch_1):page461_i20@pure_quanta.q_cap_diffbus(chips)"
			("LOCATION" "C928")
		)
		("@s9s_mb_2u_lib.s9s_mb_2u(sch_1):page461_i19@pure_quanta.q_cap_diffbus(chips)"
			("LOCATION" "C929")
		)
		("@s9s_mb_2u_lib.s9s_mb_2u(sch_1):page461_i18@pure_quanta.q_cap_diffbus(chips)"
			("LOCATION" "C930")
		)
		("@s9s_mb_2u_lib.s9s_mb_2u(sch_1):page461_i17@pure_quanta.q_cap_diffbus(chips)"
			("LOCATION" "C931")
		)
		("@s9s_mb_2u_lib.s9s_mb_2u(sch_1):page461_i16@pure_quanta.q_cap_diffbus(chips)"
			("LOCATION" "C932")
		)
		("@s9s_mb_2u_lib.s9s_mb_2u(sch_1):page461_i15@pure_quanta.q_cap_diffbus(chips)"
			("LOCATION" "C933")
		)
		("@s9s_mb_2u_lib.s9s_mb_2u(sch_1):page461_i201@pure_quanta.q_cap_diffbus(chips)"
			("LOCATION" "C934")
		)
		("@s9s_mb_2u_lib.s9s_mb_2u(sch_1):page461_i202@pure_quanta.q_cap_diffbus(chips)"
			("LOCATION" "C935")
		)
		("@s9s_mb_2u_lib.s9s_mb_2u(sch_1):page461_i200@pure_quanta.q_cap_diffbus(chips)"
			("LOCATION" "C936")
		)
		("@s9s_mb_2u_lib.s9s_mb_2u(sch_1):page461_i199@pure_quanta.q_cap_diffbus(chips)"
			("LOCATION" "C937")
		)
		("@s9s_mb_2u_lib.s9s_mb_2u(sch_1):page461_i183@pure_quanta.q_cap_diffbus(chips)"
			("LOCATION" "C938")
		)
		("@s9s_mb_2u_lib.s9s_mb_2u(sch_1):page461_i184@pure_quanta.q_cap_diffbus(chips)"
			("LOCATION" "C939")
		)
		("@s9s_mb_2u_lib.s9s_mb_2u(sch_1):page461_i185@pure_quanta.q_cap_diffbus(chips)"
			("LOCATION" "C940")
		)
		("@s9s_mb_2u_lib.s9s_mb_2u(sch_1):page461_i180@pure_quanta.q_cap_diffbus(chips)"
			("LOCATION" "C941")
		)
		("@s9s_mb_2u_lib.s9s_mb_2u(sch_1):page461_i181@pure_quanta.q_cap_diffbus(chips)"
			("LOCATION" "C942")
		)
		("@s9s_mb_2u_lib.s9s_mb_2u(sch_1):page461_i182@pure_quanta.q_cap_diffbus(chips)"
			("LOCATION" "C943")
		)
		("@s9s_mb_2u_lib.s9s_mb_2u(sch_1):page461_i179@pure_quanta.q_cap_diffbus(chips)"
			("LOCATION" "C944")
		)
		("@s9s_mb_2u_lib.s9s_mb_2u(sch_1):page461_i178@pure_quanta.q_cap_diffbus(chips)"
			("LOCATION" "C945")
		)
		("@s9s_mb_2u_lib.s9s_mb_2u(sch_1):page461_i177@pure_quanta.q_cap_diffbus(chips)"
			("LOCATION" "C946")
		)
		("@s9s_mb_2u_lib.s9s_mb_2u(sch_1):page461_i176@pure_quanta.q_cap_diffbus(chips)"
			("LOCATION" "C947")
		)
		("@s9s_mb_2u_lib.s9s_mb_2u(sch_1):page461_i168@pure_quanta.q_cap_diffbus(chips)"
			("LOCATION" "C948")
		)
		("@s9s_mb_2u_lib.s9s_mb_2u(sch_1):page461_i167@pure_quanta.q_cap_diffbus(chips)"
			("LOCATION" "C949")
		)
		("@s9s_mb_2u_lib.s9s_mb_2u(sch_1):page461_i165@pure_quanta.q_cap_diffbus(chips)"
			("LOCATION" "C950")
		)
		("@s9s_mb_2u_lib.s9s_mb_2u(sch_1):page461_i166@pure_quanta.q_cap_diffbus(chips)"
			("LOCATION" "C951")
		)
		("@s9s_mb_2u_lib.s9s_mb_2u(sch_1):page461_i164@pure_quanta.q_cap_diffbus(chips)"
			("LOCATION" "C952")
		)
		("@s9s_mb_2u_lib.s9s_mb_2u(sch_1):page461_i163@pure_quanta.q_cap_diffbus(chips)"
			("LOCATION" "C953")
		)
		("@s9s_mb_2u_lib.s9s_mb_2u(sch_1):page461_i162@pure_quanta.q_cap_diffbus(chips)"
			("LOCATION" "C954")
		)
		("@s9s_mb_2u_lib.s9s_mb_2u(sch_1):page461_i125@pure_quanta.q_cap_diffbus(chips)"
			("LOCATION" "C955")
		)
		("@s9s_mb_2u_lib.s9s_mb_2u(sch_1):page461_i124@pure_quanta.q_cap_diffbus(chips)"
			("LOCATION" "C956")
		)
		("@s9s_mb_2u_lib.s9s_mb_2u(sch_1):page461_i123@pure_quanta.q_cap_diffbus(chips)"
			("LOCATION" "C957")
		)
		("@s9s_mb_2u_lib.s9s_mb_2u(sch_1):page461_i122@pure_quanta.q_cap_diffbus(chips)"
			("LOCATION" "C958")
		)
		("@s9s_mb_2u_lib.s9s_mb_2u(sch_1):page461_i121@pure_quanta.q_cap_diffbus(chips)"
			("LOCATION" "C959")
		)
		("@s9s_mb_2u_lib.s9s_mb_2u(sch_1):page461_i119@pure_quanta.q_cap_diffbus(chips)"
			("LOCATION" "C960")
		)
		("@s9s_mb_2u_lib.s9s_mb_2u(sch_1):page461_i120@pure_quanta.q_cap_diffbus(chips)"
			("LOCATION" "C961")
		)
		("@s9s_mb_2u_lib.s9s_mb_2u(sch_1):page461_i118@pure_quanta.q_cap_diffbus(chips)"
			("LOCATION" "C962")
		)
		("@s9s_mb_2u_lib.s9s_mb_2u(sch_1):page461_i116@pure_quanta.q_cap_diffbus(chips)"
			("LOCATION" "C963")
		)
		("@s9s_mb_2u_lib.s9s_mb_2u(sch_1):page461_i117@pure_quanta.q_cap_diffbus(chips)"
			("LOCATION" "C964")
		)
		("@s9s_mb_2u_lib.s9s_mb_2u(sch_1):page461_i115@pure_quanta.q_cap_diffbus(chips)"
			("LOCATION" "C965")
		)
		("@s9s_mb_2u_lib.s9s_mb_2u(sch_1):page576_i79@pure_quanta.q_cap(chips)"
			("LOCATION" "C1042")
		)
		("@s9s_mb_2u_lib.s9s_mb_2u(sch_1):page576_i80@pure_quanta.q_cap(chips)"
			("LOCATION" "C1170")
		)
		("@s9s_mb_2u_lib.s9s_mb_2u(sch_1):page576_i81@pure_quanta.q_cap(chips)"
			("LOCATION" "C1171")
		)
		("@s9s_mb_2u_lib.s9s_mb_2u(sch_1):page576_i72@pure_quanta.q_cap(chips)"
			("LOCATION" "C1172")
		)
		("@s9s_mb_2u_lib.s9s_mb_2u(sch_1):page576_i78@pure_quanta.q_cap(chips)"
			("LOCATION" "C1226")
		)
		("@s9s_mb_2u_lib.s9s_mb_2u(sch_1):page576_i82@pure_quanta.q_cap(chips)"
			("LOCATION" "C1227")
		)
		("@s9s_mb_2u_lib.s9s_mb_2u(sch_1):page576_i73@pure_quanta.q_cap(chips)"
			("LOCATION" "C1326")
		)
		("@s9s_mb_2u_lib.s9s_mb_2u(sch_1):page576_i83@pure_quanta.q_cap(chips)"
			("LOCATION" "C1331")
		)
		("@s9s_mb_2u_lib.s9s_mb_2u(sch_1):page576_i63@pure_quanta.q_cap(chips)"
			("LOCATION" "C1332")
		)
		("@s9s_mb_2u_lib.s9s_mb_2u(sch_1):page576_i64@pure_quanta.q_cap(chips)"
			("LOCATION" "C1333")
		)
		("@s9s_mb_2u_lib.s9s_mb_2u(sch_1):page576_i65@pure_quanta.q_cap(chips)"
			("LOCATION" "C1338")
		)
		("@s9s_mb_2u_lib.s9s_mb_2u(sch_1):page576_i66@pure_quanta.q_cap(chips)"
			("LOCATION" "C1339")
		)
		("@s9s_mb_2u_lib.s9s_mb_2u(sch_1):page576_i67@pure_quanta.q_cap(chips)"
			("LOCATION" "C1340")
		)
		("@s9s_mb_2u_lib.s9s_mb_2u(sch_1):page576_i69@pure_quanta.bat547f(chips)"
			("LOCATION" "D7")
		)
		("@s9s_mb_2u_lib.s9s_mb_2u(sch_1):page576_i91@pure_quanta.mosfet_nch_1d3s(chips)"
			("LOCATION" "PQ1")
		)
		("@s9s_mb_2u_lib.s9s_mb_2u(sch_1):page576_i90@pure_quanta.mosfet_nch_1d3s(chips)"
			("LOCATION" "PQ2")
		)
		("@s9s_mb_2u_lib.s9s_mb_2u(sch_1):page576_i75@pure_quanta.mosfet_nch_dual(chips)"
			("LOCATION" "Q37")
		)
		("@s9s_mb_2u_lib.s9s_mb_2u(sch_1):page576_i76@pure_quanta.mosfet_nch_dual(chips)"
			("LOCATION" "Q37")
		)
		("@s9s_mb_2u_lib.s9s_mb_2u(sch_1):page576_i85@pure_quanta.q_res(chips)"
			("LOCATION" "R1607")
		)
		("@s9s_mb_2u_lib.s9s_mb_2u(sch_1):page576_i84@pure_quanta.q_res(chips)"
			("LOCATION" "R1640")
		)
		("@s9s_mb_2u_lib.s9s_mb_2u(sch_1):page576_i74@pure_quanta.q_res(chips)"
			("LOCATION" "R1641")
		)
		("@s9s_mb_2u_lib.s9s_mb_2u(sch_1):page576_i87@pure_quanta.q_res(chips)"
			("LOCATION" "R1642")
		)
		("@s9s_mb_2u_lib.s9s_mb_2u(sch_1):page576_i86@pure_quanta.q_res(chips)"
			("LOCATION" "R1643")
		)
		("@s9s_mb_2u_lib.s9s_mb_2u(sch_1):page576_i77@pure_quanta.q_res(chips)"
			("LOCATION" "R1654")
		)
		("@s9s_mb_2u_lib.s9s_mb_2u(sch_1):page576_i71@pure_quanta.q_res(chips)"
			("LOCATION" "R1655")
		)
		("@s9s_mb_2u_lib.s9s_mb_2u(sch_1):page576_i88@pure_quanta.q_res(chips)"
			("LOCATION" "R1682")
		)
		("@s9s_mb_2u_lib.s9s_mb_2u(sch_1):page576_i89@pure_quanta.q_res(chips)"
			("LOCATION" "R1698")
		)
		("@s9s_mb_2u_lib.s9s_mb_2u(sch_1):page576_i68@pure_quanta.q_res(chips)"
			("LOCATION" "R1706")
		)
		("@s9s_mb_2u_lib.s9s_mb_2u(sch_1):page576_i62@pure_quanta.slg55221120010vtr(chips)"
			("LOCATION" "U79")
		)
		("@s9s_mb_2u_lib.s9s_mb_2u(sch_1):page576_i70@pure_quanta.rt9818c44gv(chips)"
			("LOCATION" "U99")
		)
		("@s9s_mb_2u_lib.s9s_mb_2u(sch_1):page496_i40@pure_quanta.q_cap(chips)"
			("LOCATION" "C1046")
		)
		("@s9s_mb_2u_lib.s9s_mb_2u(sch_1):page496_i37@pure_quanta.q_cap(chips)"
			("LOCATION" "C1047")
		)
		("@s9s_mb_2u_lib.s9s_mb_2u(sch_1):page496_i36@pure_quanta.q_cap(chips)"
			("LOCATION" "C1048")
		)
		("@s9s_mb_2u_lib.s9s_mb_2u(sch_1):page496_i35@pure_quanta.q_cap(chips)"
			("LOCATION" "C1049")
		)
		("@s9s_mb_2u_lib.s9s_mb_2u(sch_1):page496_i34@pure_quanta.q_cap(chips)"
			("LOCATION" "C1050")
		)
		("@s9s_mb_2u_lib.s9s_mb_2u(sch_1):page496_i33@pure_quanta.q_cap(chips)"
			("LOCATION" "C1051")
		)
		("@s9s_mb_2u_lib.s9s_mb_2u(sch_1):page496_i31@pure_quanta.q_cap(chips)"
			("LOCATION" "C1052")
		)
		("@s9s_mb_2u_lib.s9s_mb_2u(sch_1):page496_i29@pure_quanta.q_cap(chips)"
			("LOCATION" "C1053")
		)
		("@s9s_mb_2u_lib.s9s_mb_2u(sch_1):page496_i94@pure_quanta.q_cap(chips)"
			("LOCATION" "C1208")
		)
		("@s9s_mb_2u_lib.s9s_mb_2u(sch_1):page496_i92@pure_quanta.q_cap(chips)"
			("LOCATION" "C1215")
		)
		("@s9s_mb_2u_lib.s9s_mb_2u(sch_1):page496_i53@pure_quanta.sconn84_123318136(chips)"
			("LOCATION" "J33")
		)
		("@s9s_mb_2u_lib.s9s_mb_2u(sch_1):page496_i71@pure_quanta.q_res(chips)"
			("LOCATION" "R394")
		)
		("@s9s_mb_2u_lib.s9s_mb_2u(sch_1):page496_i77@pure_quanta.q_res(chips)"
			("LOCATION" "R395")
		)
		("@s9s_mb_2u_lib.s9s_mb_2u(sch_1):page496_i78@pure_quanta.q_res(chips)"
			("LOCATION" "R396")
		)
		("@s9s_mb_2u_lib.s9s_mb_2u(sch_1):page496_i114@pure_quanta.q_res(chips)"
			("LOCATION" "R1584")
		)
		("@s9s_mb_2u_lib.s9s_mb_2u(sch_1):page496_i112@pure_quanta.q_res(chips)"
			("LOCATION" "R1585")
		)
		("@s9s_mb_2u_lib.s9s_mb_2u(sch_1):page496_i88@pure_quanta.q_res(chips)"
			("LOCATION" "R1609")
		)
		("@s9s_mb_2u_lib.s9s_mb_2u(sch_1):page496_i97@pure_quanta.q_res(chips)"
			("LOCATION" "R1613")
		)
		("@s9s_mb_2u_lib.s9s_mb_2u(sch_1):page496_i98@pure_quanta.q_res(chips)"
			("LOCATION" "R1614")
		)
		("@s9s_mb_2u_lib.s9s_mb_2u(sch_1):page496_i146@pure_quanta.q_res(chips)"
			("LOCATION" "R1858")
		)
		("@s9s_mb_2u_lib.s9s_mb_2u(sch_1):page496_i145@pure_quanta.q_res(chips)"
			("LOCATION" "R1859")
		)
		("@s9s_mb_2u_lib.s9s_mb_2u(sch_1):page497_i30@pure_quanta.q_cap(chips)"
			("LOCATION" "C1054")
		)
		("@s9s_mb_2u_lib.s9s_mb_2u(sch_1):page497_i60@pure_quanta.q_cap(chips)"
			("LOCATION" "C1055")
		)
		("@s9s_mb_2u_lib.s9s_mb_2u(sch_1):page497_i59@pure_quanta.q_cap(chips)"
			("LOCATION" "C1056")
		)
		("@s9s_mb_2u_lib.s9s_mb_2u(sch_1):page497_i58@pure_quanta.q_cap(chips)"
			("LOCATION" "C1057")
		)
		("@s9s_mb_2u_lib.s9s_mb_2u(sch_1):page497_i57@pure_quanta.q_cap(chips)"
			("LOCATION" "C1058")
		)
		("@s9s_mb_2u_lib.s9s_mb_2u(sch_1):page497_i56@pure_quanta.q_cap(chips)"
			("LOCATION" "C1059")
		)
		("@s9s_mb_2u_lib.s9s_mb_2u(sch_1):page497_i54@pure_quanta.q_cap(chips)"
			("LOCATION" "C1060")
		)
		("@s9s_mb_2u_lib.s9s_mb_2u(sch_1):page497_i53@pure_quanta.q_cap(chips)"
			("LOCATION" "C1061")
		)
		("@s9s_mb_2u_lib.s9s_mb_2u(sch_1):page497_i91@pure_quanta.q_cap(chips)"
			("LOCATION" "C1216")
		)
		("@s9s_mb_2u_lib.s9s_mb_2u(sch_1):page497_i89@pure_quanta.q_cap(chips)"
			("LOCATION" "C1217")
		)
		("@s9s_mb_2u_lib.s9s_mb_2u(sch_1):page497_i43@pure_quanta.sconn84_123318136(chips)"
			("LOCATION" "J34")
		)
		("@s9s_mb_2u_lib.s9s_mb_2u(sch_1):page497_i71@pure_quanta.q_res(chips)"
			("LOCATION" "R398")
		)
		("@s9s_mb_2u_lib.s9s_mb_2u(sch_1):page497_i77@pure_quanta.q_res(chips)"
			("LOCATION" "R399")
		)
		("@s9s_mb_2u_lib.s9s_mb_2u(sch_1):page497_i78@pure_quanta.q_res(chips)"
			("LOCATION" "R400")
		)
		("@s9s_mb_2u_lib.s9s_mb_2u(sch_1):page497_i100@pure_quanta.q_res(chips)"
			("LOCATION" "R1586")
		)
		("@s9s_mb_2u_lib.s9s_mb_2u(sch_1):page497_i98@pure_quanta.q_res(chips)"
			("LOCATION" "R1587")
		)
		("@s9s_mb_2u_lib.s9s_mb_2u(sch_1):page497_i85@pure_quanta.q_res(chips)"
			("LOCATION" "R1610")
		)
		("@s9s_mb_2u_lib.s9s_mb_2u(sch_1):page497_i95@pure_quanta.q_res(chips)"
			("LOCATION" "R1615")
		)
		("@s9s_mb_2u_lib.s9s_mb_2u(sch_1):page497_i93@pure_quanta.q_res(chips)"
			("LOCATION" "R1616")
		)
		("@s9s_mb_2u_lib.s9s_mb_2u(sch_1):page497_i104@pure_quanta.q_res(chips)"
			("LOCATION" "R1860")
		)
		("@s9s_mb_2u_lib.s9s_mb_2u(sch_1):page497_i106@pure_quanta.q_res(chips)"
			("LOCATION" "R1861")
		)
		("@s9s_mb_2u_lib.s9s_mb_2u(sch_1):page498_i40@pure_quanta.q_cap(chips)"
			("LOCATION" "C1062")
		)
		("@s9s_mb_2u_lib.s9s_mb_2u(sch_1):page498_i39@pure_quanta.q_cap(chips)"
			("LOCATION" "C1063")
		)
		("@s9s_mb_2u_lib.s9s_mb_2u(sch_1):page498_i37@pure_quanta.q_cap(chips)"
			("LOCATION" "C1064")
		)
		("@s9s_mb_2u_lib.s9s_mb_2u(sch_1):page498_i33@pure_quanta.q_cap(chips)"
			("LOCATION" "C1065")
		)
		("@s9s_mb_2u_lib.s9s_mb_2u(sch_1):page498_i30@pure_quanta.q_cap(chips)"
			("LOCATION" "C1066")
		)
		("@s9s_mb_2u_lib.s9s_mb_2u(sch_1):page498_i29@pure_quanta.q_cap(chips)"
			("LOCATION" "C1067")
		)
		("@s9s_mb_2u_lib.s9s_mb_2u(sch_1):page498_i28@pure_quanta.q_cap(chips)"
			("LOCATION" "C1068")
		)
		("@s9s_mb_2u_lib.s9s_mb_2u(sch_1):page498_i2@pure_quanta.q_cap(chips)"
			("LOCATION" "C1069")
		)
		("@s9s_mb_2u_lib.s9s_mb_2u(sch_1):page498_i91@pure_quanta.q_cap(chips)"
			("LOCATION" "C1218")
		)
		("@s9s_mb_2u_lib.s9s_mb_2u(sch_1):page498_i89@pure_quanta.q_cap(chips)"
			("LOCATION" "C1219")
		)
		("@s9s_mb_2u_lib.s9s_mb_2u(sch_1):page498_i64@pure_quanta.sconn84_123318136(chips)"
			("LOCATION" "J35")
		)
		("@s9s_mb_2u_lib.s9s_mb_2u(sch_1):page498_i70@pure_quanta.q_res(chips)"
			("LOCATION" "R402")
		)
		("@s9s_mb_2u_lib.s9s_mb_2u(sch_1):page498_i77@pure_quanta.q_res(chips)"
			("LOCATION" "R403")
		)
		("@s9s_mb_2u_lib.s9s_mb_2u(sch_1):page498_i78@pure_quanta.q_res(chips)"
			("LOCATION" "R404")
		)
		("@s9s_mb_2u_lib.s9s_mb_2u(sch_1):page498_i121@pure_quanta.q_res(chips)"
			("LOCATION" "R1588")
		)
		("@s9s_mb_2u_lib.s9s_mb_2u(sch_1):page498_i120@pure_quanta.q_res(chips)"
			("LOCATION" "R1589")
		)
		("@s9s_mb_2u_lib.s9s_mb_2u(sch_1):page498_i85@pure_quanta.q_res(chips)"
			("LOCATION" "R1611")
		)
		("@s9s_mb_2u_lib.s9s_mb_2u(sch_1):page498_i95@pure_quanta.q_res(chips)"
			("LOCATION" "R1617")
		)
		("@s9s_mb_2u_lib.s9s_mb_2u(sch_1):page498_i93@pure_quanta.q_res(chips)"
			("LOCATION" "R1618")
		)
		("@s9s_mb_2u_lib.s9s_mb_2u(sch_1):page498_i142@pure_quanta.q_res(chips)"
			("LOCATION" "R1862")
		)
		("@s9s_mb_2u_lib.s9s_mb_2u(sch_1):page498_i144@pure_quanta.q_res(chips)"
			("LOCATION" "R1863")
		)
		("@s9s_mb_2u_lib.s9s_mb_2u(sch_1):page499_i17@pure_quanta.q_cap(chips)"
			("LOCATION" "C1070")
		)
		("@s9s_mb_2u_lib.s9s_mb_2u(sch_1):page499_i59@pure_quanta.q_cap(chips)"
			("LOCATION" "C1071")
		)
		("@s9s_mb_2u_lib.s9s_mb_2u(sch_1):page499_i39@pure_quanta.q_cap(chips)"
			("LOCATION" "C1072")
		)
		("@s9s_mb_2u_lib.s9s_mb_2u(sch_1):page499_i38@pure_quanta.q_cap(chips)"
			("LOCATION" "C1073")
		)
		("@s9s_mb_2u_lib.s9s_mb_2u(sch_1):page499_i37@pure_quanta.q_cap(chips)"
			("LOCATION" "C1074")
		)
		("@s9s_mb_2u_lib.s9s_mb_2u(sch_1):page499_i36@pure_quanta.q_cap(chips)"
			("LOCATION" "C1075")
		)
		("@s9s_mb_2u_lib.s9s_mb_2u(sch_1):page499_i13@pure_quanta.q_cap(chips)"
			("LOCATION" "C1076")
		)
		("@s9s_mb_2u_lib.s9s_mb_2u(sch_1):page499_i11@pure_quanta.q_cap(chips)"
			("LOCATION" "C1077")
		)
		("@s9s_mb_2u_lib.s9s_mb_2u(sch_1):page499_i91@pure_quanta.q_cap(chips)"
			("LOCATION" "C1220")
		)
		("@s9s_mb_2u_lib.s9s_mb_2u(sch_1):page499_i89@pure_quanta.q_cap(chips)"
			("LOCATION" "C1221")
		)
		("@s9s_mb_2u_lib.s9s_mb_2u(sch_1):page499_i52@pure_quanta.sconn84_123318136(chips)"
			("LOCATION" "J36")
		)
		("@s9s_mb_2u_lib.s9s_mb_2u(sch_1):page499_i70@pure_quanta.q_res(chips)"
			("LOCATION" "R406")
		)
		("@s9s_mb_2u_lib.s9s_mb_2u(sch_1):page499_i77@pure_quanta.q_res(chips)"
			("LOCATION" "R407")
		)
		("@s9s_mb_2u_lib.s9s_mb_2u(sch_1):page499_i78@pure_quanta.q_res(chips)"
			("LOCATION" "R408")
		)
		("@s9s_mb_2u_lib.s9s_mb_2u(sch_1):page499_i126@pure_quanta.q_res(chips)"
			("LOCATION" "R1590")
		)
		("@s9s_mb_2u_lib.s9s_mb_2u(sch_1):page499_i124@pure_quanta.q_res(chips)"
			("LOCATION" "R1591")
		)
		("@s9s_mb_2u_lib.s9s_mb_2u(sch_1):page499_i85@pure_quanta.q_res(chips)"
			("LOCATION" "R1612")
		)
		("@s9s_mb_2u_lib.s9s_mb_2u(sch_1):page499_i95@pure_quanta.q_res(chips)"
			("LOCATION" "R1619")
		)
		("@s9s_mb_2u_lib.s9s_mb_2u(sch_1):page499_i93@pure_quanta.q_res(chips)"
			("LOCATION" "R1620")
		)
		("@s9s_mb_2u_lib.s9s_mb_2u(sch_1):page499_i144@pure_quanta.q_res(chips)"
			("LOCATION" "R1864")
		)
		("@s9s_mb_2u_lib.s9s_mb_2u(sch_1):page499_i146@pure_quanta.q_res(chips)"
			("LOCATION" "R1865")
		)
		("@s9s_mb_2u_lib.s9s_mb_2u(sch_1):page526_i88@pure_quanta.q_cap(chips)"
			("LOCATION" "C1078")
		)
		("@s9s_mb_2u_lib.s9s_mb_2u(sch_1):page526_i75@pure_quanta.q_cap(chips)"
			("LOCATION" "C1079")
		)
		("@s9s_mb_2u_lib.s9s_mb_2u(sch_1):page526_i90@pure_quanta.q_cap(chips)"
			("LOCATION" "C1080")
		)
		("@s9s_mb_2u_lib.s9s_mb_2u(sch_1):page526_i76@pure_quanta.q_cap(chips)"
			("LOCATION" "C1081")
		)
		("@s9s_mb_2u_lib.s9s_mb_2u(sch_1):page526_i96@pure_quanta.q_cap(chips)"
			("LOCATION" "C1082")
		)
		("@s9s_mb_2u_lib.s9s_mb_2u(sch_1):page526_i91@pure_quanta.q_cap(chips)"
			("LOCATION" "C1083")
		)
		("@s9s_mb_2u_lib.s9s_mb_2u(sch_1):page526_i97@pure_quanta.q_cap(chips)"
			("LOCATION" "C1084")
		)
		("@s9s_mb_2u_lib.s9s_mb_2u(sch_1):page526_i92@pure_quanta.q_cap(chips)"
			("LOCATION" "C1085")
		)
		("@s9s_mb_2u_lib.s9s_mb_2u(sch_1):page526_i98@pure_quanta.q_cap(chips)"
			("LOCATION" "C1086")
		)
		("@s9s_mb_2u_lib.s9s_mb_2u(sch_1):page526_i93@pure_quanta.q_cap(chips)"
			("LOCATION" "C1087")
		)
		("@s9s_mb_2u_lib.s9s_mb_2u(sch_1):page526_i100@pure_quanta.q_cap(chips)"
			("LOCATION" "C1088")
		)
		("@s9s_mb_2u_lib.s9s_mb_2u(sch_1):page526_i95@pure_quanta.q_cap(chips)"
			("LOCATION" "C1089")
		)
		("@s9s_mb_2u_lib.s9s_mb_2u(sch_1):page526_i239@pure_quanta.q_cap_diffbus(chips)"
			("LOCATION" "C1418")
		)
		("@s9s_mb_2u_lib.s9s_mb_2u(sch_1):page526_i240@pure_quanta.q_cap_diffbus(chips)"
			("LOCATION" "C1419")
		)
		("@s9s_mb_2u_lib.s9s_mb_2u(sch_1):page526_i243@pure_quanta.q_cap_diffbus(chips)"
			("LOCATION" "C1420")
		)
		("@s9s_mb_2u_lib.s9s_mb_2u(sch_1):page526_i246@pure_quanta.q_cap_diffbus(chips)"
			("LOCATION" "C1421")
		)
		("@s9s_mb_2u_lib.s9s_mb_2u(sch_1):page526_i178@pure_quanta.sconn75k_apci0155p004a(chips)"
			("LOCATION" "J59")
		)
		("@s9s_mb_2u_lib.s9s_mb_2u(sch_1):page526_i224@pure_quanta.sconn75k_apci0155p004a(chips)"
			("LOCATION" "J60")
		)
		("@s9s_mb_2u_lib.s9s_mb_2u(sch_1):page526_i176@pure_quanta.q_res(chips)"
			("LOCATION" "R478")
		)
		("@s9s_mb_2u_lib.s9s_mb_2u(sch_1):page526_i227@pure_quanta.q_res(chips)"
			("LOCATION" "R479")
		)
		("@s9s_mb_2u_lib.s9s_mb_2u(sch_1):page526_i170@pure_quanta.q_res(chips)"
			("LOCATION" "R484")
		)
		("@s9s_mb_2u_lib.s9s_mb_2u(sch_1):page526_i122@pure_quanta.q_res(chips)"
			("LOCATION" "R485")
		)
		("@s9s_mb_2u_lib.s9s_mb_2u(sch_1):page526_i162@pure_quanta.q_res(chips)"
			("LOCATION" "R486")
		)
		("@s9s_mb_2u_lib.s9s_mb_2u(sch_1):page526_i173@pure_quanta.q_res(chips)"
			("LOCATION" "R487")
		)
		("@s9s_mb_2u_lib.s9s_mb_2u(sch_1):page526_i226@pure_quanta.q_res(chips)"
			("LOCATION" "R488")
		)
		("@s9s_mb_2u_lib.s9s_mb_2u(sch_1):page526_i228@pure_quanta.q_res(chips)"
			("LOCATION" "R489")
		)
		("@s9s_mb_2u_lib.s9s_mb_2u(sch_1):page526_i229@pure_quanta.q_res(chips)"
			("LOCATION" "R490")
		)
		("@s9s_mb_2u_lib.s9s_mb_2u(sch_1):page526_i164@pure_quanta.q_res(chips)"
			("LOCATION" "R491")
		)
		("@s9s_mb_2u_lib.s9s_mb_2u(sch_1):page526_i230@pure_quanta.q_res(chips)"
			("LOCATION" "R492")
		)
		("@s9s_mb_2u_lib.s9s_mb_2u(sch_1):page526_i167@pure_quanta.q_res(chips)"
			("LOCATION" "R1396")
		)
		("@s9s_mb_2u_lib.s9s_mb_2u(sch_1):page526_i225@pure_quanta.q_res(chips)"
			("LOCATION" "R1397")
		)
		("@s9s_mb_2u_lib.s9s_mb_2u(sch_1):page526_i109@pure_quanta.q_res(chips)"
			("LOCATION" "R1604")
		)
		("@s9s_mb_2u_lib.s9s_mb_2u(sch_1):page526_i105@pure_quanta.q_res(chips)"
			("LOCATION" "R1605")
		)
		("@s9s_mb_2u_lib.s9s_mb_2u(sch_1):page546_i66@pure_quanta.q_cap(chips)"
			("LOCATION" "C1106")
		)
		("@s9s_mb_2u_lib.s9s_mb_2u(sch_1):page546_i15@pure_quanta.q_cap(chips)"
			("LOCATION" "C1107")
		)
		("@s9s_mb_2u_lib.s9s_mb_2u(sch_1):page546_i52@pure_quanta.q_cap(chips)"
			("LOCATION" "C1108")
		)
		("@s9s_mb_2u_lib.s9s_mb_2u(sch_1):page546_i65@pure_quanta.q_cap(chips)"
			("LOCATION" "C1109")
		)
		("@s9s_mb_2u_lib.s9s_mb_2u(sch_1):page546_i18@pure_quanta.q_cap(chips)"
			("LOCATION" "C1110")
		)
		("@s9s_mb_2u_lib.s9s_mb_2u(sch_1):page546_i51@pure_quanta.q_cap(chips)"
			("LOCATION" "C1111")
		)
		("@s9s_mb_2u_lib.s9s_mb_2u(sch_1):page546_i63@pure_quanta.q_cap(chips)"
			("LOCATION" "C1112")
		)
		("@s9s_mb_2u_lib.s9s_mb_2u(sch_1):page546_i19@pure_quanta.q_cap(chips)"
			("LOCATION" "C1113")
		)
		("@s9s_mb_2u_lib.s9s_mb_2u(sch_1):page546_i49@pure_quanta.q_cap(chips)"
			("LOCATION" "C1114")
		)
		("@s9s_mb_2u_lib.s9s_mb_2u(sch_1):page546_i99@pure_quanta.q_cap(chips)"
			("LOCATION" "C1115")
		)
		("@s9s_mb_2u_lib.s9s_mb_2u(sch_1):page546_i93@pure_quanta.q_cap(chips)"
			("LOCATION" "C1116")
		)
		("@s9s_mb_2u_lib.s9s_mb_2u(sch_1):page546_i62@pure_quanta.q_cap(chips)"
			("LOCATION" "C1117")
		)
		("@s9s_mb_2u_lib.s9s_mb_2u(sch_1):page546_i21@pure_quanta.q_cap(chips)"
			("LOCATION" "C1118")
		)
		("@s9s_mb_2u_lib.s9s_mb_2u(sch_1):page546_i48@pure_quanta.q_cap(chips)"
			("LOCATION" "C1119")
		)
		("@s9s_mb_2u_lib.s9s_mb_2u(sch_1):page546_i133@pure_quanta.q_cap(chips)"
			("LOCATION" "C1120")
		)
		("@s9s_mb_2u_lib.s9s_mb_2u(sch_1):page546_i61@pure_quanta.q_cap(chips)"
			("LOCATION" "C1121")
		)
		("@s9s_mb_2u_lib.s9s_mb_2u(sch_1):page546_i20@pure_quanta.q_cap(chips)"
			("LOCATION" "C1122")
		)
		("@s9s_mb_2u_lib.s9s_mb_2u(sch_1):page546_i47@pure_quanta.q_cap(chips)"
			("LOCATION" "C1123")
		)
		("@s9s_mb_2u_lib.s9s_mb_2u(sch_1):page546_i107@pure_quanta.q_cap(chips)"
			("LOCATION" "C1124")
		)
		("@s9s_mb_2u_lib.s9s_mb_2u(sch_1):page546_i95@pure_quanta.q_cap(chips)"
			("LOCATION" "C1125")
		)
		("@s9s_mb_2u_lib.s9s_mb_2u(sch_1):page546_i60@pure_quanta.q_cap(chips)"
			("LOCATION" "C1126")
		)
		("@s9s_mb_2u_lib.s9s_mb_2u(sch_1):page546_i22@pure_quanta.q_cap(chips)"
			("LOCATION" "C1127")
		)
		("@s9s_mb_2u_lib.s9s_mb_2u(sch_1):page546_i46@pure_quanta.q_cap(chips)"
			("LOCATION" "C1128")
		)
		("@s9s_mb_2u_lib.s9s_mb_2u(sch_1):page546_i126@pure_quanta.q_cap(chips)"
			("LOCATION" "C1129")
		)
		("@s9s_mb_2u_lib.s9s_mb_2u(sch_1):page546_i106@pure_quanta.q_cap(chips)"
			("LOCATION" "C1130")
		)
		("@s9s_mb_2u_lib.s9s_mb_2u(sch_1):page546_i98@pure_quanta.q_cap(chips)"
			("LOCATION" "C1131")
		)
		("@s9s_mb_2u_lib.s9s_mb_2u(sch_1):page546_i59@pure_quanta.q_cap(chips)"
			("LOCATION" "C1132")
		)
		("@s9s_mb_2u_lib.s9s_mb_2u(sch_1):page546_i23@pure_quanta.q_cap(chips)"
			("LOCATION" "C1133")
		)
		("@s9s_mb_2u_lib.s9s_mb_2u(sch_1):page546_i45@pure_quanta.q_cap(chips)"
			("LOCATION" "C1134")
		)
		("@s9s_mb_2u_lib.s9s_mb_2u(sch_1):page546_i125@pure_quanta.q_cap(chips)"
			("LOCATION" "C1135")
		)
		("@s9s_mb_2u_lib.s9s_mb_2u(sch_1):page546_i105@pure_quanta.q_cap(chips)"
			("LOCATION" "C1136")
		)
		("@s9s_mb_2u_lib.s9s_mb_2u(sch_1):page546_i58@pure_quanta.q_cap(chips)"
			("LOCATION" "C1137")
		)
		("@s9s_mb_2u_lib.s9s_mb_2u(sch_1):page546_i24@pure_quanta.q_cap(chips)"
			("LOCATION" "C1138")
		)
		("@s9s_mb_2u_lib.s9s_mb_2u(sch_1):page546_i44@pure_quanta.q_cap(chips)"
			("LOCATION" "C1139")
		)
		("@s9s_mb_2u_lib.s9s_mb_2u(sch_1):page546_i104@pure_quanta.q_cap(chips)"
			("LOCATION" "C1140")
		)
		("@s9s_mb_2u_lib.s9s_mb_2u(sch_1):page546_i57@pure_quanta.q_cap(chips)"
			("LOCATION" "C1141")
		)
		("@s9s_mb_2u_lib.s9s_mb_2u(sch_1):page546_i25@pure_quanta.q_cap(chips)"
			("LOCATION" "C1142")
		)
		("@s9s_mb_2u_lib.s9s_mb_2u(sch_1):page546_i43@pure_quanta.q_cap(chips)"
			("LOCATION" "C1143")
		)
		("@s9s_mb_2u_lib.s9s_mb_2u(sch_1):page546_i102@pure_quanta.q_cap(chips)"
			("LOCATION" "C1144")
		)
		("@s9s_mb_2u_lib.s9s_mb_2u(sch_1):page546_i56@pure_quanta.q_cap(chips)"
			("LOCATION" "C1145")
		)
		("@s9s_mb_2u_lib.s9s_mb_2u(sch_1):page546_i27@pure_quanta.q_cap(chips)"
			("LOCATION" "C1146")
		)
		("@s9s_mb_2u_lib.s9s_mb_2u(sch_1):page546_i42@pure_quanta.q_cap(chips)"
			("LOCATION" "C1147")
		)
		("@s9s_mb_2u_lib.s9s_mb_2u(sch_1):page546_i101@pure_quanta.q_cap(chips)"
			("LOCATION" "C1148")
		)
		("@s9s_mb_2u_lib.s9s_mb_2u(sch_1):page546_i68@pure_quanta.q_cap(chips)"
			("LOCATION" "C1149")
		)
		("@s9s_mb_2u_lib.s9s_mb_2u(sch_1):page546_i26@pure_quanta.q_cap(chips)"
			("LOCATION" "C1150")
		)
		("@s9s_mb_2u_lib.s9s_mb_2u(sch_1):page546_i41@pure_quanta.q_cap(chips)"
			("LOCATION" "C1151")
		)
		("@s9s_mb_2u_lib.s9s_mb_2u(sch_1):page546_i28@pure_quanta.q_cap(chips)"
			("LOCATION" "C1152")
		)
		("@s9s_mb_2u_lib.s9s_mb_2u(sch_1):page546_i40@pure_quanta.q_cap(chips)"
			("LOCATION" "C1153")
		)
		("@s9s_mb_2u_lib.s9s_mb_2u(sch_1):page546_i30@pure_quanta.q_cap(chips)"
			("LOCATION" "C1154")
		)
		("@s9s_mb_2u_lib.s9s_mb_2u(sch_1):page546_i39@pure_quanta.q_cap(chips)"
			("LOCATION" "C1155")
		)
		("@s9s_mb_2u_lib.s9s_mb_2u(sch_1):page546_i149@pure_quanta.q_cap(chips)"
			("LOCATION" "C1156")
		)
		("@s9s_mb_2u_lib.s9s_mb_2u(sch_1):page546_i33@pure_quanta.q_cap(chips)"
			("LOCATION" "C1157")
		)
		("@s9s_mb_2u_lib.s9s_mb_2u(sch_1):page546_i38@pure_quanta.q_cap(chips)"
			("LOCATION" "C1158")
		)
		("@s9s_mb_2u_lib.s9s_mb_2u(sch_1):page546_i147@pure_quanta.q_cap(chips)"
			("LOCATION" "C1159")
		)
		("@s9s_mb_2u_lib.s9s_mb_2u(sch_1):page546_i134@pure_quanta.q_cap(chips)"
			("LOCATION" "C1160")
		)
		("@s9s_mb_2u_lib.s9s_mb_2u(sch_1):page546_i32@pure_quanta.q_cap(chips)"
			("LOCATION" "C1161")
		)
		("@s9s_mb_2u_lib.s9s_mb_2u(sch_1):page546_i37@pure_quanta.q_cap(chips)"
			("LOCATION" "C1162")
		)
		("@s9s_mb_2u_lib.s9s_mb_2u(sch_1):page546_i151@pure_quanta.q_cap(chips)"
			("LOCATION" "C1163")
		)
		("@s9s_mb_2u_lib.s9s_mb_2u(sch_1):page546_i31@pure_quanta.q_cap(chips)"
			("LOCATION" "C1164")
		)
		("@s9s_mb_2u_lib.s9s_mb_2u(sch_1):page546_i36@pure_quanta.q_cap(chips)"
			("LOCATION" "C1165")
		)
		("@s9s_mb_2u_lib.s9s_mb_2u(sch_1):page546_i132@pure_quanta.q_cap(chips)"
			("LOCATION" "C1166")
		)
		("@s9s_mb_2u_lib.s9s_mb_2u(sch_1):page546_i29@pure_quanta.q_cap(chips)"
			("LOCATION" "C1167")
		)
		("@s9s_mb_2u_lib.s9s_mb_2u(sch_1):page546_i35@pure_quanta.q_cap(chips)"
			("LOCATION" "C1168")
		)
		("@s9s_mb_2u_lib.s9s_mb_2u(sch_1):page546_i131@pure_quanta.q_cap(chips)"
			("LOCATION" "C1169")
		)
		("@s9s_mb_2u_lib.s9s_mb_2u(sch_1):page546_i143@pure_quanta.q_inductor(chips)"
			("LOCATION" "L36")
		)
		("@s9s_mb_2u_lib.s9s_mb_2u(sch_1):page546_i145@pure_quanta.q_inductor(chips)"
			("LOCATION" "L37")
		)
		("@s9s_mb_2u_lib.s9s_mb_2u(sch_1):page546_i7@pure_quanta.q_res(chips)"
			("LOCATION" "R507")
		)
		("@s9s_mb_2u_lib.s9s_mb_2u(sch_1):page546_i8@pure_quanta.q_res(chips)"
			("LOCATION" "R508")
		)
		("@s9s_mb_2u_lib.s9s_mb_2u(sch_1):page546_i13@pure_quanta.q_res(chips)"
			("LOCATION" "R509")
		)
		("@s9s_mb_2u_lib.s9s_mb_2u(sch_1):page546_i14@pure_quanta.q_res(chips)"
			("LOCATION" "R510")
		)
		("@s9s_mb_2u_lib.s9s_mb_2u(sch_1):page546_i137@pure_quanta.q_res(chips)"
			("LOCATION" "R511")
		)
		("@s9s_mb_2u_lib.s9s_mb_2u(sch_1):page546_i138@pure_quanta.q_res(chips)"
			("LOCATION" "R512")
		)
		("@s9s_mb_2u_lib.s9s_mb_2u(sch_1):page546_i141@pure_quanta.q_res(chips)"
			("LOCATION" "R513")
		)
		("@s9s_mb_2u_lib.s9s_mb_2u(sch_1):page546_i140@pure_quanta.q_res(chips)"
			("LOCATION" "R514")
		)
		("@s9s_mb_2u_lib.s9s_mb_2u(sch_1):page546_i1@pure_quanta.\\10m25daf484c7g\\(chips)"
			("LOCATION" "U3")
		)
		("@s9s_mb_2u_lib.s9s_mb_2u(sch_1):page620_i67@pure_quanta.q_cap(chips)"
			("LOCATION" "C1177")
		)
		("@s9s_mb_2u_lib.s9s_mb_2u(sch_1):page620_i28@pure_quanta.q_res(chips)"
			("LOCATION" "R1317")
		)
		("@s9s_mb_2u_lib.s9s_mb_2u(sch_1):page620_i68@pure_quanta.q_res(chips)"
			("LOCATION" "R1320")
		)
		("@s9s_mb_2u_lib.s9s_mb_2u(sch_1):page620_i26@pure_quanta.q_res(chips)"
			("LOCATION" "R1324")
		)
		("@s9s_mb_2u_lib.s9s_mb_2u(sch_1):page620_i75@pure_quanta.q_res(chips)"
			("LOCATION" "R1325")
		)
		("@s9s_mb_2u_lib.s9s_mb_2u(sch_1):page620_i49@pure_quanta.q_res(chips)"
			("LOCATION" "R1333")
		)
		("@s9s_mb_2u_lib.s9s_mb_2u(sch_1):page620_i54@pure_quanta.q_res(chips)"
			("LOCATION" "R1334")
		)
		("@s9s_mb_2u_lib.s9s_mb_2u(sch_1):page620_i50@pure_quanta.q_res(chips)"
			("LOCATION" "R1335")
		)
		("@s9s_mb_2u_lib.s9s_mb_2u(sch_1):page620_i77@pure_quanta.q_res(chips)"
			("LOCATION" "R1337")
		)
		("@s9s_mb_2u_lib.s9s_mb_2u(sch_1):page620_i29@pure_quanta.q_res(chips)"
			("LOCATION" "R1338")
		)
		("@s9s_mb_2u_lib.s9s_mb_2u(sch_1):page620_i13@pure_quanta.q_res(chips)"
			("LOCATION" "R1339")
		)
		("@s9s_mb_2u_lib.s9s_mb_2u(sch_1):page620_i57@pure_quanta.q_res(chips)"
			("LOCATION" "R1340")
		)
		("@s9s_mb_2u_lib.s9s_mb_2u(sch_1):page620_i69@pure_quanta.q_res(chips)"
			("LOCATION" "R1341")
		)
		("@s9s_mb_2u_lib.s9s_mb_2u(sch_1):page620_i45@pure_quanta.q_res(chips)"
			("LOCATION" "R1342")
		)
		("@s9s_mb_2u_lib.s9s_mb_2u(sch_1):page620_i44@pure_quanta.q_res(chips)"
			("LOCATION" "R1343")
		)
		("@s9s_mb_2u_lib.s9s_mb_2u(sch_1):page620_i4@pure_quanta.sw8s_dhnf04ftvtr(chips)"
			("LOCATION" "S1")
		)
		("@s9s_mb_2u_lib.s9s_mb_2u(sch_1):page620_i35@pure_quanta.sw8s_dhnf04ftvtr(chips)"
			("LOCATION" "S2")
		)
		("@s9s_mb_2u_lib.s9s_mb_2u(sch_1):page525_i6@pure_quanta.q_cap(chips)"
			("LOCATION" "C1178")
		)
		("@s9s_mb_2u_lib.s9s_mb_2u(sch_1):page525_i27@pure_quanta.q_cap(chips)"
			("LOCATION" "C1181")
		)
		("@s9s_mb_2u_lib.s9s_mb_2u(sch_1):page525_i42@pure_quanta.q_cap(chips)"
			("LOCATION" "C1182")
		)
		("@s9s_mb_2u_lib.s9s_mb_2u(sch_1):page525_i51@pure_quanta.q_cap(chips)"
			("LOCATION" "C1183")
		)
		("@s9s_mb_2u_lib.s9s_mb_2u(sch_1):page525_i91@pure_quanta.q_cap(chips)"
			("LOCATION" "C1184")
		)
		("@s9s_mb_2u_lib.s9s_mb_2u(sch_1):page525_i7@pure_quanta.q_cap(chips)"
			("LOCATION" "C1185")
		)
		("@s9s_mb_2u_lib.s9s_mb_2u(sch_1):page525_i25@pure_quanta.q_cap(chips)"
			("LOCATION" "C1186")
		)
		("@s9s_mb_2u_lib.s9s_mb_2u(sch_1):page525_i40@pure_quanta.q_cap(chips)"
			("LOCATION" "C1187")
		)
		("@s9s_mb_2u_lib.s9s_mb_2u(sch_1):page525_i58@pure_quanta.q_cap(chips)"
			("LOCATION" "C1189")
		)
		("@s9s_mb_2u_lib.s9s_mb_2u(sch_1):page525_i89@pure_quanta.q_cap(chips)"
			("LOCATION" "C1191")
		)
		("@s9s_mb_2u_lib.s9s_mb_2u(sch_1):page525_i8@pure_quanta.q_cap(chips)"
			("LOCATION" "C1192")
		)
		("@s9s_mb_2u_lib.s9s_mb_2u(sch_1):page525_i30@pure_quanta.q_cap(chips)"
			("LOCATION" "C1197")
		)
		("@s9s_mb_2u_lib.s9s_mb_2u(sch_1):page525_i43@pure_quanta.q_cap(chips)"
			("LOCATION" "C1198")
		)
		("@s9s_mb_2u_lib.s9s_mb_2u(sch_1):page525_i59@pure_quanta.q_cap(chips)"
			("LOCATION" "C1200")
		)
		("@s9s_mb_2u_lib.s9s_mb_2u(sch_1):page525_i87@pure_quanta.q_cap(chips)"
			("LOCATION" "C1201")
		)
		("@s9s_mb_2u_lib.s9s_mb_2u(sch_1):page525_i29@pure_quanta.q_cap(chips)"
			("LOCATION" "C1202")
		)
		("@s9s_mb_2u_lib.s9s_mb_2u(sch_1):page525_i48@pure_quanta.q_cap(chips)"
			("LOCATION" "C1203")
		)
		("@s9s_mb_2u_lib.s9s_mb_2u(sch_1):page525_i60@pure_quanta.q_cap(chips)"
			("LOCATION" "C1204")
		)
		("@s9s_mb_2u_lib.s9s_mb_2u(sch_1):page525_i12@pure_quanta.q_cap(chips)"
			("LOCATION" "C1205")
		)
		("@s9s_mb_2u_lib.s9s_mb_2u(sch_1):page525_i78@pure_quanta.q_cap(chips)"
			("LOCATION" "C1206")
		)
		("@s9s_mb_2u_lib.s9s_mb_2u(sch_1):page525_i32@pure_quanta.q_cap(chips)"
			("LOCATION" "C1207")
		)
		("@s9s_mb_2u_lib.s9s_mb_2u(sch_1):page525_i45@pure_quanta.q_cap(chips)"
			("LOCATION" "C1210")
		)
		("@s9s_mb_2u_lib.s9s_mb_2u(sch_1):page525_i61@pure_quanta.q_cap(chips)"
			("LOCATION" "C1214")
		)
		("@s9s_mb_2u_lib.s9s_mb_2u(sch_1):page525_i13@pure_quanta.q_cap(chips)"
			("LOCATION" "C1228")
		)
		("@s9s_mb_2u_lib.s9s_mb_2u(sch_1):page525_i49@pure_quanta.q_cap(chips)"
			("LOCATION" "C1231")
		)
		("@s9s_mb_2u_lib.s9s_mb_2u(sch_1):page525_i63@pure_quanta.q_cap(chips)"
			("LOCATION" "C1242")
		)
		("@s9s_mb_2u_lib.s9s_mb_2u(sch_1):page525_i83@pure_quanta.q_cap(chips)"
			("LOCATION" "C1243")
		)
		("@s9s_mb_2u_lib.s9s_mb_2u(sch_1):page525_i15@pure_quanta.q_cap(chips)"
			("LOCATION" "C1244")
		)
		("@s9s_mb_2u_lib.s9s_mb_2u(sch_1):page525_i81@pure_quanta.q_cap(chips)"
			("LOCATION" "C1245")
		)
		("@s9s_mb_2u_lib.s9s_mb_2u(sch_1):page525_i21@pure_quanta.q_cap(chips)"
			("LOCATION" "C1246")
		)
		("@s9s_mb_2u_lib.s9s_mb_2u(sch_1):page525_i65@pure_quanta.q_cap(chips)"
			("LOCATION" "C1247")
		)
		("@s9s_mb_2u_lib.s9s_mb_2u(sch_1):page525_i22@pure_quanta.q_cap(chips)"
			("LOCATION" "C1248")
		)
		("@s9s_mb_2u_lib.s9s_mb_2u(sch_1):page525_i66@pure_quanta.q_cap(chips)"
			("LOCATION" "C1249")
		)
		("@s9s_mb_2u_lib.s9s_mb_2u(sch_1):page525_i137@pure_quanta.q_cap(chips)"
			("LOCATION" "C1250")
		)
		("@s9s_mb_2u_lib.s9s_mb_2u(sch_1):page525_i110@pure_quanta.q_cap(chips)"
			("LOCATION" "C1251")
		)
		("@s9s_mb_2u_lib.s9s_mb_2u(sch_1):page525_i125@pure_quanta.q_cap(chips)"
			("LOCATION" "C1252")
		)
		("@s9s_mb_2u_lib.s9s_mb_2u(sch_1):page525_i147@pure_quanta.q_cap(chips)"
			("LOCATION" "C1253")
		)
		("@s9s_mb_2u_lib.s9s_mb_2u(sch_1):page525_i111@pure_quanta.q_cap(chips)"
			("LOCATION" "C1254")
		)
		("@s9s_mb_2u_lib.s9s_mb_2u(sch_1):page525_i123@pure_quanta.q_cap(chips)"
			("LOCATION" "C1255")
		)
		("@s9s_mb_2u_lib.s9s_mb_2u(sch_1):page525_i136@pure_quanta.q_cap(chips)"
			("LOCATION" "C1256")
		)
		("@s9s_mb_2u_lib.s9s_mb_2u(sch_1):page525_i146@pure_quanta.q_cap(chips)"
			("LOCATION" "C1257")
		)
		("@s9s_mb_2u_lib.s9s_mb_2u(sch_1):page525_i112@pure_quanta.q_cap(chips)"
			("LOCATION" "C1258")
		)
		("@s9s_mb_2u_lib.s9s_mb_2u(sch_1):page525_i121@pure_quanta.q_cap(chips)"
			("LOCATION" "C1259")
		)
		("@s9s_mb_2u_lib.s9s_mb_2u(sch_1):page525_i131@pure_quanta.q_cap(chips)"
			("LOCATION" "C1260")
		)
		("@s9s_mb_2u_lib.s9s_mb_2u(sch_1):page525_i142@pure_quanta.q_cap(chips)"
			("LOCATION" "C1261")
		)
		("@s9s_mb_2u_lib.s9s_mb_2u(sch_1):page525_i104@pure_quanta.q_cap(chips)"
			("LOCATION" "C1262")
		)
		("@s9s_mb_2u_lib.s9s_mb_2u(sch_1):page525_i119@pure_quanta.q_cap(chips)"
			("LOCATION" "C1263")
		)
		("@s9s_mb_2u_lib.s9s_mb_2u(sch_1):page525_i133@pure_quanta.q_cap(chips)"
			("LOCATION" "C1264")
		)
		("@s9s_mb_2u_lib.s9s_mb_2u(sch_1):page525_i140@pure_quanta.q_cap(chips)"
			("LOCATION" "C1265")
		)
		("@s9s_mb_2u_lib.s9s_mb_2u(sch_1):page525_i127@pure_quanta.q_cap(chips)"
			("LOCATION" "C1266")
		)
		("@s9s_mb_2u_lib.s9s_mb_2u(sch_1):page525_i100@pure_quanta.q_cap(chips)"
			("LOCATION" "C1272")
		)
		("@s9s_mb_2u_lib.s9s_mb_2u(sch_1):page525_i116@pure_quanta.q_cap(chips)"
			("LOCATION" "C1273")
		)
		("@s9s_mb_2u_lib.s9s_mb_2u(sch_1):page525_i135@pure_quanta.q_inductor(chips)"
			("LOCATION" "L2")
		)
		("@s9s_mb_2u_lib.s9s_mb_2u(sch_1):page525_i145@pure_quanta.q_inductor(chips)"
			("LOCATION" "L10")
		)
		("@s9s_mb_2u_lib.s9s_mb_2u(sch_1):page525_i129@pure_quanta.q_res(chips)"
			("LOCATION" "R1463")
		)
		("@s9s_mb_2u_lib.s9s_mb_2u(sch_1):page525_i144@pure_quanta.q_res(chips)"
			("LOCATION" "R1464")
		)
		("@s9s_mb_2u_lib.s9s_mb_2u(sch_1):page511_i245@pure_quanta.q_capp(chips)"
			("LOCATION" "C1179")
		)
		("@s9s_mb_2u_lib.s9s_mb_2u(sch_1):page511_i248@pure_quanta.q_cap(chips)"
			("LOCATION" "C1180")
		)
		("@s9s_mb_2u_lib.s9s_mb_2u(sch_1):page511_i249@pure_quanta.q_capp(chips)"
			("LOCATION" "C1188")
		)
		("@s9s_mb_2u_lib.s9s_mb_2u(sch_1):page511_i251@pure_quanta.q_cap(chips)"
			("LOCATION" "C1193")
		)
		("@s9s_mb_2u_lib.s9s_mb_2u(sch_1):page511_i297@pure_quanta.q_cap(chips)"
			("LOCATION" "C1222")
		)
		("@s9s_mb_2u_lib.s9s_mb_2u(sch_1):page511_i298@pure_quanta.q_cap(chips)"
			("LOCATION" "C1223")
		)
		("@s9s_mb_2u_lib.s9s_mb_2u(sch_1):page511_i148@pure_quanta.sconn140_123322056(chips)"
			("LOCATION" "J39")
		)
		("@s9s_mb_2u_lib.s9s_mb_2u(sch_1):page511_i315@pure_quanta.conn4_g87mp042502thr(chips)"
			("LOCATION" "J51")
		)
		("@s9s_mb_2u_lib.s9s_mb_2u(sch_1):page511_i332@pure_quanta.q_res(chips)"
			("LOCATION" "R443")
		)
		("@s9s_mb_2u_lib.s9s_mb_2u(sch_1):page511_i328@pure_quanta.q_res(chips)"
			("LOCATION" "R493")
		)
		("@s9s_mb_2u_lib.s9s_mb_2u(sch_1):page511_i319@pure_quanta.q_res(chips)"
			("LOCATION" "R956")
		)
		("@s9s_mb_2u_lib.s9s_mb_2u(sch_1):page511_i326@pure_quanta.q_res(chips)"
			("LOCATION" "R957")
		)
		("@s9s_mb_2u_lib.s9s_mb_2u(sch_1):page511_i292@pure_quanta.q_res(chips)"
			("LOCATION" "R1621")
		)
		("@s9s_mb_2u_lib.s9s_mb_2u(sch_1):page511_i291@pure_quanta.q_res(chips)"
			("LOCATION" "R1622")
		)
		("@s9s_mb_2u_lib.s9s_mb_2u(sch_1):page511_i284@pure_quanta.q_res(chips)"
			("LOCATION" "R1623")
		)
		("@s9s_mb_2u_lib.s9s_mb_2u(sch_1):page511_i281@pure_quanta.q_res(chips)"
			("LOCATION" "R1624")
		)
		("@s9s_mb_2u_lib.s9s_mb_2u(sch_1):page511_i274@pure_quanta.q_res(chips)"
			("LOCATION" "R1625")
		)
		("@s9s_mb_2u_lib.s9s_mb_2u(sch_1):page511_i275@pure_quanta.q_res(chips)"
			("LOCATION" "R1626")
		)
		("@s9s_mb_2u_lib.s9s_mb_2u(sch_1):page511_i276@pure_quanta.q_res(chips)"
			("LOCATION" "R1627")
		)
		("@s9s_mb_2u_lib.s9s_mb_2u(sch_1):page511_i277@pure_quanta.q_res(chips)"
			("LOCATION" "R1628")
		)
		("@s9s_mb_2u_lib.s9s_mb_2u(sch_1):page511_i278@pure_quanta.q_res(chips)"
			("LOCATION" "R1629")
		)
		("@s9s_mb_2u_lib.s9s_mb_2u(sch_1):page511_i318@pure_quanta.q_res(chips)"
			("LOCATION" "R1851")
		)
		("@s9s_mb_2u_lib.s9s_mb_2u(sch_1):page512_i268@pure_quanta.q_capp(chips)"
			("LOCATION" "C1194")
		)
		("@s9s_mb_2u_lib.s9s_mb_2u(sch_1):page512_i273@pure_quanta.q_cap(chips)"
			("LOCATION" "C1195")
		)
		("@s9s_mb_2u_lib.s9s_mb_2u(sch_1):page512_i269@pure_quanta.q_capp(chips)"
			("LOCATION" "C1196")
		)
		("@s9s_mb_2u_lib.s9s_mb_2u(sch_1):page512_i270@pure_quanta.q_cap(chips)"
			("LOCATION" "C1199")
		)
		("@s9s_mb_2u_lib.s9s_mb_2u(sch_1):page512_i309@pure_quanta.q_cap(chips)"
			("LOCATION" "C1224")
		)
		("@s9s_mb_2u_lib.s9s_mb_2u(sch_1):page512_i306@pure_quanta.q_cap(chips)"
			("LOCATION" "C1225")
		)
		("@s9s_mb_2u_lib.s9s_mb_2u(sch_1):page512_i25@pure_quanta.sconn140_123322056(chips)"
			("LOCATION" "J40")
		)
		("@s9s_mb_2u_lib.s9s_mb_2u(sch_1):page512_i314@pure_quanta.conn4_g87mp042502thr(chips)"
			("LOCATION" "J52")
		)
		("@s9s_mb_2u_lib.s9s_mb_2u(sch_1):page512_i329@pure_quanta.q_res(chips)"
			("LOCATION" "R505")
		)
		("@s9s_mb_2u_lib.s9s_mb_2u(sch_1):page512_i322@pure_quanta.q_res(chips)"
			("LOCATION" "R958")
		)
		("@s9s_mb_2u_lib.s9s_mb_2u(sch_1):page512_i326@pure_quanta.q_res(chips)"
			("LOCATION" "R959")
		)
		("@s9s_mb_2u_lib.s9s_mb_2u(sch_1):page512_i332@pure_quanta.q_res(chips)"
			("LOCATION" "R1517")
		)
		("@s9s_mb_2u_lib.s9s_mb_2u(sch_1):page512_i301@pure_quanta.q_res(chips)"
			("LOCATION" "R1630")
		)
		("@s9s_mb_2u_lib.s9s_mb_2u(sch_1):page512_i303@pure_quanta.q_res(chips)"
			("LOCATION" "R1631")
		)
		("@s9s_mb_2u_lib.s9s_mb_2u(sch_1):page512_i297@pure_quanta.q_res(chips)"
			("LOCATION" "R1632")
		)
		("@s9s_mb_2u_lib.s9s_mb_2u(sch_1):page512_i294@pure_quanta.q_res(chips)"
			("LOCATION" "R1633")
		)
		("@s9s_mb_2u_lib.s9s_mb_2u(sch_1):page512_i284@pure_quanta.q_res(chips)"
			("LOCATION" "R1634")
		)
		("@s9s_mb_2u_lib.s9s_mb_2u(sch_1):page512_i283@pure_quanta.q_res(chips)"
			("LOCATION" "R1635")
		)
		("@s9s_mb_2u_lib.s9s_mb_2u(sch_1):page512_i282@pure_quanta.q_res(chips)"
			("LOCATION" "R1636")
		)
		("@s9s_mb_2u_lib.s9s_mb_2u(sch_1):page512_i281@pure_quanta.q_res(chips)"
			("LOCATION" "R1637")
		)
		("@s9s_mb_2u_lib.s9s_mb_2u(sch_1):page512_i280@pure_quanta.q_res(chips)"
			("LOCATION" "R1638")
		)
		("@s9s_mb_2u_lib.s9s_mb_2u(sch_1):page512_i318@pure_quanta.q_res(chips)"
			("LOCATION" "R1852")
		)
		("@s9s_mb_2u_lib.s9s_mb_2u(sch_1):page547_i236@pure_quanta.q_cap(chips)"
			("LOCATION" "C1209")
		)
		("@s9s_mb_2u_lib.s9s_mb_2u(sch_1):page547_i240@pure_quanta.q_cap(chips)"
			("LOCATION" "C1211")
		)
		("@s9s_mb_2u_lib.s9s_mb_2u(sch_1):page547_i249@pure_quanta.q_res(chips)"
			("LOCATION" "R139")
		)
		("@s9s_mb_2u_lib.s9s_mb_2u(sch_1):page547_i254@pure_quanta.q_res(chips)"
			("LOCATION" "R140")
		)
		("@s9s_mb_2u_lib.s9s_mb_2u(sch_1):page547_i255@pure_quanta.q_res(chips)"
			("LOCATION" "R141")
		)
		("@s9s_mb_2u_lib.s9s_mb_2u(sch_1):page547_i325@pure_quanta.q_res(chips)"
			("LOCATION" "R393")
		)
		("@s9s_mb_2u_lib.s9s_mb_2u(sch_1):page547_i324@pure_quanta.q_res(chips)"
			("LOCATION" "R397")
		)
		("@s9s_mb_2u_lib.s9s_mb_2u(sch_1):page547_i311@pure_quanta.q_res(chips)"
			("LOCATION" "R546")
		)
		("@s9s_mb_2u_lib.s9s_mb_2u(sch_1):page547_i313@pure_quanta.q_res(chips)"
			("LOCATION" "R547")
		)
		("@s9s_mb_2u_lib.s9s_mb_2u(sch_1):page547_i123@pure_quanta.q_res(chips)"
			("LOCATION" "R735")
		)
		("@s9s_mb_2u_lib.s9s_mb_2u(sch_1):page547_i125@pure_quanta.q_res(chips)"
			("LOCATION" "R736")
		)
		("@s9s_mb_2u_lib.s9s_mb_2u(sch_1):page547_i265@pure_quanta.q_res(chips)"
			("LOCATION" "R921")
		)
		("@s9s_mb_2u_lib.s9s_mb_2u(sch_1):page547_i266@pure_quanta.q_res(chips)"
			("LOCATION" "R922")
		)
		("@s9s_mb_2u_lib.s9s_mb_2u(sch_1):page547_i131@pure_quanta.q_res(chips)"
			("LOCATION" "R990")
		)
		("@s9s_mb_2u_lib.s9s_mb_2u(sch_1):page547_i144@pure_quanta.q_res(chips)"
			("LOCATION" "R991")
		)
		("@s9s_mb_2u_lib.s9s_mb_2u(sch_1):page547_i141@pure_quanta.q_res(chips)"
			("LOCATION" "R992")
		)
		("@s9s_mb_2u_lib.s9s_mb_2u(sch_1):page547_i294@pure_quanta.q_res(chips)"
			("LOCATION" "R1302")
		)
		("@s9s_mb_2u_lib.s9s_mb_2u(sch_1):page547_i321@pure_quanta.q_res(chips)"
			("LOCATION" "R1304")
		)
		("@s9s_mb_2u_lib.s9s_mb_2u(sch_1):page547_i252@pure_quanta.q_res(chips)"
			("LOCATION" "R1308")
		)
		("@s9s_mb_2u_lib.s9s_mb_2u(sch_1):page547_i260@pure_quanta.q_res(chips)"
			("LOCATION" "R1312")
		)
		("@s9s_mb_2u_lib.s9s_mb_2u(sch_1):page547_i295@pure_quanta.q_res(chips)"
			("LOCATION" "R1326")
		)
		("@s9s_mb_2u_lib.s9s_mb_2u(sch_1):page547_i298@pure_quanta.q_res(chips)"
			("LOCATION" "R1327")
		)
		("@s9s_mb_2u_lib.s9s_mb_2u(sch_1):page547_i299@pure_quanta.q_res(chips)"
			("LOCATION" "R1328")
		)
		("@s9s_mb_2u_lib.s9s_mb_2u(sch_1):page547_i301@pure_quanta.q_res(chips)"
			("LOCATION" "R1329")
		)
		("@s9s_mb_2u_lib.s9s_mb_2u(sch_1):page547_i303@pure_quanta.q_res(chips)"
			("LOCATION" "R1330")
		)
		("@s9s_mb_2u_lib.s9s_mb_2u(sch_1):page547_i305@pure_quanta.q_res(chips)"
			("LOCATION" "R1388")
		)
		("@s9s_mb_2u_lib.s9s_mb_2u(sch_1):page547_i307@pure_quanta.q_res(chips)"
			("LOCATION" "R1389")
		)
		("@s9s_mb_2u_lib.s9s_mb_2u(sch_1):page547_i139@pure_quanta.q_res(chips)"
			("LOCATION" "R1398")
		)
		("@s9s_mb_2u_lib.s9s_mb_2u(sch_1):page547_i269@pure_quanta.q_res(chips)"
			("LOCATION" "R1399")
		)
		("@s9s_mb_2u_lib.s9s_mb_2u(sch_1):page547_i270@pure_quanta.q_res(chips)"
			("LOCATION" "R1400")
		)
		("@s9s_mb_2u_lib.s9s_mb_2u(sch_1):page547_i277@pure_quanta.q_res(chips)"
			("LOCATION" "R1401")
		)
		("@s9s_mb_2u_lib.s9s_mb_2u(sch_1):page547_i132@pure_quanta.q_res(chips)"
			("LOCATION" "R1402")
		)
		("@s9s_mb_2u_lib.s9s_mb_2u(sch_1):page547_i127@pure_quanta.q_res(chips)"
			("LOCATION" "R1403")
		)
		("@s9s_mb_2u_lib.s9s_mb_2u(sch_1):page547_i169@pure_quanta.q_res(chips)"
			("LOCATION" "R1404")
		)
		("@s9s_mb_2u_lib.s9s_mb_2u(sch_1):page547_i170@pure_quanta.q_res(chips)"
			("LOCATION" "R1405")
		)
		("@s9s_mb_2u_lib.s9s_mb_2u(sch_1):page547_i173@pure_quanta.q_res(chips)"
			("LOCATION" "R1406")
		)
		("@s9s_mb_2u_lib.s9s_mb_2u(sch_1):page547_i175@pure_quanta.q_res(chips)"
			("LOCATION" "R1407")
		)
		("@s9s_mb_2u_lib.s9s_mb_2u(sch_1):page547_i176@pure_quanta.q_res(chips)"
			("LOCATION" "R1408")
		)
		("@s9s_mb_2u_lib.s9s_mb_2u(sch_1):page547_i179@pure_quanta.q_res(chips)"
			("LOCATION" "R1409")
		)
		("@s9s_mb_2u_lib.s9s_mb_2u(sch_1):page547_i180@pure_quanta.q_res(chips)"
			("LOCATION" "R1410")
		)
		("@s9s_mb_2u_lib.s9s_mb_2u(sch_1):page547_i184@pure_quanta.q_res(chips)"
			("LOCATION" "R1411")
		)
		("@s9s_mb_2u_lib.s9s_mb_2u(sch_1):page547_i183@pure_quanta.q_res(chips)"
			("LOCATION" "R1412")
		)
		("@s9s_mb_2u_lib.s9s_mb_2u(sch_1):page547_i188@pure_quanta.q_res(chips)"
			("LOCATION" "R1413")
		)
		("@s9s_mb_2u_lib.s9s_mb_2u(sch_1):page547_i186@pure_quanta.q_res(chips)"
			("LOCATION" "R1414")
		)
		("@s9s_mb_2u_lib.s9s_mb_2u(sch_1):page547_i148@pure_quanta.q_res(chips)"
			("LOCATION" "R1415")
		)
		("@s9s_mb_2u_lib.s9s_mb_2u(sch_1):page547_i149@pure_quanta.q_res(chips)"
			("LOCATION" "R1416")
		)
		("@s9s_mb_2u_lib.s9s_mb_2u(sch_1):page547_i150@pure_quanta.q_res(chips)"
			("LOCATION" "R1417")
		)
		("@s9s_mb_2u_lib.s9s_mb_2u(sch_1):page547_i151@pure_quanta.q_res(chips)"
			("LOCATION" "R1418")
		)
		("@s9s_mb_2u_lib.s9s_mb_2u(sch_1):page547_i153@pure_quanta.q_res(chips)"
			("LOCATION" "R1419")
		)
		("@s9s_mb_2u_lib.s9s_mb_2u(sch_1):page547_i152@pure_quanta.q_res(chips)"
			("LOCATION" "R1420")
		)
		("@s9s_mb_2u_lib.s9s_mb_2u(sch_1):page547_i155@pure_quanta.q_res(chips)"
			("LOCATION" "R1421")
		)
		("@s9s_mb_2u_lib.s9s_mb_2u(sch_1):page547_i197@pure_quanta.q_res(chips)"
			("LOCATION" "R1425")
		)
		("@s9s_mb_2u_lib.s9s_mb_2u(sch_1):page547_i198@pure_quanta.q_res(chips)"
			("LOCATION" "R1426")
		)
		("@s9s_mb_2u_lib.s9s_mb_2u(sch_1):page547_i199@pure_quanta.q_res(chips)"
			("LOCATION" "R1427")
		)
		("@s9s_mb_2u_lib.s9s_mb_2u(sch_1):page547_i202@pure_quanta.q_res(chips)"
			("LOCATION" "R1428")
		)
		("@s9s_mb_2u_lib.s9s_mb_2u(sch_1):page547_i205@pure_quanta.q_res(chips)"
			("LOCATION" "R1429")
		)
		("@s9s_mb_2u_lib.s9s_mb_2u(sch_1):page547_i203@pure_quanta.q_res(chips)"
			("LOCATION" "R1430")
		)
		("@s9s_mb_2u_lib.s9s_mb_2u(sch_1):page547_i213@pure_quanta.q_res(chips)"
			("LOCATION" "R1431")
		)
		("@s9s_mb_2u_lib.s9s_mb_2u(sch_1):page547_i214@pure_quanta.q_res(chips)"
			("LOCATION" "R1432")
		)
		("@s9s_mb_2u_lib.s9s_mb_2u(sch_1):page547_i215@pure_quanta.q_res(chips)"
			("LOCATION" "R1433")
		)
		("@s9s_mb_2u_lib.s9s_mb_2u(sch_1):page547_i216@pure_quanta.q_res(chips)"
			("LOCATION" "R1434")
		)
		("@s9s_mb_2u_lib.s9s_mb_2u(sch_1):page547_i221@pure_quanta.q_res(chips)"
			("LOCATION" "R1435")
		)
		("@s9s_mb_2u_lib.s9s_mb_2u(sch_1):page547_i278@pure_quanta.q_res(chips)"
			("LOCATION" "R1436")
		)
		("@s9s_mb_2u_lib.s9s_mb_2u(sch_1):page547_i224@pure_quanta.q_res(chips)"
			("LOCATION" "R1437")
		)
		("@s9s_mb_2u_lib.s9s_mb_2u(sch_1):page547_i226@pure_quanta.q_res(chips)"
			("LOCATION" "R1438")
		)
		("@s9s_mb_2u_lib.s9s_mb_2u(sch_1):page547_i229@pure_quanta.q_res(chips)"
			("LOCATION" "R1439")
		)
		("@s9s_mb_2u_lib.s9s_mb_2u(sch_1):page547_i231@pure_quanta.q_res(chips)"
			("LOCATION" "R1440")
		)
		("@s9s_mb_2u_lib.s9s_mb_2u(sch_1):page547_i235@pure_quanta.q_res(chips)"
			("LOCATION" "R1441")
		)
		("@s9s_mb_2u_lib.s9s_mb_2u(sch_1):page547_i261@pure_quanta.q_res(chips)"
			("LOCATION" "R1473")
		)
		("@s9s_mb_2u_lib.s9s_mb_2u(sch_1):page547_i262@pure_quanta.q_res(chips)"
			("LOCATION" "R1474")
		)
		("@s9s_mb_2u_lib.s9s_mb_2u(sch_1):page547_i279@pure_quanta.q_res(chips)"
			("LOCATION" "R1488")
		)
		("@s9s_mb_2u_lib.s9s_mb_2u(sch_1):page547_i290@pure_quanta.q_res(chips)"
			("LOCATION" "R1489")
		)
		("@s9s_mb_2u_lib.s9s_mb_2u(sch_1):page547_i291@pure_quanta.q_res(chips)"
			("LOCATION" "R1490")
		)
		("@s9s_mb_2u_lib.s9s_mb_2u(sch_1):page547_i282@pure_quanta.q_res(chips)"
			("LOCATION" "R1491")
		)
		("@s9s_mb_2u_lib.s9s_mb_2u(sch_1):page547_i272@pure_quanta.q_res(chips)"
			("LOCATION" "R1492")
		)
		("@s9s_mb_2u_lib.s9s_mb_2u(sch_1):page547_i287@pure_quanta.q_res(chips)"
			("LOCATION" "R1493")
		)
		("@s9s_mb_2u_lib.s9s_mb_2u(sch_1):page547_i275@pure_quanta.q_res(chips)"
			("LOCATION" "R1494")
		)
		("@s9s_mb_2u_lib.s9s_mb_2u(sch_1):page547_i286@pure_quanta.q_res(chips)"
			("LOCATION" "R1495")
		)
		("@s9s_mb_2u_lib.s9s_mb_2u(sch_1):page547_i317@pure_quanta.q_res(chips)"
			("LOCATION" "R1552")
		)
		("@s9s_mb_2u_lib.s9s_mb_2u(sch_1):page547_i316@pure_quanta.q_res(chips)"
			("LOCATION" "R1557")
		)
		("@s9s_mb_2u_lib.s9s_mb_2u(sch_1):page547_i318@pure_quanta.q_res(chips)"
			("LOCATION" "R1558")
		)
		("@s9s_mb_2u_lib.s9s_mb_2u(sch_1):page547_i322@pure_quanta.q_res(chips)"
			("LOCATION" "R1639")
		)
		("@s9s_mb_2u_lib.s9s_mb_2u(sch_1):page547_i328@pure_quanta.q_res(chips)"
			("LOCATION" "R1660")
		)
		("@s9s_mb_2u_lib.s9s_mb_2u(sch_1):page547_i330@pure_quanta.q_res(chips)"
			("LOCATION" "R1741")
		)
		("@s9s_mb_2u_lib.s9s_mb_2u(sch_1):page547_i329@pure_quanta.q_res(chips)"
			("LOCATION" "R1742")
		)
		("@s9s_mb_2u_lib.s9s_mb_2u(sch_1):page500_i316@pure_quanta.q_cap(chips)"
			("LOCATION" "C1213")
		)
		("@s9s_mb_2u_lib.s9s_mb_2u(sch_1):page500_i331@pure_quanta.q_cap(chips)"
			("LOCATION" "C1232")
		)
		("@s9s_mb_2u_lib.s9s_mb_2u(sch_1):page500_i319@pure_quanta.q_cap(chips)"
			("LOCATION" "C1233")
		)
		("@s9s_mb_2u_lib.s9s_mb_2u(sch_1):page500_i332@pure_quanta.q_cap(chips)"
			("LOCATION" "C1234")
		)
		("@s9s_mb_2u_lib.s9s_mb_2u(sch_1):page500_i333@pure_quanta.q_cap(chips)"
			("LOCATION" "C1235")
		)
		("@s9s_mb_2u_lib.s9s_mb_2u(sch_1):page500_i322@pure_quanta.q_cap(chips)"
			("LOCATION" "C1236")
		)
		("@s9s_mb_2u_lib.s9s_mb_2u(sch_1):page500_i334@pure_quanta.q_cap(chips)"
			("LOCATION" "C1237")
		)
		("@s9s_mb_2u_lib.s9s_mb_2u(sch_1):page500_i338@pure_quanta.q_cap(chips)"
			("LOCATION" "C1238")
		)
		("@s9s_mb_2u_lib.s9s_mb_2u(sch_1):page500_i337@pure_quanta.q_cap(chips)"
			("LOCATION" "C1239")
		)
		("@s9s_mb_2u_lib.s9s_mb_2u(sch_1):page500_i335@pure_quanta.q_cap(chips)"
			("LOCATION" "C1240")
		)
		("@s9s_mb_2u_lib.s9s_mb_2u(sch_1):page500_i86@pure_quanta.sconn168_623403212(chips)"
			("LOCATION" "J37")
		)
		("@s9s_mb_2u_lib.s9s_mb_2u(sch_1):page500_i147@pure_quanta.q_res(chips)"
			("LOCATION" "R409")
		)
		("@s9s_mb_2u_lib.s9s_mb_2u(sch_1):page500_i148@pure_quanta.q_res(chips)"
			("LOCATION" "R410")
		)
		("@s9s_mb_2u_lib.s9s_mb_2u(sch_1):page500_i362@pure_quanta.q_res(chips)"
			("LOCATION" "R413")
		)
		("@s9s_mb_2u_lib.s9s_mb_2u(sch_1):page500_i144@pure_quanta.q_res(chips)"
			("LOCATION" "R414")
		)
		("@s9s_mb_2u_lib.s9s_mb_2u(sch_1):page500_i145@pure_quanta.q_res(chips)"
			("LOCATION" "R415")
		)
		("@s9s_mb_2u_lib.s9s_mb_2u(sch_1):page500_i253@pure_quanta.q_res(chips)"
			("LOCATION" "R416")
		)
		("@s9s_mb_2u_lib.s9s_mb_2u(sch_1):page500_i255@pure_quanta.q_res(chips)"
			("LOCATION" "R417")
		)
		("@s9s_mb_2u_lib.s9s_mb_2u(sch_1):page500_i258@pure_quanta.q_res(chips)"
			("LOCATION" "R418")
		)
		("@s9s_mb_2u_lib.s9s_mb_2u(sch_1):page500_i10@pure_quanta.q_res(chips)"
			("LOCATION" "R420")
		)
		("@s9s_mb_2u_lib.s9s_mb_2u(sch_1):page500_i11@pure_quanta.q_res(chips)"
			("LOCATION" "R421")
		)
		("@s9s_mb_2u_lib.s9s_mb_2u(sch_1):page500_i12@pure_quanta.q_res(chips)"
			("LOCATION" "R422")
		)
		("@s9s_mb_2u_lib.s9s_mb_2u(sch_1):page500_i13@pure_quanta.q_res(chips)"
			("LOCATION" "R423")
		)
		("@s9s_mb_2u_lib.s9s_mb_2u(sch_1):page500_i173@pure_quanta.q_res(chips)"
			("LOCATION" "R424")
		)
		("@s9s_mb_2u_lib.s9s_mb_2u(sch_1):page500_i174@pure_quanta.q_res(chips)"
			("LOCATION" "R425")
		)
		("@s9s_mb_2u_lib.s9s_mb_2u(sch_1):page500_i344@pure_quanta.q_res(chips)"
			("LOCATION" "R429")
		)
		("@s9s_mb_2u_lib.s9s_mb_2u(sch_1):page500_i350@pure_quanta.q_res(chips)"
			("LOCATION" "R444")
		)
		("@s9s_mb_2u_lib.s9s_mb_2u(sch_1):page500_i349@pure_quanta.q_res(chips)"
			("LOCATION" "R445")
		)
		("@s9s_mb_2u_lib.s9s_mb_2u(sch_1):page500_i314@pure_quanta.q_res(chips)"
			("LOCATION" "R454")
		)
		("@s9s_mb_2u_lib.s9s_mb_2u(sch_1):page500_i340@pure_quanta.q_res(chips)"
			("LOCATION" "R1671")
		)
		("@s9s_mb_2u_lib.s9s_mb_2u(sch_1):page500_i353@pure_quanta.q_res(chips)"
			("LOCATION" "R1895")
		)
		("@s9s_mb_2u_lib.s9s_mb_2u(sch_1):page500_i360@pure_quanta.q_res(chips)"
			("LOCATION" "R1929")
		)
		("@s9s_mb_2u_lib.s9s_mb_2u(sch_1):page500_i359@pure_quanta.q_res(chips)"
			("LOCATION" "R1930")
		)
		("@s9s_mb_2u_lib.s9s_mb_2u(sch_1):page519_i168@pure_quanta.q_cap(chips)"
			("LOCATION" "C1229")
		)
		("@s9s_mb_2u_lib.s9s_mb_2u(sch_1):page519_i163@pure_quanta.q_cap(chips)"
			("LOCATION" "C1230")
		)
		("@s9s_mb_2u_lib.s9s_mb_2u(sch_1):page519_i206@pure_quanta.q_cap(chips)"
			("LOCATION" "C1408")
		)
		("@s9s_mb_2u_lib.s9s_mb_2u(sch_1):page519_i213@pure_quanta.q_res(chips)"
			("LOCATION" "R474")
		)
		("@s9s_mb_2u_lib.s9s_mb_2u(sch_1):page519_i226@pure_quanta.q_res(chips)"
			("LOCATION" "R631")
		)
		("@s9s_mb_2u_lib.s9s_mb_2u(sch_1):page519_i214@pure_quanta.q_res(chips)"
			("LOCATION" "R632")
		)
		("@s9s_mb_2u_lib.s9s_mb_2u(sch_1):page519_i215@pure_quanta.q_res(chips)"
			("LOCATION" "R633")
		)
		("@s9s_mb_2u_lib.s9s_mb_2u(sch_1):page519_i233@pure_quanta.q_res(chips)"
			("LOCATION" "R634")
		)
		("@s9s_mb_2u_lib.s9s_mb_2u(sch_1):page519_i234@pure_quanta.q_res(chips)"
			("LOCATION" "R635")
		)
		("@s9s_mb_2u_lib.s9s_mb_2u(sch_1):page519_i102@pure_quanta.q_res(chips)"
			("LOCATION" "R699")
		)
		("@s9s_mb_2u_lib.s9s_mb_2u(sch_1):page519_i236@pure_quanta.q_res(chips)"
			("LOCATION" "R727")
		)
		("@s9s_mb_2u_lib.s9s_mb_2u(sch_1):page519_i239@pure_quanta.q_res(chips)"
			("LOCATION" "R770")
		)
		("@s9s_mb_2u_lib.s9s_mb_2u(sch_1):page519_i241@pure_quanta.q_res(chips)"
			("LOCATION" "R913")
		)
		("@s9s_mb_2u_lib.s9s_mb_2u(sch_1):page519_i222@pure_quanta.q_res(chips)"
			("LOCATION" "R1268")
		)
		("@s9s_mb_2u_lib.s9s_mb_2u(sch_1):page519_i225@pure_quanta.q_res(chips)"
			("LOCATION" "R1269")
		)
		("@s9s_mb_2u_lib.s9s_mb_2u(sch_1):page519_i109@pure_quanta.q_res(chips)"
			("LOCATION" "R1451")
		)
		("@s9s_mb_2u_lib.s9s_mb_2u(sch_1):page519_i112@pure_quanta.q_res(chips)"
			("LOCATION" "R1452")
		)
		("@s9s_mb_2u_lib.s9s_mb_2u(sch_1):page519_i120@pure_quanta.q_res(chips)"
			("LOCATION" "R1453")
		)
		("@s9s_mb_2u_lib.s9s_mb_2u(sch_1):page519_i121@pure_quanta.q_res(chips)"
			("LOCATION" "R1454")
		)
		("@s9s_mb_2u_lib.s9s_mb_2u(sch_1):page519_i125@pure_quanta.q_res(chips)"
			("LOCATION" "R1487")
		)
		("@s9s_mb_2u_lib.s9s_mb_2u(sch_1):page519_i137@pure_quanta.q_res(chips)"
			("LOCATION" "R1545")
		)
		("@s9s_mb_2u_lib.s9s_mb_2u(sch_1):page519_i138@pure_quanta.q_res(chips)"
			("LOCATION" "R1546")
		)
		("@s9s_mb_2u_lib.s9s_mb_2u(sch_1):page519_i142@pure_quanta.q_res(chips)"
			("LOCATION" "R1581")
		)
		("@s9s_mb_2u_lib.s9s_mb_2u(sch_1):page519_i141@pure_quanta.q_res(chips)"
			("LOCATION" "R1582")
		)
		("@s9s_mb_2u_lib.s9s_mb_2u(sch_1):page519_i144@pure_quanta.q_res(chips)"
			("LOCATION" "R1583")
		)
		("@s9s_mb_2u_lib.s9s_mb_2u(sch_1):page519_i148@pure_quanta.q_res(chips)"
			("LOCATION" "R1600")
		)
		("@s9s_mb_2u_lib.s9s_mb_2u(sch_1):page519_i151@pure_quanta.q_res(chips)"
			("LOCATION" "R1601")
		)
		("@s9s_mb_2u_lib.s9s_mb_2u(sch_1):page519_i178@pure_quanta.q_res(chips)"
			("LOCATION" "R1656")
		)
		("@s9s_mb_2u_lib.s9s_mb_2u(sch_1):page519_i180@pure_quanta.q_res(chips)"
			("LOCATION" "R1657")
		)
		("@s9s_mb_2u_lib.s9s_mb_2u(sch_1):page519_i174@pure_quanta.q_res(chips)"
			("LOCATION" "R1658")
		)
		("@s9s_mb_2u_lib.s9s_mb_2u(sch_1):page519_i181@pure_quanta.q_res(chips)"
			("LOCATION" "R1659")
		)
		("@s9s_mb_2u_lib.s9s_mb_2u(sch_1):page519_i184@pure_quanta.q_res(chips)"
			("LOCATION" "R1696")
		)
		("@s9s_mb_2u_lib.s9s_mb_2u(sch_1):page519_i186@pure_quanta.q_res(chips)"
			("LOCATION" "R1697")
		)
		("@s9s_mb_2u_lib.s9s_mb_2u(sch_1):page519_i243@pure_quanta.q_res(chips)"
			("LOCATION" "R1777")
		)
		("@s9s_mb_2u_lib.s9s_mb_2u(sch_1):page519_i244@pure_quanta.q_res(chips)"
			("LOCATION" "R1778")
		)
		("@s9s_mb_2u_lib.s9s_mb_2u(sch_1):page519_i193@pure_quanta.q_res(chips)"
			("LOCATION" "R1827")
		)
		("@s9s_mb_2u_lib.s9s_mb_2u(sch_1):page519_i188@pure_quanta.q_res(chips)"
			("LOCATION" "R1828")
		)
		("@s9s_mb_2u_lib.s9s_mb_2u(sch_1):page519_i93@pure_quanta.emmitsburg_rev0p9(chips)"
			("LOCATION" "U4")
		)
		("@s9s_mb_2u_lib.s9s_mb_2u(sch_1):page519_i165@pure_quanta.\\74lvc1g07gv\\(chips)"
			("LOCATION" "U54")
		)
		("@s9s_mb_2u_lib.s9s_mb_2u(sch_1):page519_i158@pure_quanta.\\74lvc1g07gv\\(chips)"
			("LOCATION" "U55")
		)
		("@s9s_mb_2u_lib.s9s_mb_2u(sch_1):page519_i205@pure_quanta.sn74lvc1g17dckr(chips)"
			("LOCATION" "U101")
		)
		("@s9s_mb_2u_lib.s9s_mb_2u(sch_1):page503_i166@pure_quanta.q_cap(chips)"
			("LOCATION" "C1276")
		)
		("@s9s_mb_2u_lib.s9s_mb_2u(sch_1):page503_i167@pure_quanta.q_cap(chips)"
			("LOCATION" "C1277")
		)
		("@s9s_mb_2u_lib.s9s_mb_2u(sch_1):page503_i168@pure_quanta.q_cap(chips)"
			("LOCATION" "C1278")
		)
		("@s9s_mb_2u_lib.s9s_mb_2u(sch_1):page503_i170@pure_quanta.q_cap(chips)"
			("LOCATION" "C1279")
		)
		("@s9s_mb_2u_lib.s9s_mb_2u(sch_1):page503_i171@pure_quanta.q_cap(chips)"
			("LOCATION" "C1280")
		)
		("@s9s_mb_2u_lib.s9s_mb_2u(sch_1):page503_i173@pure_quanta.q_cap(chips)"
			("LOCATION" "C1281")
		)
		("@s9s_mb_2u_lib.s9s_mb_2u(sch_1):page503_i174@pure_quanta.q_cap(chips)"
			("LOCATION" "C1282")
		)
		("@s9s_mb_2u_lib.s9s_mb_2u(sch_1):page503_i175@pure_quanta.q_cap(chips)"
			("LOCATION" "C1283")
		)
		("@s9s_mb_2u_lib.s9s_mb_2u(sch_1):page503_i176@pure_quanta.q_cap(chips)"
			("LOCATION" "C1284")
		)
		("@s9s_mb_2u_lib.s9s_mb_2u(sch_1):page503_i179@pure_quanta.q_cap(chips)"
			("LOCATION" "C1285")
		)
		("@s9s_mb_2u_lib.s9s_mb_2u(sch_1):page503_i107@pure_quanta.sconn168_623403212(chips)"
			("LOCATION" "J38")
		)
		("@s9s_mb_2u_lib.s9s_mb_2u(sch_1):page503_i154@pure_quanta.q_res(chips)"
			("LOCATION" "R405")
		)
		("@s9s_mb_2u_lib.s9s_mb_2u(sch_1):page503_i189@pure_quanta.q_res(chips)"
			("LOCATION" "R426")
		)
		("@s9s_mb_2u_lib.s9s_mb_2u(sch_1):page503_i190@pure_quanta.q_res(chips)"
			("LOCATION" "R427")
		)
		("@s9s_mb_2u_lib.s9s_mb_2u(sch_1):page503_i186@pure_quanta.q_res(chips)"
			("LOCATION" "R430")
		)
		("@s9s_mb_2u_lib.s9s_mb_2u(sch_1):page503_i187@pure_quanta.q_res(chips)"
			("LOCATION" "R431")
		)
		("@s9s_mb_2u_lib.s9s_mb_2u(sch_1):page503_i204@pure_quanta.q_res(chips)"
			("LOCATION" "R436")
		)
		("@s9s_mb_2u_lib.s9s_mb_2u(sch_1):page503_i159@pure_quanta.q_res(chips)"
			("LOCATION" "R437")
		)
		("@s9s_mb_2u_lib.s9s_mb_2u(sch_1):page503_i205@pure_quanta.q_res(chips)"
			("LOCATION" "R438")
		)
		("@s9s_mb_2u_lib.s9s_mb_2u(sch_1):page503_i161@pure_quanta.q_res(chips)"
			("LOCATION" "R439")
		)
		("@s9s_mb_2u_lib.s9s_mb_2u(sch_1):page503_i207@pure_quanta.q_res(chips)"
			("LOCATION" "R446")
		)
		("@s9s_mb_2u_lib.s9s_mb_2u(sch_1):page503_i94@pure_quanta.q_res(chips)"
			("LOCATION" "R449")
		)
		("@s9s_mb_2u_lib.s9s_mb_2u(sch_1):page503_i93@pure_quanta.q_res(chips)"
			("LOCATION" "R450")
		)
		("@s9s_mb_2u_lib.s9s_mb_2u(sch_1):page503_i96@pure_quanta.q_res(chips)"
			("LOCATION" "R451")
		)
		("@s9s_mb_2u_lib.s9s_mb_2u(sch_1):page503_i95@pure_quanta.q_res(chips)"
			("LOCATION" "R452")
		)
		("@s9s_mb_2u_lib.s9s_mb_2u(sch_1):page503_i23@pure_quanta.q_res(chips)"
			("LOCATION" "R457")
		)
		("@s9s_mb_2u_lib.s9s_mb_2u(sch_1):page503_i24@pure_quanta.q_res(chips)"
			("LOCATION" "R458")
		)
		("@s9s_mb_2u_lib.s9s_mb_2u(sch_1):page503_i194@pure_quanta.q_res(chips)"
			("LOCATION" "R925")
		)
		("@s9s_mb_2u_lib.s9s_mb_2u(sch_1):page503_i200@pure_quanta.q_res(chips)"
			("LOCATION" "R926")
		)
		("@s9s_mb_2u_lib.s9s_mb_2u(sch_1):page503_i203@pure_quanta.q_res(chips)"
			("LOCATION" "R1102")
		)
		("@s9s_mb_2u_lib.s9s_mb_2u(sch_1):page503_i180@pure_quanta.q_res(chips)"
			("LOCATION" "R1672")
		)
		("@s9s_mb_2u_lib.s9s_mb_2u(sch_1):page503_i183@pure_quanta.q_res(chips)"
			("LOCATION" "R1673")
		)
		("@s9s_mb_2u_lib.s9s_mb_2u(sch_1):page578_i53@pure_quanta.q_cap(chips)"
			("LOCATION" "C1286")
		)
		("@s9s_mb_2u_lib.s9s_mb_2u(sch_1):page578_i37@pure_quanta.q_cap(chips)"
			("LOCATION" "PC113")
		)
		("@s9s_mb_2u_lib.s9s_mb_2u(sch_1):page578_i15@pure_quanta.q_capp(chips)"
			("LOCATION" "PC117")
		)
		("@s9s_mb_2u_lib.s9s_mb_2u(sch_1):page578_i43@pure_quanta.q_capp(chips)"
			("LOCATION" "PC1215")
		)
		("@s9s_mb_2u_lib.s9s_mb_2u(sch_1):page578_i39@pure_quanta.q_cap(chips)"
			("LOCATION" "PC1216")
		)
		("@s9s_mb_2u_lib.s9s_mb_2u(sch_1):page578_i29@pure_quanta.q_cap(chips)"
			("LOCATION" "PC1217")
		)
		("@s9s_mb_2u_lib.s9s_mb_2u(sch_1):page578_i26@pure_quanta.q_cap(chips)"
			("LOCATION" "PC1218")
		)
		("@s9s_mb_2u_lib.s9s_mb_2u(sch_1):page578_i25@pure_quanta.q_cap(chips)"
			("LOCATION" "PC1219")
		)
		("@s9s_mb_2u_lib.s9s_mb_2u(sch_1):page578_i30@pure_quanta.q_cap(chips)"
			("LOCATION" "PC1221")
		)
		("@s9s_mb_2u_lib.s9s_mb_2u(sch_1):page578_i23@pure_quanta.q_cap(chips)"
			("LOCATION" "PC1222")
		)
		("@s9s_mb_2u_lib.s9s_mb_2u(sch_1):page578_i18@pure_quanta.q_cap(chips)"
			("LOCATION" "PC1223")
		)
		("@s9s_mb_2u_lib.s9s_mb_2u(sch_1):page578_i16@pure_quanta.q_cap(chips)"
			("LOCATION" "PC1224")
		)
		("@s9s_mb_2u_lib.s9s_mb_2u(sch_1):page578_i12@pure_quanta.q_cap(chips)"
			("LOCATION" "PC1225")
		)
		("@s9s_mb_2u_lib.s9s_mb_2u(sch_1):page578_i11@pure_quanta.q_cap(chips)"
			("LOCATION" "PC1226")
		)
		("@s9s_mb_2u_lib.s9s_mb_2u(sch_1):page578_i14@pure_quanta.q_capp(chips)"
			("LOCATION" "PC1227")
		)
		("@s9s_mb_2u_lib.s9s_mb_2u(sch_1):page578_i6@pure_quanta.q_capp(chips)"
			("LOCATION" "PC1229")
		)
		("@s9s_mb_2u_lib.s9s_mb_2u(sch_1):page578_i8@pure_quanta.q_capp(chips)"
			("LOCATION" "PC1230")
		)
		("@s9s_mb_2u_lib.s9s_mb_2u(sch_1):page578_i13@pure_quanta.q_short(chips)"
			("LOCATION" "PJ62")
		)
		("@s9s_mb_2u_lib.s9s_mb_2u(sch_1):page578_i40@pure_quanta.q_inductor(chips)"
			("LOCATION" "PL110")
		)
		("@s9s_mb_2u_lib.s9s_mb_2u(sch_1):page578_i5@pure_quanta.q_inductor(chips)"
			("LOCATION" "PL150")
		)
		("@s9s_mb_2u_lib.s9s_mb_2u(sch_1):page578_i22@pure_quanta.q_res(chips)"
			("LOCATION" "PR186")
		)
		("@s9s_mb_2u_lib.s9s_mb_2u(sch_1):page578_i19@pure_quanta.q_res(chips)"
			("LOCATION" "PR187")
		)
		("@s9s_mb_2u_lib.s9s_mb_2u(sch_1):page578_i36@pure_quanta.q_res(chips)"
			("LOCATION" "PR1326")
		)
		("@s9s_mb_2u_lib.s9s_mb_2u(sch_1):page578_i33@pure_quanta.q_res(chips)"
			("LOCATION" "PR1327")
		)
		("@s9s_mb_2u_lib.s9s_mb_2u(sch_1):page578_i17@pure_quanta.q_res(chips)"
			("LOCATION" "PR1328")
		)
		("@s9s_mb_2u_lib.s9s_mb_2u(sch_1):page578_i27@pure_quanta.q_res(chips)"
			("LOCATION" "PR1388")
		)
		("@s9s_mb_2u_lib.s9s_mb_2u(sch_1):page578_i28@pure_quanta.q_res(chips)"
			("LOCATION" "PR1389")
		)
		("@s9s_mb_2u_lib.s9s_mb_2u(sch_1):page578_i50@pure_quanta.q_res(chips)"
			("LOCATION" "PR1647")
		)
		("@s9s_mb_2u_lib.s9s_mb_2u(sch_1):page578_i49@pure_quanta.q_res(chips)"
			("LOCATION" "PR1650")
		)
		("@s9s_mb_2u_lib.s9s_mb_2u(sch_1):page578_i4@pure_quanta.q_res(chips)"
			("LOCATION" "PR2390")
		)
		("@s9s_mb_2u_lib.s9s_mb_2u(sch_1):page578_i32@pure_quanta.mpq8633bglec838z(chips)"
			("LOCATION" "PU73")
		)
		("@s9s_mb_2u_lib.s9s_mb_2u(sch_1):page578_i52@pure_quanta.q_res(chips)"
			("LOCATION" "R1649")
		)
		("@s9s_mb_2u_lib.s9s_mb_2u(sch_1):page492_i112@pure_quanta.q_cap(chips)"
			("LOCATION" "C1288")
		)
		("@s9s_mb_2u_lib.s9s_mb_2u(sch_1):page492_i110@pure_quanta.q_cap(chips)"
			("LOCATION" "C1289")
		)
		("@s9s_mb_2u_lib.s9s_mb_2u(sch_1):page492_i90@pure_quanta.q_cap(chips)"
			("LOCATION" "C1292")
		)
		("@s9s_mb_2u_lib.s9s_mb_2u(sch_1):page492_i95@pure_quanta.q_cap(chips)"
			("LOCATION" "C1293")
		)
		("@s9s_mb_2u_lib.s9s_mb_2u(sch_1):page492_i108@pure_quanta.conn3_210hp1030br1(chips)"
			("LOCATION" "JP6")
		)
		("@s9s_mb_2u_lib.s9s_mb_2u(sch_1):page492_i88@pure_quanta.q_res(chips)"
			("LOCATION" "R1348")
		)
		("@s9s_mb_2u_lib.s9s_mb_2u(sch_1):page492_i87@pure_quanta.q_res(chips)"
			("LOCATION" "R1349")
		)
		("@s9s_mb_2u_lib.s9s_mb_2u(sch_1):page492_i116@pure_quanta.q_res(chips)"
			("LOCATION" "R1365")
		)
		("@s9s_mb_2u_lib.s9s_mb_2u(sch_1):page492_i98@pure_quanta.q_res(chips)"
			("LOCATION" "R1370")
		)
		("@s9s_mb_2u_lib.s9s_mb_2u(sch_1):page492_i106@pure_quanta.q_res(chips)"
			("LOCATION" "R1371")
		)
		("@s9s_mb_2u_lib.s9s_mb_2u(sch_1):page492_i102@pure_quanta.q_res(chips)"
			("LOCATION" "R1372")
		)
		("@s9s_mb_2u_lib.s9s_mb_2u(sch_1):page492_i105@pure_quanta.q_res(chips)"
			("LOCATION" "R1373")
		)
		("@s9s_mb_2u_lib.s9s_mb_2u(sch_1):page492_i103@pure_quanta.q_res(chips)"
			("LOCATION" "R1374")
		)
		("@s9s_mb_2u_lib.s9s_mb_2u(sch_1):page492_i97@pure_quanta.q_res(chips)"
			("LOCATION" "R1375")
		)
		("@s9s_mb_2u_lib.s9s_mb_2u(sch_1):page492_i109@pure_quanta.nc7sb3157(chips)"
			("LOCATION" "U85")
		)
		("@s9s_mb_2u_lib.s9s_mb_2u(sch_1):page492_i84@pure_quanta.\\74cbtlv3126pw\\(chips)"
			("LOCATION" "U86")
		)
		("@s9s_mb_2u_lib.s9s_mb_2u(sch_1):page492_i96@pure_quanta.mosfet_n(chips)"
			("LOCATION" "U87")
		)
		("@s9s_mb_2u_lib.s9s_mb_2u(sch_1):page561_i43@pure_quanta.q_cap(chips)"
			("LOCATION" "C1290")
		)
		("@s9s_mb_2u_lib.s9s_mb_2u(sch_1):page561_i16@pure_quanta.q_cap(chips)"
			("LOCATION" "C1291")
		)
		("@s9s_mb_2u_lib.s9s_mb_2u(sch_1):page561_i55@pure_quanta.q_cap(chips)"
			("LOCATION" "C1321")
		)
		("@s9s_mb_2u_lib.s9s_mb_2u(sch_1):page561_i27@pure_quanta.q_cap(chips)"
			("LOCATION" "C1322")
		)
		("@s9s_mb_2u_lib.s9s_mb_2u(sch_1):page561_i59@pure_quanta.q_res(chips)"
			("LOCATION" "R480")
		)
		("@s9s_mb_2u_lib.s9s_mb_2u(sch_1):page561_i58@pure_quanta.q_res(chips)"
			("LOCATION" "R481")
		)
		("@s9s_mb_2u_lib.s9s_mb_2u(sch_1):page561_i57@pure_quanta.q_res(chips)"
			("LOCATION" "R482")
		)
		("@s9s_mb_2u_lib.s9s_mb_2u(sch_1):page561_i37@pure_quanta.q_res(chips)"
			("LOCATION" "R483")
		)
		("@s9s_mb_2u_lib.s9s_mb_2u(sch_1):page561_i14@pure_quanta.q_res(chips)"
			("LOCATION" "R1184")
		)
		("@s9s_mb_2u_lib.s9s_mb_2u(sch_1):page561_i13@pure_quanta.q_res(chips)"
			("LOCATION" "R1345")
		)
		("@s9s_mb_2u_lib.s9s_mb_2u(sch_1):page561_i34@pure_quanta.q_res(chips)"
			("LOCATION" "R1346")
		)
		("@s9s_mb_2u_lib.s9s_mb_2u(sch_1):page561_i10@pure_quanta.q_res(chips)"
			("LOCATION" "R1347")
		)
		("@s9s_mb_2u_lib.s9s_mb_2u(sch_1):page561_i64@pure_quanta.q_res(chips)"
			("LOCATION" "R1366")
		)
		("@s9s_mb_2u_lib.s9s_mb_2u(sch_1):page561_i65@pure_quanta.q_res(chips)"
			("LOCATION" "R1367")
		)
		("@s9s_mb_2u_lib.s9s_mb_2u(sch_1):page561_i48@pure_quanta.q_res(chips)"
			("LOCATION" "R1368")
		)
		("@s9s_mb_2u_lib.s9s_mb_2u(sch_1):page561_i47@pure_quanta.q_res(chips)"
			("LOCATION" "R1369")
		)
		("@s9s_mb_2u_lib.s9s_mb_2u(sch_1):page561_i35@pure_quanta.q_res(chips)"
			("LOCATION" "R1376")
		)
		("@s9s_mb_2u_lib.s9s_mb_2u(sch_1):page561_i11@pure_quanta.q_res(chips)"
			("LOCATION" "R1377")
		)
		("@s9s_mb_2u_lib.s9s_mb_2u(sch_1):page561_i36@pure_quanta.q_res(chips)"
			("LOCATION" "R1378")
		)
		("@s9s_mb_2u_lib.s9s_mb_2u(sch_1):page561_i12@pure_quanta.q_res(chips)"
			("LOCATION" "R1379")
		)
		("@s9s_mb_2u_lib.s9s_mb_2u(sch_1):page561_i31@pure_quanta.q_res(chips)"
			("LOCATION" "R1380")
		)
		("@s9s_mb_2u_lib.s9s_mb_2u(sch_1):page561_i7@pure_quanta.q_res(chips)"
			("LOCATION" "R1381")
		)
		("@s9s_mb_2u_lib.s9s_mb_2u(sch_1):page561_i20@pure_quanta.q_res(chips)"
			("LOCATION" "R1382")
		)
		("@s9s_mb_2u_lib.s9s_mb_2u(sch_1):page561_i1@pure_quanta.q_res(chips)"
			("LOCATION" "R1383")
		)
		("@s9s_mb_2u_lib.s9s_mb_2u(sch_1):page561_i79@pure_quanta.q_res(chips)"
			("LOCATION" "R1813")
		)
		("@s9s_mb_2u_lib.s9s_mb_2u(sch_1):page561_i77@pure_quanta.q_res(chips)"
			("LOCATION" "R1814")
		)
		("@s9s_mb_2u_lib.s9s_mb_2u(sch_1):page561_i82@pure_quanta.q_res(chips)"
			("LOCATION" "R1831")
		)
		("@s9s_mb_2u_lib.s9s_mb_2u(sch_1):page561_i80@pure_quanta.q_res(chips)"
			("LOCATION" "R1832")
		)
		("@s9s_mb_2u_lib.s9s_mb_2u(sch_1):page561_i45@pure_quanta.gtl2014pw(chips)"
			("LOCATION" "U83")
		)
		("@s9s_mb_2u_lib.s9s_mb_2u(sch_1):page561_i18@pure_quanta.gtl2014pw(chips)"
			("LOCATION" "U84")
		)
		("@s9s_mb_2u_lib.s9s_mb_2u(sch_1):page561_i68@pure_quanta.ts3a24157rser(chips)"
			("LOCATION" "U96")
		)
		("@s9s_mb_2u_lib.s9s_mb_2u(sch_1):page561_i38@pure_quanta.ts3a24157rser(chips)"
			("LOCATION" "U97")
		)
		("@s9s_mb_2u_lib.s9s_mb_2u(sch_1):page486_i65@pure_quanta.q_cap(chips)"
			("LOCATION" "C1294")
		)
		("@s9s_mb_2u_lib.s9s_mb_2u(sch_1):page486_i10@pure_quanta.q_res(chips)"
			("LOCATION" "R159")
		)
		("@s9s_mb_2u_lib.s9s_mb_2u(sch_1):page486_i17@pure_quanta.q_res(chips)"
			("LOCATION" "R160")
		)
		("@s9s_mb_2u_lib.s9s_mb_2u(sch_1):page486_i18@pure_quanta.q_res(chips)"
			("LOCATION" "R161")
		)
		("@s9s_mb_2u_lib.s9s_mb_2u(sch_1):page486_i19@pure_quanta.q_res(chips)"
			("LOCATION" "R162")
		)
		("@s9s_mb_2u_lib.s9s_mb_2u(sch_1):page486_i25@pure_quanta.q_res(chips)"
			("LOCATION" "R163")
		)
		("@s9s_mb_2u_lib.s9s_mb_2u(sch_1):page486_i26@pure_quanta.q_res(chips)"
			("LOCATION" "R164")
		)
		("@s9s_mb_2u_lib.s9s_mb_2u(sch_1):page486_i32@pure_quanta.q_res(chips)"
			("LOCATION" "R165")
		)
		("@s9s_mb_2u_lib.s9s_mb_2u(sch_1):page486_i33@pure_quanta.q_res(chips)"
			("LOCATION" "R166")
		)
		("@s9s_mb_2u_lib.s9s_mb_2u(sch_1):page486_i42@pure_quanta.q_res(chips)"
			("LOCATION" "R167")
		)
		("@s9s_mb_2u_lib.s9s_mb_2u(sch_1):page486_i43@pure_quanta.q_res(chips)"
			("LOCATION" "R168")
		)
		("@s9s_mb_2u_lib.s9s_mb_2u(sch_1):page486_i53@pure_quanta.q_res(chips)"
			("LOCATION" "R170")
		)
		("@s9s_mb_2u_lib.s9s_mb_2u(sch_1):page486_i52@pure_quanta.q_res(chips)"
			("LOCATION" "R171")
		)
		("@s9s_mb_2u_lib.s9s_mb_2u(sch_1):page486_i49@pure_quanta.q_res(chips)"
			("LOCATION" "R173")
		)
		("@s9s_mb_2u_lib.s9s_mb_2u(sch_1):page486_i55@pure_quanta.q_res(chips)"
			("LOCATION" "R174")
		)
		("@s9s_mb_2u_lib.s9s_mb_2u(sch_1):page486_i16@pure_quanta.q_res(chips)"
			("LOCATION" "R175")
		)
		("@s9s_mb_2u_lib.s9s_mb_2u(sch_1):page486_i12@pure_quanta.q_res(chips)"
			("LOCATION" "R176")
		)
		("@s9s_mb_2u_lib.s9s_mb_2u(sch_1):page486_i23@pure_quanta.q_res(chips)"
			("LOCATION" "R177")
		)
		("@s9s_mb_2u_lib.s9s_mb_2u(sch_1):page486_i24@pure_quanta.q_res(chips)"
			("LOCATION" "R178")
		)
		("@s9s_mb_2u_lib.s9s_mb_2u(sch_1):page486_i30@pure_quanta.q_res(chips)"
			("LOCATION" "R179")
		)
		("@s9s_mb_2u_lib.s9s_mb_2u(sch_1):page486_i31@pure_quanta.q_res(chips)"
			("LOCATION" "R180")
		)
		("@s9s_mb_2u_lib.s9s_mb_2u(sch_1):page486_i38@pure_quanta.q_res(chips)"
			("LOCATION" "R181")
		)
		("@s9s_mb_2u_lib.s9s_mb_2u(sch_1):page486_i37@pure_quanta.q_res(chips)"
			("LOCATION" "R182")
		)
		("@s9s_mb_2u_lib.s9s_mb_2u(sch_1):page486_i62@pure_quanta.q_res(chips)"
			("LOCATION" "R183")
		)
		("@s9s_mb_2u_lib.s9s_mb_2u(sch_1):page486_i56@pure_quanta.q_res(chips)"
			("LOCATION" "R184")
		)
		("@s9s_mb_2u_lib.s9s_mb_2u(sch_1):page486_i60@pure_quanta.q_res(chips)"
			("LOCATION" "R185")
		)
		("@s9s_mb_2u_lib.s9s_mb_2u(sch_1):page486_i61@pure_quanta.q_res(chips)"
			("LOCATION" "R186")
		)
		("@s9s_mb_2u_lib.s9s_mb_2u(sch_1):page486_i67@pure_quanta.\\74lvc07apw\\(chips)"
			("LOCATION" "U5")
		)
		("@s9s_mb_2u_lib.s9s_mb_2u(sch_1):page486_i2@pure_quanta.\\74lvc07apw\\(chips)"
			("LOCATION" "U5")
		)
		("@s9s_mb_2u_lib.s9s_mb_2u(sch_1):page486_i3@pure_quanta.\\74lvc07apw\\(chips)"
			("LOCATION" "U5")
		)
		("@s9s_mb_2u_lib.s9s_mb_2u(sch_1):page486_i4@pure_quanta.\\74lvc07apw\\(chips)"
			("LOCATION" "U5")
		)
		("@s9s_mb_2u_lib.s9s_mb_2u(sch_1):page486_i5@pure_quanta.\\74lvc07apw\\(chips)"
			("LOCATION" "U5")
		)
		("@s9s_mb_2u_lib.s9s_mb_2u(sch_1):page486_i6@pure_quanta.\\74lvc07apw\\(chips)"
			("LOCATION" "U5")
		)
		("@s9s_mb_2u_lib.s9s_mb_2u(sch_1):page487_i54@pure_quanta.q_cap(chips)"
			("LOCATION" "C1295")
		)
		("@s9s_mb_2u_lib.s9s_mb_2u(sch_1):page487_i18@pure_quanta.q_res(chips)"
			("LOCATION" "R121")
		)
		("@s9s_mb_2u_lib.s9s_mb_2u(sch_1):page487_i17@pure_quanta.q_res(chips)"
			("LOCATION" "R122")
		)
		("@s9s_mb_2u_lib.s9s_mb_2u(sch_1):page487_i16@pure_quanta.q_res(chips)"
			("LOCATION" "R123")
		)
		("@s9s_mb_2u_lib.s9s_mb_2u(sch_1):page487_i15@pure_quanta.q_res(chips)"
			("LOCATION" "R124")
		)
		("@s9s_mb_2u_lib.s9s_mb_2u(sch_1):page487_i14@pure_quanta.q_res(chips)"
			("LOCATION" "R125")
		)
		("@s9s_mb_2u_lib.s9s_mb_2u(sch_1):page487_i13@pure_quanta.q_res(chips)"
			("LOCATION" "R126")
		)
		("@s9s_mb_2u_lib.s9s_mb_2u(sch_1):page487_i12@pure_quanta.q_res(chips)"
			("LOCATION" "R127")
		)
		("@s9s_mb_2u_lib.s9s_mb_2u(sch_1):page487_i7@pure_quanta.q_res(chips)"
			("LOCATION" "R128")
		)
		("@s9s_mb_2u_lib.s9s_mb_2u(sch_1):page487_i6@pure_quanta.q_res(chips)"
			("LOCATION" "R129")
		)
		("@s9s_mb_2u_lib.s9s_mb_2u(sch_1):page487_i5@pure_quanta.q_res(chips)"
			("LOCATION" "R130")
		)
		("@s9s_mb_2u_lib.s9s_mb_2u(sch_1):page487_i4@pure_quanta.q_res(chips)"
			("LOCATION" "R131")
		)
		("@s9s_mb_2u_lib.s9s_mb_2u(sch_1):page487_i3@pure_quanta.q_res(chips)"
			("LOCATION" "R132")
		)
		("@s9s_mb_2u_lib.s9s_mb_2u(sch_1):page487_i22@pure_quanta.q_res(chips)"
			("LOCATION" "R133")
		)
		("@s9s_mb_2u_lib.s9s_mb_2u(sch_1):page487_i21@pure_quanta.q_res(chips)"
			("LOCATION" "R134")
		)
		("@s9s_mb_2u_lib.s9s_mb_2u(sch_1):page487_i44@pure_quanta.q_res(chips)"
			("LOCATION" "R135")
		)
		("@s9s_mb_2u_lib.s9s_mb_2u(sch_1):page487_i43@pure_quanta.q_res(chips)"
			("LOCATION" "R136")
		)
		("@s9s_mb_2u_lib.s9s_mb_2u(sch_1):page487_i42@pure_quanta.q_res(chips)"
			("LOCATION" "R137")
		)
		("@s9s_mb_2u_lib.s9s_mb_2u(sch_1):page487_i39@pure_quanta.q_res(chips)"
			("LOCATION" "R150")
		)
		("@s9s_mb_2u_lib.s9s_mb_2u(sch_1):page487_i37@pure_quanta.q_res(chips)"
			("LOCATION" "R151")
		)
		("@s9s_mb_2u_lib.s9s_mb_2u(sch_1):page487_i38@pure_quanta.q_res(chips)"
			("LOCATION" "R152")
		)
		("@s9s_mb_2u_lib.s9s_mb_2u(sch_1):page487_i36@pure_quanta.q_res(chips)"
			("LOCATION" "R153")
		)
		("@s9s_mb_2u_lib.s9s_mb_2u(sch_1):page487_i35@pure_quanta.q_res(chips)"
			("LOCATION" "R154")
		)
		("@s9s_mb_2u_lib.s9s_mb_2u(sch_1):page487_i26@pure_quanta.q_res(chips)"
			("LOCATION" "R155")
		)
		("@s9s_mb_2u_lib.s9s_mb_2u(sch_1):page487_i25@pure_quanta.q_res(chips)"
			("LOCATION" "R156")
		)
		("@s9s_mb_2u_lib.s9s_mb_2u(sch_1):page487_i24@pure_quanta.q_res(chips)"
			("LOCATION" "R157")
		)
		("@s9s_mb_2u_lib.s9s_mb_2u(sch_1):page487_i23@pure_quanta.q_res(chips)"
			("LOCATION" "R158")
		)
		("@s9s_mb_2u_lib.s9s_mb_2u(sch_1):page487_i55@pure_quanta.\\74lvc07apw\\(chips)"
			("LOCATION" "U6")
		)
		("@s9s_mb_2u_lib.s9s_mb_2u(sch_1):page487_i31@pure_quanta.\\74lvc07apw\\(chips)"
			("LOCATION" "U6")
		)
		("@s9s_mb_2u_lib.s9s_mb_2u(sch_1):page487_i32@pure_quanta.\\74lvc07apw\\(chips)"
			("LOCATION" "U6")
		)
		("@s9s_mb_2u_lib.s9s_mb_2u(sch_1):page487_i33@pure_quanta.\\74lvc07apw\\(chips)"
			("LOCATION" "U6")
		)
		("@s9s_mb_2u_lib.s9s_mb_2u(sch_1):page487_i19@pure_quanta.\\74lvc07apw\\(chips)"
			("LOCATION" "U6")
		)
		("@s9s_mb_2u_lib.s9s_mb_2u(sch_1):page487_i20@pure_quanta.\\74lvc07apw\\(chips)"
			("LOCATION" "U6")
		)
		("@s9s_mb_2u_lib.s9s_mb_2u(sch_1):page586_i34@pure_quanta.q_cap(chips)"
			("LOCATION" "C1296")
		)
		("@s9s_mb_2u_lib.s9s_mb_2u(sch_1):page586_i37@pure_quanta.q_cap(chips)"
			("LOCATION" "C1307")
		)
		("@s9s_mb_2u_lib.s9s_mb_2u(sch_1):page586_i26@pure_quanta.q_cap(chips)"
			("LOCATION" "PC645")
		)
		("@s9s_mb_2u_lib.s9s_mb_2u(sch_1):page586_i2@pure_quanta.q_cap(chips)"
			("LOCATION" "PC1206")
		)
		("@s9s_mb_2u_lib.s9s_mb_2u(sch_1):page586_i16@pure_quanta.q_cap(chips)"
			("LOCATION" "PC1272")
		)
		("@s9s_mb_2u_lib.s9s_mb_2u(sch_1):page586_i14@pure_quanta.q_cap(chips)"
			("LOCATION" "PC1273")
		)
		("@s9s_mb_2u_lib.s9s_mb_2u(sch_1):page586_i13@pure_quanta.q_cap(chips)"
			("LOCATION" "PC1274")
		)
		("@s9s_mb_2u_lib.s9s_mb_2u(sch_1):page586_i12@pure_quanta.q_cap(chips)"
			("LOCATION" "PC1275")
		)
		("@s9s_mb_2u_lib.s9s_mb_2u(sch_1):page586_i8@pure_quanta.q_cap(chips)"
			("LOCATION" "PC1276")
		)
		("@s9s_mb_2u_lib.s9s_mb_2u(sch_1):page586_i7@pure_quanta.q_cap(chips)"
			("LOCATION" "PC1277")
		)
		("@s9s_mb_2u_lib.s9s_mb_2u(sch_1):page586_i6@pure_quanta.q_cap(chips)"
			("LOCATION" "PC1278")
		)
		("@s9s_mb_2u_lib.s9s_mb_2u(sch_1):page586_i4@pure_quanta.q_cap(chips)"
			("LOCATION" "PC1279")
		)
		("@s9s_mb_2u_lib.s9s_mb_2u(sch_1):page586_i9@pure_quanta.q_inductor(chips)"
			("LOCATION" "PL120")
		)
		("@s9s_mb_2u_lib.s9s_mb_2u(sch_1):page586_i31@pure_quanta.q_res(chips)"
			("LOCATION" "PR1317")
		)
		("@s9s_mb_2u_lib.s9s_mb_2u(sch_1):page586_i25@pure_quanta.q_res(chips)"
			("LOCATION" "PR1341")
		)
		("@s9s_mb_2u_lib.s9s_mb_2u(sch_1):page586_i23@pure_quanta.q_res(chips)"
			("LOCATION" "PR1342")
		)
		("@s9s_mb_2u_lib.s9s_mb_2u(sch_1):page586_i21@pure_quanta.nb695gdz(chips)"
			("LOCATION" "PU81")
		)
		("@s9s_mb_2u_lib.s9s_mb_2u(sch_1):page586_i36@pure_quanta.q_res(chips)"
			("LOCATION" "R1145")
		)
		("@s9s_mb_2u_lib.s9s_mb_2u(sch_1):page586_i38@pure_quanta.q_res(chips)"
			("LOCATION" "R1445")
		)
		("@s9s_mb_2u_lib.s9s_mb_2u(sch_1):page586_i28@pure_quanta.q_res(chips)"
			("LOCATION" "R1652")
		)
		("@s9s_mb_2u_lib.s9s_mb_2u(sch_1):page610_i38@pure_quanta.q_cap(chips)"
			("LOCATION" "C1297")
		)
		("@s9s_mb_2u_lib.s9s_mb_2u(sch_1):page610_i49@pure_quanta.q_cap(chips)"
			("LOCATION" "C1308")
		)
		("@s9s_mb_2u_lib.s9s_mb_2u(sch_1):page610_i25@pure_quanta.q_cap(chips)"
			("LOCATION" "PC1170")
		)
		("@s9s_mb_2u_lib.s9s_mb_2u(sch_1):page610_i2@pure_quanta.q_cap(chips)"
			("LOCATION" "PC1207")
		)
		("@s9s_mb_2u_lib.s9s_mb_2u(sch_1):page610_i18@pure_quanta.q_cap(chips)"
			("LOCATION" "PC1280")
		)
		("@s9s_mb_2u_lib.s9s_mb_2u(sch_1):page610_i17@pure_quanta.q_cap(chips)"
			("LOCATION" "PC1281")
		)
		("@s9s_mb_2u_lib.s9s_mb_2u(sch_1):page610_i16@pure_quanta.q_cap(chips)"
			("LOCATION" "PC1282")
		)
		("@s9s_mb_2u_lib.s9s_mb_2u(sch_1):page610_i8@pure_quanta.q_cap(chips)"
			("LOCATION" "PC1283")
		)
		("@s9s_mb_2u_lib.s9s_mb_2u(sch_1):page610_i11@pure_quanta.q_cap(chips)"
			("LOCATION" "PC1284")
		)
		("@s9s_mb_2u_lib.s9s_mb_2u(sch_1):page610_i10@pure_quanta.q_cap(chips)"
			("LOCATION" "PC1285")
		)
		("@s9s_mb_2u_lib.s9s_mb_2u(sch_1):page610_i9@pure_quanta.q_cap(chips)"
			("LOCATION" "PC1286")
		)
		("@s9s_mb_2u_lib.s9s_mb_2u(sch_1):page610_i3@pure_quanta.q_cap(chips)"
			("LOCATION" "PC1287")
		)
		("@s9s_mb_2u_lib.s9s_mb_2u(sch_1):page610_i12@pure_quanta.q_inductor(chips)"
			("LOCATION" "PL121")
		)
		("@s9s_mb_2u_lib.s9s_mb_2u(sch_1):page610_i34@pure_quanta.q_res(chips)"
			("LOCATION" "PR1320")
		)
		("@s9s_mb_2u_lib.s9s_mb_2u(sch_1):page610_i24@pure_quanta.q_res(chips)"
			("LOCATION" "PR1343")
		)
		("@s9s_mb_2u_lib.s9s_mb_2u(sch_1):page610_i20@pure_quanta.q_res(chips)"
			("LOCATION" "PR1344")
		)
		("@s9s_mb_2u_lib.s9s_mb_2u(sch_1):page610_i14@pure_quanta.nb695gdz(chips)"
			("LOCATION" "PU82")
		)
		("@s9s_mb_2u_lib.s9s_mb_2u(sch_1):page610_i35@pure_quanta.q_res(chips)"
			("LOCATION" "R1653")
		)
		("@s9s_mb_2u_lib.s9s_mb_2u(sch_1):page610_i48@pure_quanta.q_res(chips)"
			("LOCATION" "R1686")
		)
		("@s9s_mb_2u_lib.s9s_mb_2u(sch_1):page610_i50@pure_quanta.q_res(chips)"
			("LOCATION" "R1687")
		)
		("@s9s_mb_2u_lib.s9s_mb_2u(sch_1):page454_i40@pure_quanta.q_cap(chips)"
			("LOCATION" "C1300")
		)
		("@s9s_mb_2u_lib.s9s_mb_2u(sch_1):page454_i46@pure_quanta.q_cap(chips)"
			("LOCATION" "C1301")
		)
		("@s9s_mb_2u_lib.s9s_mb_2u(sch_1):page454_i29@pure_quanta.q_cap(chips)"
			("LOCATION" "PC1247")
		)
		("@s9s_mb_2u_lib.s9s_mb_2u(sch_1):page454_i28@pure_quanta.q_cap(chips)"
			("LOCATION" "PC1248")
		)
		("@s9s_mb_2u_lib.s9s_mb_2u(sch_1):page454_i24@pure_quanta.q_cap(chips)"
			("LOCATION" "PC1249")
		)
		("@s9s_mb_2u_lib.s9s_mb_2u(sch_1):page454_i21@pure_quanta.q_cap(chips)"
			("LOCATION" "PC1251")
		)
		("@s9s_mb_2u_lib.s9s_mb_2u(sch_1):page454_i15@pure_quanta.q_cap(chips)"
			("LOCATION" "PC1252")
		)
		("@s9s_mb_2u_lib.s9s_mb_2u(sch_1):page454_i17@pure_quanta.q_cap(chips)"
			("LOCATION" "PC1253")
		)
		("@s9s_mb_2u_lib.s9s_mb_2u(sch_1):page454_i7@pure_quanta.q_cap(chips)"
			("LOCATION" "PC1254")
		)
		("@s9s_mb_2u_lib.s9s_mb_2u(sch_1):page454_i5@pure_quanta.q_cap(chips)"
			("LOCATION" "PC1255")
		)
		("@s9s_mb_2u_lib.s9s_mb_2u(sch_1):page454_i4@pure_quanta.q_cap(chips)"
			("LOCATION" "PC1256")
		)
		("@s9s_mb_2u_lib.s9s_mb_2u(sch_1):page454_i3@pure_quanta.q_cap(chips)"
			("LOCATION" "PC1257")
		)
		("@s9s_mb_2u_lib.s9s_mb_2u(sch_1):page454_i2@pure_quanta.q_capp(chips)"
			("LOCATION" "PC1258")
		)
		("@s9s_mb_2u_lib.s9s_mb_2u(sch_1):page454_i49@pure_quanta.q_cap(chips)"
			("LOCATION" "PC1417")
		)
		("@s9s_mb_2u_lib.s9s_mb_2u(sch_1):page454_i35@pure_quanta.q_cap(chips)"
			("LOCATION" "PC2643")
		)
		("@s9s_mb_2u_lib.s9s_mb_2u(sch_1):page454_i12@pure_quanta.q_inductor(chips)"
			("LOCATION" "PL118")
		)
		("@s9s_mb_2u_lib.s9s_mb_2u(sch_1):page454_i42@pure_quanta.q_res(chips)"
			("LOCATION" "PR1309")
		)
		("@s9s_mb_2u_lib.s9s_mb_2u(sch_1):page454_i19@pure_quanta.q_res(chips)"
			("LOCATION" "PR1310")
		)
		("@s9s_mb_2u_lib.s9s_mb_2u(sch_1):page454_i34@pure_quanta.q_res(chips)"
			("LOCATION" "PR1335")
		)
		("@s9s_mb_2u_lib.s9s_mb_2u(sch_1):page454_i26@pure_quanta.q_res(chips)"
			("LOCATION" "PR1336")
		)
		("@s9s_mb_2u_lib.s9s_mb_2u(sch_1):page454_i16@pure_quanta.q_res(chips)"
			("LOCATION" "PR1337")
		)
		("@s9s_mb_2u_lib.s9s_mb_2u(sch_1):page454_i25@pure_quanta.mpq8633aglec807z(chips)"
			("LOCATION" "PU79")
		)
		("@s9s_mb_2u_lib.s9s_mb_2u(sch_1):page454_i18@pure_quanta.q_res(chips)"
			("LOCATION" "R542")
		)
		("@s9s_mb_2u_lib.s9s_mb_2u(sch_1):page454_i37@pure_quanta.q_res(chips)"
			("LOCATION" "R1677")
		)
		("@s9s_mb_2u_lib.s9s_mb_2u(sch_1):page454_i41@pure_quanta.q_res(chips)"
			("LOCATION" "R1678")
		)
		("@s9s_mb_2u_lib.s9s_mb_2u(sch_1):page454_i47@pure_quanta.q_res(chips)"
			("LOCATION" "R1679")
		)
		("@s9s_mb_2u_lib.s9s_mb_2u(sch_1):page454_i10@pure_quanta.mosfet_n(chips)"
			("LOCATION" "U73")
		)
		("@s9s_mb_2u_lib.s9s_mb_2u(sch_1):page562_i101@pure_quanta.q_cap(chips)"
			("LOCATION" "C1302")
		)
		("@s9s_mb_2u_lib.s9s_mb_2u(sch_1):page562_i323@pure_quanta.q_cap(chips)"
			("LOCATION" "C1348")
		)
		("@s9s_mb_2u_lib.s9s_mb_2u(sch_1):page562_i333@pure_quanta.q_cap(chips)"
			("LOCATION" "C1352")
		)
		("@s9s_mb_2u_lib.s9s_mb_2u(sch_1):page562_i115@pure_quanta.sconn168_623403212(chips)"
			("LOCATION" "J41")
		)
		("@s9s_mb_2u_lib.s9s_mb_2u(sch_1):page562_i314@pure_quanta.mosfet_pch_gds_esd_protected(chips)"
			("LOCATION" "Q32")
		)
		("@s9s_mb_2u_lib.s9s_mb_2u(sch_1):page562_i381@pure_quanta.mosfet_nch_dual(chips)"
			("LOCATION" "Q39")
		)
		("@s9s_mb_2u_lib.s9s_mb_2u(sch_1):page562_i372@pure_quanta.mosfet_nch_dual(chips)"
			("LOCATION" "Q39")
		)
		("@s9s_mb_2u_lib.s9s_mb_2u(sch_1):page562_i99@pure_quanta.q_res(chips)"
			("LOCATION" "R142")
		)
		("@s9s_mb_2u_lib.s9s_mb_2u(sch_1):page562_i284@pure_quanta.q_res(chips)"
			("LOCATION" "R506")
		)
		("@s9s_mb_2u_lib.s9s_mb_2u(sch_1):page562_i268@pure_quanta.q_res(chips)"
			("LOCATION" "R1711")
		)
		("@s9s_mb_2u_lib.s9s_mb_2u(sch_1):page562_i331@pure_quanta.q_res(chips)"
			("LOCATION" "R1797")
		)
		("@s9s_mb_2u_lib.s9s_mb_2u(sch_1):page562_i332@pure_quanta.q_res(chips)"
			("LOCATION" "R1798")
		)
		("@s9s_mb_2u_lib.s9s_mb_2u(sch_1):page562_i398@pure_quanta.q_res(chips)"
			("LOCATION" "R1801")
		)
		("@s9s_mb_2u_lib.s9s_mb_2u(sch_1):page562_i269@pure_quanta.q_res(chips)"
			("LOCATION" "R1815")
		)
		("@s9s_mb_2u_lib.s9s_mb_2u(sch_1):page562_i270@pure_quanta.q_res(chips)"
			("LOCATION" "R1816")
		)
		("@s9s_mb_2u_lib.s9s_mb_2u(sch_1):page562_i285@pure_quanta.q_res(chips)"
			("LOCATION" "R1833")
		)
		("@s9s_mb_2u_lib.s9s_mb_2u(sch_1):page562_i278@pure_quanta.q_res(chips)"
			("LOCATION" "R1845")
		)
		("@s9s_mb_2u_lib.s9s_mb_2u(sch_1):page562_i390@pure_quanta.q_res(chips)"
			("LOCATION" "R1854")
		)
		("@s9s_mb_2u_lib.s9s_mb_2u(sch_1):page562_i386@pure_quanta.q_res(chips)"
			("LOCATION" "R1855")
		)
		("@s9s_mb_2u_lib.s9s_mb_2u(sch_1):page562_i391@pure_quanta.q_res(chips)"
			("LOCATION" "R1856")
		)
		("@s9s_mb_2u_lib.s9s_mb_2u(sch_1):page562_i374@pure_quanta.q_res(chips)"
			("LOCATION" "R1857")
		)
		("@s9s_mb_2u_lib.s9s_mb_2u(sch_1):page562_i406@pure_quanta.q_res(chips)"
			("LOCATION" "R1925")
		)
		("@s9s_mb_2u_lib.s9s_mb_2u(sch_1):page562_i407@pure_quanta.q_res(chips)"
			("LOCATION" "R1926")
		)
		("@s9s_mb_2u_lib.s9s_mb_2u(sch_1):page604_i42@pure_quanta.q_cap(chips)"
			("LOCATION" "C1303")
		)
		("@s9s_mb_2u_lib.s9s_mb_2u(sch_1):page604_i50@pure_quanta.q_cap(chips)"
			("LOCATION" "C1304")
		)
		("@s9s_mb_2u_lib.s9s_mb_2u(sch_1):page604_i35@pure_quanta.q_cap(chips)"
			("LOCATION" "PC644")
		)
		("@s9s_mb_2u_lib.s9s_mb_2u(sch_1):page604_i28@pure_quanta.q_cap(chips)"
			("LOCATION" "PC1259")
		)
		("@s9s_mb_2u_lib.s9s_mb_2u(sch_1):page604_i26@pure_quanta.q_cap(chips)"
			("LOCATION" "PC1260")
		)
		("@s9s_mb_2u_lib.s9s_mb_2u(sch_1):page604_i25@pure_quanta.q_cap(chips)"
			("LOCATION" "PC1261")
		)
		("@s9s_mb_2u_lib.s9s_mb_2u(sch_1):page604_i24@pure_quanta.q_cap(chips)"
			("LOCATION" "PC1262")
		)
		("@s9s_mb_2u_lib.s9s_mb_2u(sch_1):page604_i21@pure_quanta.q_cap(chips)"
			("LOCATION" "PC1264")
		)
		("@s9s_mb_2u_lib.s9s_mb_2u(sch_1):page604_i18@pure_quanta.q_cap(chips)"
			("LOCATION" "PC1265")
		)
		("@s9s_mb_2u_lib.s9s_mb_2u(sch_1):page604_i16@pure_quanta.q_cap(chips)"
			("LOCATION" "PC1266")
		)
		("@s9s_mb_2u_lib.s9s_mb_2u(sch_1):page604_i10@pure_quanta.q_cap(chips)"
			("LOCATION" "PC1267")
		)
		("@s9s_mb_2u_lib.s9s_mb_2u(sch_1):page604_i9@pure_quanta.q_cap(chips)"
			("LOCATION" "PC1268")
		)
		("@s9s_mb_2u_lib.s9s_mb_2u(sch_1):page604_i7@pure_quanta.q_cap(chips)"
			("LOCATION" "PC1269")
		)
		("@s9s_mb_2u_lib.s9s_mb_2u(sch_1):page604_i5@pure_quanta.q_cap(chips)"
			("LOCATION" "PC1270")
		)
		("@s9s_mb_2u_lib.s9s_mb_2u(sch_1):page604_i4@pure_quanta.q_capp(chips)"
			("LOCATION" "PC1771")
		)
		("@s9s_mb_2u_lib.s9s_mb_2u(sch_1):page604_i14@pure_quanta.q_inductor(chips)"
			("LOCATION" "PL119")
		)
		("@s9s_mb_2u_lib.s9s_mb_2u(sch_1):page604_i51@pure_quanta.q_res(chips)"
			("LOCATION" "PR1313")
		)
		("@s9s_mb_2u_lib.s9s_mb_2u(sch_1):page604_i20@pure_quanta.q_res(chips)"
			("LOCATION" "PR1314")
		)
		("@s9s_mb_2u_lib.s9s_mb_2u(sch_1):page604_i33@pure_quanta.q_res(chips)"
			("LOCATION" "PR1338")
		)
		("@s9s_mb_2u_lib.s9s_mb_2u(sch_1):page604_i31@pure_quanta.q_res(chips)"
			("LOCATION" "PR1339")
		)
		("@s9s_mb_2u_lib.s9s_mb_2u(sch_1):page604_i15@pure_quanta.q_res(chips)"
			("LOCATION" "PR1340")
		)
		("@s9s_mb_2u_lib.s9s_mb_2u(sch_1):page604_i29@pure_quanta.mpq8633aglec807z(chips)"
			("LOCATION" "PU80")
		)
		("@s9s_mb_2u_lib.s9s_mb_2u(sch_1):page604_i17@pure_quanta.q_res(chips)"
			("LOCATION" "R543")
		)
		("@s9s_mb_2u_lib.s9s_mb_2u(sch_1):page604_i39@pure_quanta.q_res(chips)"
			("LOCATION" "R1683")
		)
		("@s9s_mb_2u_lib.s9s_mb_2u(sch_1):page604_i41@pure_quanta.q_res(chips)"
			("LOCATION" "R1684")
		)
		("@s9s_mb_2u_lib.s9s_mb_2u(sch_1):page604_i45@pure_quanta.q_res(chips)"
			("LOCATION" "R1685")
		)
		("@s9s_mb_2u_lib.s9s_mb_2u(sch_1):page604_i13@pure_quanta.mosfet_n(chips)"
			("LOCATION" "U74")
		)
		("@s9s_mb_2u_lib.s9s_mb_2u(sch_1):page567_i8@pure_quanta.q_cap(chips)"
			("LOCATION" "C1315")
		)
		("@s9s_mb_2u_lib.s9s_mb_2u(sch_1):page567_i12@pure_quanta.q_cap(chips)"
			("LOCATION" "C1316")
		)
		("@s9s_mb_2u_lib.s9s_mb_2u(sch_1):page567_i22@pure_quanta.q_cap(chips)"
			("LOCATION" "C1317")
		)
		("@s9s_mb_2u_lib.s9s_mb_2u(sch_1):page567_i20@pure_quanta.q_cap(chips)"
			("LOCATION" "C1318")
		)
		("@s9s_mb_2u_lib.s9s_mb_2u(sch_1):page567_i29@pure_quanta.q_cap(chips)"
			("LOCATION" "C1319")
		)
		("@s9s_mb_2u_lib.s9s_mb_2u(sch_1):page567_i4@pure_quanta.q_res(chips)"
			("LOCATION" "R1688")
		)
		("@s9s_mb_2u_lib.s9s_mb_2u(sch_1):page567_i6@pure_quanta.q_res(chips)"
			("LOCATION" "R1689")
		)
		("@s9s_mb_2u_lib.s9s_mb_2u(sch_1):page567_i2@pure_quanta.q_res(chips)"
			("LOCATION" "R1690")
		)
		("@s9s_mb_2u_lib.s9s_mb_2u(sch_1):page567_i14@pure_quanta.q_res(chips)"
			("LOCATION" "R1691")
		)
		("@s9s_mb_2u_lib.s9s_mb_2u(sch_1):page567_i15@pure_quanta.q_res(chips)"
			("LOCATION" "R1692")
		)
		("@s9s_mb_2u_lib.s9s_mb_2u(sch_1):page567_i25@pure_quanta.q_res(chips)"
			("LOCATION" "R1693")
		)
		("@s9s_mb_2u_lib.s9s_mb_2u(sch_1):page567_i28@pure_quanta.q_res(chips)"
			("LOCATION" "R1694")
		)
		("@s9s_mb_2u_lib.s9s_mb_2u(sch_1):page567_i31@pure_quanta.q_res(chips)"
			("LOCATION" "R1695")
		)
		("@s9s_mb_2u_lib.s9s_mb_2u(sch_1):page567_i33@pure_quanta.q_res(chips)"
			("LOCATION" "R1745")
		)
		("@s9s_mb_2u_lib.s9s_mb_2u(sch_1):page567_i1@pure_quanta.adm1085akszreel7(chips)"
			("LOCATION" "U94")
		)
		("@s9s_mb_2u_lib.s9s_mb_2u(sch_1):page567_i18@pure_quanta.sn74lvc1g07dckr(chips)"
			("LOCATION" "U95")
		)
		("@s9s_mb_2u_lib.s9s_mb_2u(sch_1):page542_i134@pure_quanta.q_cap(chips)"
			("LOCATION" "C1320")
		)
		("@s9s_mb_2u_lib.s9s_mb_2u(sch_1):page542_i132@pure_quanta.q_osc4p(chips)"
			("LOCATION" "OSC2")
		)
		("@s9s_mb_2u_lib.s9s_mb_2u(sch_1):page542_i136@pure_quanta.q_res(chips)"
			("LOCATION" "R1099")
		)
		("@s9s_mb_2u_lib.s9s_mb_2u(sch_1):page542_i139@pure_quanta.q_res(chips)"
			("LOCATION" "R1100")
		)
		("@s9s_mb_2u_lib.s9s_mb_2u(sch_1):page542_i149@pure_quanta.q_res(chips)"
			("LOCATION" "R1644")
		)
		("@s9s_mb_2u_lib.s9s_mb_2u(sch_1):page542_i144@pure_quanta.q_res(chips)"
			("LOCATION" "R1737")
		)
		("@s9s_mb_2u_lib.s9s_mb_2u(sch_1):page542_i152@pure_quanta.q_res(chips)"
			("LOCATION" "R1823")
		)
		("@s9s_mb_2u_lib.s9s_mb_2u(sch_1):page542_i33@pure_quanta.\\10m25daf484c7g\\(chips)"
			("LOCATION" "U3")
		)
		("@s9s_mb_2u_lib.s9s_mb_2u(sch_1):page545_i166@pure_quanta.q_cap(chips)"
			("LOCATION" "C1325")
		)
		("@s9s_mb_2u_lib.s9s_mb_2u(sch_1):page545_i144@pure_quanta.q_led(chips)"
			("LOCATION" "D0")
		)
		("@s9s_mb_2u_lib.s9s_mb_2u(sch_1):page545_i152@pure_quanta.q_res(chips)"
			("LOCATION" "R1106")
		)
		("@s9s_mb_2u_lib.s9s_mb_2u(sch_1):page545_i143@pure_quanta.q_res(chips)"
			("LOCATION" "R1195")
		)
		("@s9s_mb_2u_lib.s9s_mb_2u(sch_1):page545_i165@pure_quanta.q_res(chips)"
			("LOCATION" "R1710")
		)
		("@s9s_mb_2u_lib.s9s_mb_2u(sch_1):page545_i204@pure_quanta.q_res(chips)"
			("LOCATION" "R1738")
		)
		("@s9s_mb_2u_lib.s9s_mb_2u(sch_1):page545_i205@pure_quanta.q_res(chips)"
			("LOCATION" "R1739")
		)
		("@s9s_mb_2u_lib.s9s_mb_2u(sch_1):page545_i206@pure_quanta.q_res(chips)"
			("LOCATION" "R1740")
		)
		("@s9s_mb_2u_lib.s9s_mb_2u(sch_1):page545_i221@pure_quanta.q_res(chips)"
			("LOCATION" "R1917")
		)
		("@s9s_mb_2u_lib.s9s_mb_2u(sch_1):page545_i224@pure_quanta.q_res(chips)"
			("LOCATION" "R1918")
		)
		("@s9s_mb_2u_lib.s9s_mb_2u(sch_1):page545_i229@pure_quanta.q_res(chips)"
			("LOCATION" "R1936")
		)
		("@s9s_mb_2u_lib.s9s_mb_2u(sch_1):page545_i227@pure_quanta.q_res(chips)"
			("LOCATION" "R1937")
		)
		("@s9s_mb_2u_lib.s9s_mb_2u(sch_1):page545_i235@pure_quanta.q_res(chips)"
			("LOCATION" "R1938")
		)
		("@s9s_mb_2u_lib.s9s_mb_2u(sch_1):page545_i232@pure_quanta.q_res(chips)"
			("LOCATION" "R1939")
		)
		("@s9s_mb_2u_lib.s9s_mb_2u(sch_1):page545_i28@pure_quanta.\\10m25daf484c7g\\(chips)"
			("LOCATION" "U3")
		)
		("@s9s_mb_2u_lib.s9s_mb_2u(sch_1):page545_i29@pure_quanta.\\10m25daf484c7g\\(chips)"
			("LOCATION" "U3")
		)
		("@s9s_mb_2u_lib.s9s_mb_2u(sch_1):page545_i149@pure_quanta.mosfet_n(chips)"
			("LOCATION" "U89")
		)
		("@s9s_mb_2u_lib.s9s_mb_2u(sch_1):page577_i17@pure_quanta.q_cap(chips)"
			("LOCATION" "C1327")
		)
		("@s9s_mb_2u_lib.s9s_mb_2u(sch_1):page577_i2@pure_quanta.q_cap(chips)"
			("LOCATION" "C1328")
		)
		("@s9s_mb_2u_lib.s9s_mb_2u(sch_1):page577_i5@pure_quanta.q_cap(chips)"
			("LOCATION" "C1329")
		)
		("@s9s_mb_2u_lib.s9s_mb_2u(sch_1):page577_i7@pure_quanta.q_cap(chips)"
			("LOCATION" "C1330")
		)
		("@s9s_mb_2u_lib.s9s_mb_2u(sch_1):page577_i13@pure_quanta.q_res(chips)"
			("LOCATION" "R1716")
		)
		("@s9s_mb_2u_lib.s9s_mb_2u(sch_1):page577_i22@pure_quanta.q_res(chips)"
			("LOCATION" "R1729")
		)
		("@s9s_mb_2u_lib.s9s_mb_2u(sch_1):page577_i20@pure_quanta.q_res(chips)"
			("LOCATION" "R1818")
		)
		("@s9s_mb_2u_lib.s9s_mb_2u(sch_1):page577_i25@pure_quanta.q_res(chips)"
			("LOCATION" "R1819")
		)
		("@s9s_mb_2u_lib.s9s_mb_2u(sch_1):page577_i27@pure_quanta.q_res(chips)"
			("LOCATION" "R1866")
		)
		("@s9s_mb_2u_lib.s9s_mb_2u(sch_1):page577_i28@pure_quanta.q_res(chips)"
			("LOCATION" "R1867")
		)
		("@s9s_mb_2u_lib.s9s_mb_2u(sch_1):page577_i1@pure_quanta.rt9059gqw(chips)"
			("LOCATION" "U100")
		)
		("@s9s_mb_2u_lib.s9s_mb_2u(sch_1):page452_i187@pure_quanta.q_cap(chips)"
			("LOCATION" "C1334")
		)
		("@s9s_mb_2u_lib.s9s_mb_2u(sch_1):page452_i188@pure_quanta.q_cap(chips)"
			("LOCATION" "C1335")
		)
		("@s9s_mb_2u_lib.s9s_mb_2u(sch_1):page452_i132@pure_quanta.q_cap(chips)"
			("LOCATION" "PC626")
		)
		("@s9s_mb_2u_lib.s9s_mb_2u(sch_1):page452_i139@pure_quanta.q_cap(chips)"
			("LOCATION" "PC629")
		)
		("@s9s_mb_2u_lib.s9s_mb_2u(sch_1):page452_i157@pure_quanta.q_cap(chips)"
			("LOCATION" "PC632")
		)
		("@s9s_mb_2u_lib.s9s_mb_2u(sch_1):page452_i156@pure_quanta.q_cap(chips)"
			("LOCATION" "PC1196")
		)
		("@s9s_mb_2u_lib.s9s_mb_2u(sch_1):page452_i95@pure_quanta.q_short(chips)"
			("LOCATION" "PJ54")
		)
		("@s9s_mb_2u_lib.s9s_mb_2u(sch_1):page452_i84@pure_quanta.q_res(chips)"
			("LOCATION" "PR357")
		)
		("@s9s_mb_2u_lib.s9s_mb_2u(sch_1):page452_i129@pure_quanta.q_res(chips)"
			("LOCATION" "PR361")
		)
		("@s9s_mb_2u_lib.s9s_mb_2u(sch_1):page452_i126@pure_quanta.q_res(chips)"
			("LOCATION" "PR362")
		)
		("@s9s_mb_2u_lib.s9s_mb_2u(sch_1):page452_i128@pure_quanta.q_res(chips)"
			("LOCATION" "PR363")
		)
		("@s9s_mb_2u_lib.s9s_mb_2u(sch_1):page452_i127@pure_quanta.q_res(chips)"
			("LOCATION" "PR364")
		)
		("@s9s_mb_2u_lib.s9s_mb_2u(sch_1):page452_i125@pure_quanta.q_res(chips)"
			("LOCATION" "PR365")
		)
		("@s9s_mb_2u_lib.s9s_mb_2u(sch_1):page452_i124@pure_quanta.q_res(chips)"
			("LOCATION" "PR366")
		)
		("@s9s_mb_2u_lib.s9s_mb_2u(sch_1):page452_i121@pure_quanta.q_res(chips)"
			("LOCATION" "PR367")
		)
		("@s9s_mb_2u_lib.s9s_mb_2u(sch_1):page452_i122@pure_quanta.q_res(chips)"
			("LOCATION" "PR368")
		)
		("@s9s_mb_2u_lib.s9s_mb_2u(sch_1):page452_i103@pure_quanta.q_res(chips)"
			("LOCATION" "PR369")
		)
		("@s9s_mb_2u_lib.s9s_mb_2u(sch_1):page452_i112@pure_quanta.q_res(chips)"
			("LOCATION" "PR370")
		)
		("@s9s_mb_2u_lib.s9s_mb_2u(sch_1):page452_i119@pure_quanta.q_res(chips)"
			("LOCATION" "PR371")
		)
		("@s9s_mb_2u_lib.s9s_mb_2u(sch_1):page452_i113@pure_quanta.q_res(chips)"
			("LOCATION" "PR372")
		)
		("@s9s_mb_2u_lib.s9s_mb_2u(sch_1):page452_i106@pure_quanta.q_res(chips)"
			("LOCATION" "PR373")
		)
		("@s9s_mb_2u_lib.s9s_mb_2u(sch_1):page452_i158@pure_quanta.q_res(chips)"
			("LOCATION" "PR375")
		)
		("@s9s_mb_2u_lib.s9s_mb_2u(sch_1):page452_i144@pure_quanta.q_res(chips)"
			("LOCATION" "PR378")
		)
		("@s9s_mb_2u_lib.s9s_mb_2u(sch_1):page452_i94@pure_quanta.q_res(chips)"
			("LOCATION" "PR591")
		)
		("@s9s_mb_2u_lib.s9s_mb_2u(sch_1):page452_i96@pure_quanta.q_res(chips)"
			("LOCATION" "PR592")
		)
		("@s9s_mb_2u_lib.s9s_mb_2u(sch_1):page452_i195@pure_quanta.q_res(chips)"
			("LOCATION" "PR1311")
		)
		("@s9s_mb_2u_lib.s9s_mb_2u(sch_1):page452_i193@pure_quanta.q_res(chips)"
			("LOCATION" "R1717")
		)
		("@s9s_mb_2u_lib.s9s_mb_2u(sch_1):page452_i194@pure_quanta.q_res(chips)"
			("LOCATION" "R1735")
		)
		("@s9s_mb_2u_lib.s9s_mb_2u(sch_1):page571_i37@pure_quanta.q_cap(chips)"
			("LOCATION" "C1344")
		)
		("@s9s_mb_2u_lib.s9s_mb_2u(sch_1):page571_i39@pure_quanta.q_cap(chips)"
			("LOCATION" "C1345")
		)
		("@s9s_mb_2u_lib.s9s_mb_2u(sch_1):page571_i42@pure_quanta.q_cap(chips)"
			("LOCATION" "C1346")
		)
		("@s9s_mb_2u_lib.s9s_mb_2u(sch_1):page571_i3@pure_quanta.q_cap(chips)"
			("LOCATION" "C1347")
		)
		("@s9s_mb_2u_lib.s9s_mb_2u(sch_1):page571_i45@pure_quanta.q_cap(chips)"
			("LOCATION" "C1351")
		)
		("@s9s_mb_2u_lib.s9s_mb_2u(sch_1):page571_i14@pure_quanta.q_res(chips)"
			("LOCATION" "R1784")
		)
		("@s9s_mb_2u_lib.s9s_mb_2u(sch_1):page571_i17@pure_quanta.q_res(chips)"
			("LOCATION" "R1785")
		)
		("@s9s_mb_2u_lib.s9s_mb_2u(sch_1):page571_i27@pure_quanta.q_res(chips)"
			("LOCATION" "R1786")
		)
		("@s9s_mb_2u_lib.s9s_mb_2u(sch_1):page571_i28@pure_quanta.q_res(chips)"
			("LOCATION" "R1787")
		)
		("@s9s_mb_2u_lib.s9s_mb_2u(sch_1):page571_i31@pure_quanta.q_res(chips)"
			("LOCATION" "R1788")
		)
		("@s9s_mb_2u_lib.s9s_mb_2u(sch_1):page571_i34@pure_quanta.q_res(chips)"
			("LOCATION" "R1789")
		)
		("@s9s_mb_2u_lib.s9s_mb_2u(sch_1):page571_i40@pure_quanta.q_res(chips)"
			("LOCATION" "R1790")
		)
		("@s9s_mb_2u_lib.s9s_mb_2u(sch_1):page571_i43@pure_quanta.q_res(chips)"
			("LOCATION" "R1791")
		)
		("@s9s_mb_2u_lib.s9s_mb_2u(sch_1):page571_i20@pure_quanta.q_res(chips)"
			("LOCATION" "R1792")
		)
		("@s9s_mb_2u_lib.s9s_mb_2u(sch_1):page571_i19@pure_quanta.q_res(chips)"
			("LOCATION" "R1793")
		)
		("@s9s_mb_2u_lib.s9s_mb_2u(sch_1):page571_i10@pure_quanta.q_res(chips)"
			("LOCATION" "R1794")
		)
		("@s9s_mb_2u_lib.s9s_mb_2u(sch_1):page571_i44@pure_quanta.q_res(chips)"
			("LOCATION" "R1799")
		)
		("@s9s_mb_2u_lib.s9s_mb_2u(sch_1):page571_i46@pure_quanta.q_res(chips)"
			("LOCATION" "R1800")
		)
		("@s9s_mb_2u_lib.s9s_mb_2u(sch_1):page571_i1@pure_quanta.ads1015idgsr(chips)"
			("LOCATION" "U105")
		)
		("@s9s_mb_2u_lib.s9s_mb_2u(sch_1):page617_i51@pure_quanta.q_cap(chips)"
			("LOCATION" "C1363")
		)
		("@s9s_mb_2u_lib.s9s_mb_2u(sch_1):page617_i53@pure_quanta.q_cap(chips)"
			("LOCATION" "C1364")
		)
		("@s9s_mb_2u_lib.s9s_mb_2u(sch_1):page617_i47@pure_quanta.q_cap(chips)"
			("LOCATION" "C1365")
		)
		("@s9s_mb_2u_lib.s9s_mb_2u(sch_1):page617_i49@pure_quanta.q_cap(chips)"
			("LOCATION" "C1366")
		)
		("@s9s_mb_2u_lib.s9s_mb_2u(sch_1):page617_i19@pure_quanta.q_res(chips)"
			("LOCATION" "R319")
		)
		("@s9s_mb_2u_lib.s9s_mb_2u(sch_1):page617_i20@pure_quanta.q_res(chips)"
			("LOCATION" "R320")
		)
		("@s9s_mb_2u_lib.s9s_mb_2u(sch_1):page617_i21@pure_quanta.q_res(chips)"
			("LOCATION" "R321")
		)
		("@s9s_mb_2u_lib.s9s_mb_2u(sch_1):page617_i4@pure_quanta.q_res(chips)"
			("LOCATION" "R323")
		)
		("@s9s_mb_2u_lib.s9s_mb_2u(sch_1):page617_i3@pure_quanta.q_res(chips)"
			("LOCATION" "R324")
		)
		("@s9s_mb_2u_lib.s9s_mb_2u(sch_1):page617_i28@pure_quanta.q_res(chips)"
			("LOCATION" "R325")
		)
		("@s9s_mb_2u_lib.s9s_mb_2u(sch_1):page617_i29@pure_quanta.q_res(chips)"
			("LOCATION" "R326")
		)
		("@s9s_mb_2u_lib.s9s_mb_2u(sch_1):page617_i30@pure_quanta.q_res(chips)"
			("LOCATION" "R327")
		)
		("@s9s_mb_2u_lib.s9s_mb_2u(sch_1):page617_i8@pure_quanta.q_res(chips)"
			("LOCATION" "R329")
		)
		("@s9s_mb_2u_lib.s9s_mb_2u(sch_1):page617_i9@pure_quanta.q_res(chips)"
			("LOCATION" "R330")
		)
		("@s9s_mb_2u_lib.s9s_mb_2u(sch_1):page617_i45@pure_quanta.q_res(chips)"
			("LOCATION" "R383")
		)
		("@s9s_mb_2u_lib.s9s_mb_2u(sch_1):page617_i36@pure_quanta.q_res(chips)"
			("LOCATION" "R1216")
		)
		("@s9s_mb_2u_lib.s9s_mb_2u(sch_1):page617_i37@pure_quanta.q_res(chips)"
			("LOCATION" "R1217")
		)
		("@s9s_mb_2u_lib.s9s_mb_2u(sch_1):page504_i439@pure_quanta.q_cap(chips)"
			("LOCATION" "C1422")
		)
		("@s9s_mb_2u_lib.s9s_mb_2u(sch_1):page504_i381@pure_quanta.sconn140_623403242(chips)"
			("LOCATION" "J58")
		)
		("@s9s_mb_2u_lib.s9s_mb_2u(sch_1):page504_i394@pure_quanta.q_res(chips)"
			("LOCATION" "R432")
		)
		("@s9s_mb_2u_lib.s9s_mb_2u(sch_1):page504_i393@pure_quanta.q_res(chips)"
			("LOCATION" "R433")
		)
		("@s9s_mb_2u_lib.s9s_mb_2u(sch_1):page504_i396@pure_quanta.q_res(chips)"
			("LOCATION" "R434")
		)
		("@s9s_mb_2u_lib.s9s_mb_2u(sch_1):page504_i313@pure_quanta.q_res(chips)"
			("LOCATION" "R440")
		)
		("@s9s_mb_2u_lib.s9s_mb_2u(sch_1):page504_i314@pure_quanta.q_res(chips)"
			("LOCATION" "R441")
		)
		("@s9s_mb_2u_lib.s9s_mb_2u(sch_1):page504_i435@pure_quanta.q_res(chips)"
			("LOCATION" "R455")
		)
		("@s9s_mb_2u_lib.s9s_mb_2u(sch_1):page504_i432@pure_quanta.q_res(chips)"
			("LOCATION" "R503")
		)
		("@s9s_mb_2u_lib.s9s_mb_2u(sch_1):page504_i437@pure_quanta.q_res(chips)"
			("LOCATION" "R1674")
		)
		("@s9s_mb_2u_lib.s9s_mb_2u(sch_1):page504_i441@pure_quanta.q_res(chips)"
			("LOCATION" "R1927")
		)
		("@s9s_mb_2u_lib.s9s_mb_2u(sch_1):page504_i442@pure_quanta.q_res(chips)"
			("LOCATION" "R1928")
		)
		("@s9s_mb_2u_lib.s9s_mb_2u(sch_1):page544_i124@pure_quanta.q_led(chips)"
			("LOCATION" "D6")
		)
		("@s9s_mb_2u_lib.s9s_mb_2u(sch_1):page544_i126@pure_quanta.mosfet_pch_gds_esd_protected(chips)"
			("LOCATION" "Q33")
		)
		("@s9s_mb_2u_lib.s9s_mb_2u(sch_1):page544_i129@pure_quanta.q_res(chips)"
			("LOCATION" "R365")
		)
		("@s9s_mb_2u_lib.s9s_mb_2u(sch_1):page544_i122@pure_quanta.q_res(chips)"
			("LOCATION" "R366")
		)
		("@s9s_mb_2u_lib.s9s_mb_2u(sch_1):page544_i98@pure_quanta.q_res(chips)"
			("LOCATION" "R700")
		)
		("@s9s_mb_2u_lib.s9s_mb_2u(sch_1):page544_i139@pure_quanta.q_res(chips)"
			("LOCATION" "R1549")
		)
		("@s9s_mb_2u_lib.s9s_mb_2u(sch_1):page544_i137@pure_quanta.q_res(chips)"
			("LOCATION" "R1550")
		)
		("@s9s_mb_2u_lib.s9s_mb_2u(sch_1):page544_i111@pure_quanta.q_res(chips)"
			("LOCATION" "R1559")
		)
		("@s9s_mb_2u_lib.s9s_mb_2u(sch_1):page544_i112@pure_quanta.q_res(chips)"
			("LOCATION" "R1560")
		)
		("@s9s_mb_2u_lib.s9s_mb_2u(sch_1):page544_i133@pure_quanta.q_res(chips)"
			("LOCATION" "R1725")
		)
		("@s9s_mb_2u_lib.s9s_mb_2u(sch_1):page544_i156@pure_quanta.q_res(chips)"
			("LOCATION" "R1841")
		)
		("@s9s_mb_2u_lib.s9s_mb_2u(sch_1):page544_i28@pure_quanta.\\10m25daf484c7g\\(chips)"
			("LOCATION" "U3")
		)
		("@s9s_mb_2u_lib.s9s_mb_2u(sch_1):page613_i15@pure_quanta.dummy_symbol(chips)"
			("LOCATION" "DM4")
		)
		("@s9s_mb_2u_lib.s9s_mb_2u(sch_1):page613_i14@pure_quanta.dummy_symbol(chips)"
			("LOCATION" "DM7")
		)
		("@s9s_mb_2u_lib.s9s_mb_2u(sch_1):page613_i18@pure_quanta.dummy_symbol(chips)"
			("LOCATION" "DM8")
		)
		("@s9s_mb_2u_lib.s9s_mb_2u(sch_1):page613_i17@pure_quanta.dummy_symbol(chips)"
			("LOCATION" "DM9")
		)
		("@s9s_mb_2u_lib.s9s_mb_2u(sch_1):page613_i8@pure_quanta.dummy_symbol(chips)"
			("LOCATION" "DM10")
		)
		("@s9s_mb_2u_lib.s9s_mb_2u(sch_1):page613_i13@pure_quanta.dummy_symbol(chips)"
			("LOCATION" "DM13")
		)
		("@s9s_mb_2u_lib.s9s_mb_2u(sch_1):page613_i6@pure_quanta.dummy_symbol(chips)"
			("LOCATION" "DM14")
		)
		("@s9s_mb_2u_lib.s9s_mb_2u(sch_1):page613_i5@pure_quanta.dummy_symbol(chips)"
			("LOCATION" "DM15")
		)
		("@s9s_mb_2u_lib.s9s_mb_2u(sch_1):page613_i1@pure_quanta.dummy_symbol(chips)"
			("LOCATION" "DM16")
		)
		("@s9s_mb_2u_lib.s9s_mb_2u(sch_1):page613_i10@pure_quanta.me_dummy_symbol(chips)"
			("LOCATION" "ME2")
		)
		("@s9s_mb_2u_lib.s9s_mb_2u(sch_1):page613_i11@pure_quanta.me_dummy_symbol(chips)"
			("LOCATION" "ME3")
		)
		("@s9s_mb_2u_lib.s9s_mb_2u(sch_1):page613_i9@pure_quanta.me_dummy_symbol(chips)"
			("LOCATION" "ME4")
		)
		("@s9s_mb_2u_lib.s9s_mb_2u(sch_1):page613_i3@pure_quanta.me_dummy_symbol(chips)"
			("LOCATION" "ME5")
		)
		("@s9s_mb_2u_lib.s9s_mb_2u(sch_1):page613_i4@pure_quanta.me_dummy_symbol(chips)"
			("LOCATION" "ME6")
		)
		("@s9s_mb_2u_lib.s9s_mb_2u(sch_1):page613_i2@pure_quanta.me_dummy_symbol(chips)"
			("LOCATION" "ME7")
		)
		("@s9s_mb_2u_lib.s9s_mb_2u(sch_1):page613_i19@pure_quanta.dummy_symbol(chips)"
			("LOCATION" "ME8")
		)
		("@s9s_mb_2u_lib.s9s_mb_2u(sch_1):page612_i12@pure_quanta.hole(chips)"
			("LOCATION" "H1")
		)
		("@s9s_mb_2u_lib.s9s_mb_2u(sch_1):page612_i14@pure_quanta.hole(chips)"
			("LOCATION" "H2")
		)
		("@s9s_mb_2u_lib.s9s_mb_2u(sch_1):page612_i11@pure_quanta.hole(chips)"
			("LOCATION" "H3")
		)
		("@s9s_mb_2u_lib.s9s_mb_2u(sch_1):page612_i13@pure_quanta.hole(chips)"
			("LOCATION" "H4")
		)
		("@s9s_mb_2u_lib.s9s_mb_2u(sch_1):page612_i9@pure_quanta.hole(chips)"
			("LOCATION" "H5")
		)
		("@s9s_mb_2u_lib.s9s_mb_2u(sch_1):page612_i10@pure_quanta.hole(chips)"
			("LOCATION" "H6")
		)
		("@s9s_mb_2u_lib.s9s_mb_2u(sch_1):page612_i7@pure_quanta.hole(chips)"
			("LOCATION" "H7")
		)
		("@s9s_mb_2u_lib.s9s_mb_2u(sch_1):page612_i8@pure_quanta.hole(chips)"
			("LOCATION" "H8")
		)
		("@s9s_mb_2u_lib.s9s_mb_2u(sch_1):page612_i5@pure_quanta.hole(chips)"
			("LOCATION" "H9")
		)
		("@s9s_mb_2u_lib.s9s_mb_2u(sch_1):page612_i6@pure_quanta.hole(chips)"
			("LOCATION" "H10")
		)
		("@s9s_mb_2u_lib.s9s_mb_2u(sch_1):page612_i3@pure_quanta.hole(chips)"
			("LOCATION" "H11")
		)
		("@s9s_mb_2u_lib.s9s_mb_2u(sch_1):page612_i4@pure_quanta.hole(chips)"
			("LOCATION" "H12")
		)
		("@s9s_mb_2u_lib.s9s_mb_2u(sch_1):page612_i2@pure_quanta.hole(chips)"
			("LOCATION" "H13")
		)
		("@s9s_mb_2u_lib.s9s_mb_2u(sch_1):page612_i15@pure_quanta.hole(chips)"
			("LOCATION" "H15")
		)
		("@s9s_mb_2u_lib.s9s_mb_2u(sch_1):page612_i21@pure_quanta.hole(chips)"
			("LOCATION" "H16")
		)
		("@s9s_mb_2u_lib.s9s_mb_2u(sch_1):page612_i16@pure_quanta.hole(chips)"
			("LOCATION" "H17")
		)
		("@s9s_mb_2u_lib.s9s_mb_2u(sch_1):page612_i22@pure_quanta.hole(chips)"
			("LOCATION" "H18")
		)
		("@s9s_mb_2u_lib.s9s_mb_2u(sch_1):page612_i18@pure_quanta.hole(chips)"
			("LOCATION" "H19")
		)
		("@s9s_mb_2u_lib.s9s_mb_2u(sch_1):page612_i26@pure_quanta.hole(chips)"
			("LOCATION" "H20")
		)
		("@s9s_mb_2u_lib.s9s_mb_2u(sch_1):page612_i17@pure_quanta.hole(chips)"
			("LOCATION" "H21")
		)
		("@s9s_mb_2u_lib.s9s_mb_2u(sch_1):page612_i25@pure_quanta.hole(chips)"
			("LOCATION" "H22")
		)
		("@s9s_mb_2u_lib.s9s_mb_2u(sch_1):page612_i19@pure_quanta.hole(chips)"
			("LOCATION" "H23")
		)
		("@s9s_mb_2u_lib.s9s_mb_2u(sch_1):page612_i24@pure_quanta.hole(chips)"
			("LOCATION" "H24")
		)
		("@s9s_mb_2u_lib.s9s_mb_2u(sch_1):page612_i20@pure_quanta.hole(chips)"
			("LOCATION" "H25")
		)
		("@s9s_mb_2u_lib.s9s_mb_2u(sch_1):page612_i23@pure_quanta.hole(chips)"
			("LOCATION" "H26")
		)
		("@s9s_mb_2u_lib.s9s_mb_2u(sch_1):page612_i27@pure_quanta.hole(chips)"
			("LOCATION" "H27")
		)
		("@s9s_mb_2u_lib.s9s_mb_2u(sch_1):page612_i28@pure_quanta.hole(chips)"
			("LOCATION" "H28")
		)
		("@s9s_mb_2u_lib.s9s_mb_2u(sch_1):page612_i30@pure_quanta.hole(chips)"
			("LOCATION" "H29")
		)
		("@s9s_mb_2u_lib.s9s_mb_2u(sch_1):page612_i29@pure_quanta.hole(chips)"
			("LOCATION" "H30")
		)
		("@s9s_mb_2u_lib.s9s_mb_2u(sch_1):page612_i31@pure_quanta.hole(chips)"
			("LOCATION" "H31")
		)
		("@s9s_mb_2u_lib.s9s_mb_2u(sch_1):page612_i32@pure_quanta.hole(chips)"
			("LOCATION" "H32")
		)
		("@s9s_mb_2u_lib.s9s_mb_2u(sch_1):page612_i33@pure_quanta.hole(chips)"
			("LOCATION" "H33")
		)
		("@s9s_mb_2u_lib.s9s_mb_2u(sch_1):page612_i34@pure_quanta.hole(chips)"
			("LOCATION" "H34")
		)
		("@s9s_mb_2u_lib.s9s_mb_2u(sch_1):page612_i35@pure_quanta.hole(chips)"
			("LOCATION" "H35")
		)
		("@s9s_mb_2u_lib.s9s_mb_2u(sch_1):page612_i37@pure_quanta.hole(chips)"
			("LOCATION" "H36")
		)
		("@s9s_mb_2u_lib.s9s_mb_2u(sch_1):page612_i36@pure_quanta.hole(chips)"
			("LOCATION" "H37")
		)
		("@s9s_mb_2u_lib.s9s_mb_2u(sch_1):page612_i38@pure_quanta.hole(chips)"
			("LOCATION" "H38")
		)
		("@s9s_mb_2u_lib.s9s_mb_2u(sch_1):page612_i41@pure_quanta.hole(chips)"
			("LOCATION" "H39")
		)
		("@s9s_mb_2u_lib.s9s_mb_2u(sch_1):page612_i43@pure_quanta.hole(chips)"
			("LOCATION" "H40")
		)
		("@s9s_mb_2u_lib.s9s_mb_2u(sch_1):page612_i45@pure_quanta.hole(chips)"
			("LOCATION" "H41")
		)
		("@s9s_mb_2u_lib.s9s_mb_2u(sch_1):page612_i46@pure_quanta.hole(chips)"
			("LOCATION" "H42")
		)
		("@s9s_mb_2u_lib.s9s_mb_2u(sch_1):page612_i47@pure_quanta.hole(chips)"
			("LOCATION" "H43")
		)
		("@s9s_mb_2u_lib.s9s_mb_2u(sch_1):page612_i49@pure_quanta.hole(chips)"
			("LOCATION" "H44")
		)
		("@s9s_mb_2u_lib.s9s_mb_2u(sch_1):page612_i48@pure_quanta.hole(chips)"
			("LOCATION" "H45")
		)
		("@s9s_mb_2u_lib.s9s_mb_2u(sch_1):page612_i52@pure_quanta.hole(chips)"
			("LOCATION" "H47")
		)
		("@s9s_mb_2u_lib.s9s_mb_2u(sch_1):page612_i53@pure_quanta.hole(chips)"
			("LOCATION" "H49")
		)
		("@s9s_mb_2u_lib.s9s_mb_2u(sch_1):page612_i58@pure_quanta.hole(chips)"
			("LOCATION" "H54")
		)
		("@s9s_mb_2u_lib.s9s_mb_2u(sch_1):page612_i59@pure_quanta.hole(chips)"
			("LOCATION" "H55")
		)
		("@s9s_mb_2u_lib.s9s_mb_2u(sch_1):page568_i11@pure_quanta.conn24_hlh3127la00j7h(chips)"
			("LOCATION" "J44")
		)
		("@s9s_mb_2u_lib.s9s_mb_2u(sch_1):page568_i14@pure_quanta.conn24_hlh3127la00j7h(chips)"
			("LOCATION" "J45")
		)
		("@s9s_mb_2u_lib.s9s_mb_2u(sch_1):page568_i4@pure_quanta.q_res(chips)"
			("LOCATION" "R723")
		)
		("@s9s_mb_2u_lib.s9s_mb_2u(sch_1):page568_i3@pure_quanta.q_res(chips)"
			("LOCATION" "R724")
		)
		("@s9s_mb_2u_lib.s9s_mb_2u(sch_1):page568_i7@pure_quanta.q_res(chips)"
			("LOCATION" "R955")
		)
		("@s9s_mb_2u_lib.s9s_mb_2u(sch_1):page568_i20@pure_quanta.q_res(chips)"
			("LOCATION" "R1645")
		)
		("@s9s_mb_2u_lib.s9s_mb_2u(sch_1):page568_i23@pure_quanta.q_res(chips)"
			("LOCATION" "R1646")
		)
		("@s9s_mb_2u_lib.s9s_mb_2u(sch_1):page569_i60@pure_quanta.conn44_23220445(chips)"
			("LOCATION" "J46")
		)
		("@s9s_mb_2u_lib.s9s_mb_2u(sch_1):page569_i2@pure_quanta.conn12_1014699712001lf(chips)"
			("LOCATION" "J49")
		)
		("@s9s_mb_2u_lib.s9s_mb_2u(sch_1):page569_i4@pure_quanta.conn12_1014699712001lf(chips)"
			("LOCATION" "J50")
		)
		("@s9s_mb_2u_lib.s9s_mb_2u(sch_1):page569_i18@pure_quanta.conn20_hlh2103la00d7h(chips)"
			("LOCATION" "J53")
		)
		("@s9s_mb_2u_lib.s9s_mb_2u(sch_1):page569_i39@pure_quanta.q_inductor(chips)"
			("LOCATION" "L11")
		)
		("@s9s_mb_2u_lib.s9s_mb_2u(sch_1):page569_i47@pure_quanta.q_inductor(chips)"
			("LOCATION" "L12")
		)
		("@s9s_mb_2u_lib.s9s_mb_2u(sch_1):page569_i25@pure_quanta.q_res(chips)"
			("LOCATION" "R472")
		)
		("@s9s_mb_2u_lib.s9s_mb_2u(sch_1):page569_i27@pure_quanta.q_res(chips)"
			("LOCATION" "R473")
		)
		("@s9s_mb_2u_lib.s9s_mb_2u(sch_1):page569_i33@pure_quanta.q_res(chips)"
			("LOCATION" "R948")
		)
		("@s9s_mb_2u_lib.s9s_mb_2u(sch_1):page569_i35@pure_quanta.q_res(chips)"
			("LOCATION" "R949")
		)
		("@s9s_mb_2u_lib.s9s_mb_2u(sch_1):page569_i34@pure_quanta.q_res(chips)"
			("LOCATION" "R950")
		)
		("@s9s_mb_2u_lib.s9s_mb_2u(sch_1):page569_i36@pure_quanta.q_res(chips)"
			("LOCATION" "R951")
		)
		("@s9s_mb_2u_lib.s9s_mb_2u(sch_1):page569_i16@pure_quanta.q_res(chips)"
			("LOCATION" "R952")
		)
		("@s9s_mb_2u_lib.s9s_mb_2u(sch_1):page569_i45@pure_quanta.q_res(chips)"
			("LOCATION" "R1537")
		)
		("@s9s_mb_2u_lib.s9s_mb_2u(sch_1):page569_i46@pure_quanta.q_res(chips)"
			("LOCATION" "R1538")
		)
		("@s9s_mb_2u_lib.s9s_mb_2u(sch_1):page569_i52@pure_quanta.q_res(chips)"
			("LOCATION" "R1539")
		)
		("@s9s_mb_2u_lib.s9s_mb_2u(sch_1):page569_i49@pure_quanta.q_res(chips)"
			("LOCATION" "R1540")
		)
		("@s9s_mb_2u_lib.s9s_mb_2u(sch_1):page569_i14@pure_quanta.q_res(chips)"
			("LOCATION" "R1608")
		)
		("@s9s_mb_2u_lib.s9s_mb_2u(sch_1):page569_i73@pure_quanta.q_res(chips)"
			("LOCATION" "R1780")
		)
		("@s9s_mb_2u_lib.s9s_mb_2u(sch_1):page569_i74@pure_quanta.q_res(chips)"
			("LOCATION" "R1781")
		)
		("@s9s_mb_2u_lib.s9s_mb_2u(sch_1):page569_i71@pure_quanta.q_res(chips)"
			("LOCATION" "R1782")
		)
		("@s9s_mb_2u_lib.s9s_mb_2u(sch_1):page569_i75@pure_quanta.q_res(chips)"
			("LOCATION" "R1783")
		)
		("@s9s_mb_2u_lib.s9s_mb_2u(sch_1):page569_i61@pure_quanta.q_res(chips)"
			("LOCATION" "R1834")
		)
		("@s9s_mb_2u_lib.s9s_mb_2u(sch_1):page569_i65@pure_quanta.q_res(chips)"
			("LOCATION" "R1835")
		)
		("@s9s_mb_2u_lib.s9s_mb_2u(sch_1):page569_i63@pure_quanta.q_res(chips)"
			("LOCATION" "R1836")
		)
		("@s9s_mb_2u_lib.s9s_mb_2u(sch_1):page569_i81@pure_quanta.q_res(chips)"
			("LOCATION" "R1940")
		)
		("@s9s_mb_2u_lib.s9s_mb_2u(sch_1):page569_i84@pure_quanta.q_res(chips)"
			("LOCATION" "R1941")
		)
		("@s9s_mb_2u_lib.s9s_mb_2u(sch_1):page569_i51@pure_quanta.mosfet_n(chips)"
			("LOCATION" "U19")
		)
		("@s9s_mb_2u_lib.s9s_mb_2u(sch_1):page611_i1@pure_quanta.delta_l(chips)"
			("LOCATION" "J63")
		)
		("@s9s_mb_2u_lib.s9s_mb_2u(sch_1):page611_i5@pure_quanta.delta_l(chips)"
			("LOCATION" "J64")
		)
		("@s9s_mb_2u_lib.s9s_mb_2u(sch_1):page611_i10@pure_quanta.delta_l(chips)"
			("LOCATION" "J65")
		)
		("@s9s_mb_2u_lib.s9s_mb_2u(sch_1):page611_i9@pure_quanta.delta_l(chips)"
			("LOCATION" "J66")
		)
		("@s9s_mb_2u_lib.s9s_mb_2u(sch_1):page611_i24@pure_quanta.delta_l(chips)"
			("LOCATION" "J67")
		)
		("@s9s_mb_2u_lib.s9s_mb_2u(sch_1):page611_i31@pure_quanta.delta_l(chips)"
			("LOCATION" "J68")
		)
		("@s9s_mb_2u_lib.s9s_mb_2u(sch_1):page611_i60@pure_quanta.delta_l(chips)"
			("LOCATION" "J69")
		)
		("@s9s_mb_2u_lib.s9s_mb_2u(sch_1):page611_i61@pure_quanta.delta_l(chips)"
			("LOCATION" "J70")
		)
		("@s9s_mb_2u_lib.s9s_mb_2u(sch_1):page611_i62@pure_quanta.delta_l(chips)"
			("LOCATION" "J71")
		)
		("@s9s_mb_2u_lib.s9s_mb_2u(sch_1):page611_i63@pure_quanta.delta_l(chips)"
			("LOCATION" "J72")
		)
		("@s9s_mb_2u_lib.s9s_mb_2u(sch_1):page611_i64@pure_quanta.delta_l(chips)"
			("LOCATION" "J73")
		)
		("@s9s_mb_2u_lib.s9s_mb_2u(sch_1):page611_i65@pure_quanta.delta_l(chips)"
			("LOCATION" "J74")
		)
		("@s9s_mb_2u_lib.s9s_mb_2u(sch_1):page611_i34@pure_quanta.delta_l(chips)"
			("LOCATION" "J75")
		)
		("@s9s_mb_2u_lib.s9s_mb_2u(sch_1):page611_i33@pure_quanta.delta_l(chips)"
			("LOCATION" "J76")
		)
		("@s9s_mb_2u_lib.s9s_mb_2u(sch_1):page611_i50@pure_quanta.delta_l(chips)"
			("LOCATION" "J77")
		)
		("@s9s_mb_2u_lib.s9s_mb_2u(sch_1):page611_i52@pure_quanta.delta_l(chips)"
			("LOCATION" "J78")
		)
		("@s9s_mb_2u_lib.s9s_mb_2u(sch_1):page611_i56@pure_quanta.delta_l(chips)"
			("LOCATION" "J79")
		)
		("@s9s_mb_2u_lib.s9s_mb_2u(sch_1):page611_i32@pure_quanta.delta_l(chips)"
			("LOCATION" "J80")
		)
		("@s9s_mb_2u_lib.s9s_mb_2u(sch_1):page611_i71@pure_quanta.delta_l(chips)"
			("LOCATION" "J81")
		)
		("@s9s_mb_2u_lib.s9s_mb_2u(sch_1):page611_i70@pure_quanta.delta_l(chips)"
			("LOCATION" "J82")
		)
		("@s9s_mb_2u_lib.s9s_mb_2u(sch_1):page611_i69@pure_quanta.delta_l(chips)"
			("LOCATION" "J83")
		)
		("@s9s_mb_2u_lib.s9s_mb_2u(sch_1):page611_i68@pure_quanta.delta_l(chips)"
			("LOCATION" "J84")
		)
		("@s9s_mb_2u_lib.s9s_mb_2u(sch_1):page611_i67@pure_quanta.delta_l(chips)"
			("LOCATION" "J85")
		)
		("@s9s_mb_2u_lib.s9s_mb_2u(sch_1):page611_i66@pure_quanta.delta_l(chips)"
			("LOCATION" "J86")
		)
		("@s9s_mb_2u_lib.s9s_mb_2u(sch_1):page583_i10@pure_quanta.conn3_210hp1030br1(chips)"
			("LOCATION" "JP1")
		)
		("@s9s_mb_2u_lib.s9s_mb_2u(sch_1):page583_i150@pure_quanta.q_cap(chips)"
			("LOCATION" "PC327")
		)
		("@s9s_mb_2u_lib.s9s_mb_2u(sch_1):page583_i151@pure_quanta.q_cap(chips)"
			("LOCATION" "PC328")
		)
		("@s9s_mb_2u_lib.s9s_mb_2u(sch_1):page583_i20@pure_quanta.q_cap(chips)"
			("LOCATION" "PC329")
		)
		("@s9s_mb_2u_lib.s9s_mb_2u(sch_1):page583_i38@pure_quanta.q_cap(chips)"
			("LOCATION" "PC330")
		)
		("@s9s_mb_2u_lib.s9s_mb_2u(sch_1):page583_i128@pure_quanta.q_cap(chips)"
			("LOCATION" "PC332")
		)
		("@s9s_mb_2u_lib.s9s_mb_2u(sch_1):page583_i130@pure_quanta.q_cap(chips)"
			("LOCATION" "PC333")
		)
		("@s9s_mb_2u_lib.s9s_mb_2u(sch_1):page583_i94@pure_quanta.q_cap(chips)"
			("LOCATION" "PC334")
		)
		("@s9s_mb_2u_lib.s9s_mb_2u(sch_1):page583_i96@pure_quanta.q_cap(chips)"
			("LOCATION" "PC337")
		)
		("@s9s_mb_2u_lib.s9s_mb_2u(sch_1):page583_i115@pure_quanta.q_cap(chips)"
			("LOCATION" "PC1173")
		)
		("@s9s_mb_2u_lib.s9s_mb_2u(sch_1):page583_i33@pure_quanta.q_short(chips)"
			("LOCATION" "PJ47")
		)
		("@s9s_mb_2u_lib.s9s_mb_2u(sch_1):page583_i154@pure_quanta.q_res(chips)"
			("LOCATION" "PR156")
		)
		("@s9s_mb_2u_lib.s9s_mb_2u(sch_1):page583_i153@pure_quanta.q_res(chips)"
			("LOCATION" "PR157")
		)
		("@s9s_mb_2u_lib.s9s_mb_2u(sch_1):page583_i1@pure_quanta.q_res(chips)"
			("LOCATION" "PR158")
		)
		("@s9s_mb_2u_lib.s9s_mb_2u(sch_1):page583_i25@pure_quanta.q_res(chips)"
			("LOCATION" "PR159")
		)
		("@s9s_mb_2u_lib.s9s_mb_2u(sch_1):page583_i126@pure_quanta.q_res(chips)"
			("LOCATION" "PR160")
		)
		("@s9s_mb_2u_lib.s9s_mb_2u(sch_1):page583_i123@pure_quanta.q_res(chips)"
			("LOCATION" "PR161")
		)
		("@s9s_mb_2u_lib.s9s_mb_2u(sch_1):page583_i122@pure_quanta.q_res(chips)"
			("LOCATION" "PR162")
		)
		("@s9s_mb_2u_lib.s9s_mb_2u(sch_1):page583_i52@pure_quanta.q_res(chips)"
			("LOCATION" "PR163")
		)
		("@s9s_mb_2u_lib.s9s_mb_2u(sch_1):page583_i120@pure_quanta.q_res(chips)"
			("LOCATION" "PR164")
		)
		("@s9s_mb_2u_lib.s9s_mb_2u(sch_1):page583_i121@pure_quanta.q_res(chips)"
			("LOCATION" "PR165")
		)
		("@s9s_mb_2u_lib.s9s_mb_2u(sch_1):page583_i37@pure_quanta.q_res(chips)"
			("LOCATION" "PR166")
		)
		("@s9s_mb_2u_lib.s9s_mb_2u(sch_1):page583_i132@pure_quanta.q_res(chips)"
			("LOCATION" "PR167")
		)
		("@s9s_mb_2u_lib.s9s_mb_2u(sch_1):page583_i133@pure_quanta.q_res(chips)"
			("LOCATION" "PR168")
		)
		("@s9s_mb_2u_lib.s9s_mb_2u(sch_1):page583_i34@pure_quanta.q_res(chips)"
			("LOCATION" "PR169")
		)
		("@s9s_mb_2u_lib.s9s_mb_2u(sch_1):page583_i134@pure_quanta.q_res(chips)"
			("LOCATION" "PR170")
		)
		("@s9s_mb_2u_lib.s9s_mb_2u(sch_1):page583_i35@pure_quanta.q_res(chips)"
			("LOCATION" "PR172")
		)
		("@s9s_mb_2u_lib.s9s_mb_2u(sch_1):page583_i187@pure_quanta.q_res(chips)"
			("LOCATION" "PR174")
		)
		("@s9s_mb_2u_lib.s9s_mb_2u(sch_1):page583_i100@pure_quanta.q_res(chips)"
			("LOCATION" "PR176")
		)
		("@s9s_mb_2u_lib.s9s_mb_2u(sch_1):page583_i82@pure_quanta.q_res(chips)"
			("LOCATION" "PR177")
		)
		("@s9s_mb_2u_lib.s9s_mb_2u(sch_1):page583_i136@pure_quanta.q_res(chips)"
			("LOCATION" "PR527")
		)
		("@s9s_mb_2u_lib.s9s_mb_2u(sch_1):page583_i143@pure_quanta.q_res(chips)"
			("LOCATION" "PR528")
		)
		("@s9s_mb_2u_lib.s9s_mb_2u(sch_1):page583_i141@pure_quanta.q_res(chips)"
			("LOCATION" "PR529")
		)
		("@s9s_mb_2u_lib.s9s_mb_2u(sch_1):page583_i147@pure_quanta.q_res(chips)"
			("LOCATION" "PR530")
		)
		("@s9s_mb_2u_lib.s9s_mb_2u(sch_1):page583_i138@pure_quanta.q_res(chips)"
			("LOCATION" "PR531")
		)
		("@s9s_mb_2u_lib.s9s_mb_2u(sch_1):page583_i171@pure_quanta.q_res(chips)"
			("LOCATION" "R541")
		)
		("@s9s_mb_2u_lib.s9s_mb_2u(sch_1):page583_i176@pure_quanta.q_res(chips)"
			("LOCATION" "R1712")
		)
		("@s9s_mb_2u_lib.s9s_mb_2u(sch_1):page583_i177@pure_quanta.q_res(chips)"
			("LOCATION" "R1713")
		)
		("@s9s_mb_2u_lib.s9s_mb_2u(sch_1):page583_i183@pure_quanta.q_res(chips)"
			("LOCATION" "R1714")
		)
		("@s9s_mb_2u_lib.s9s_mb_2u(sch_1):page583_i182@pure_quanta.q_res(chips)"
			("LOCATION" "R1715")
		)
		("@s9s_mb_2u_lib.s9s_mb_2u(sch_1):page489_i85@pure_quanta.conn3_210hp1030br1(chips)"
			("LOCATION" "JP7")
		)
		("@s9s_mb_2u_lib.s9s_mb_2u(sch_1):page489_i53@pure_quanta.mosfet_nch_dual(chips)"
			("LOCATION" "Q15")
		)
		("@s9s_mb_2u_lib.s9s_mb_2u(sch_1):page489_i76@pure_quanta.mosfet_nch_dual(chips)"
			("LOCATION" "Q15")
		)
		("@s9s_mb_2u_lib.s9s_mb_2u(sch_1):page489_i73@pure_quanta.mosfet_nch_dual(chips)"
			("LOCATION" "Q16")
		)
		("@s9s_mb_2u_lib.s9s_mb_2u(sch_1):page489_i75@pure_quanta.mosfet_nch_dual(chips)"
			("LOCATION" "Q16")
		)
		("@s9s_mb_2u_lib.s9s_mb_2u(sch_1):page489_i20@pure_quanta.q_res(chips)"
			("LOCATION" "R331")
		)
		("@s9s_mb_2u_lib.s9s_mb_2u(sch_1):page489_i21@pure_quanta.q_res(chips)"
			("LOCATION" "R332")
		)
		("@s9s_mb_2u_lib.s9s_mb_2u(sch_1):page489_i6@pure_quanta.q_res(chips)"
			("LOCATION" "R333")
		)
		("@s9s_mb_2u_lib.s9s_mb_2u(sch_1):page489_i1@pure_quanta.q_res(chips)"
			("LOCATION" "R334")
		)
		("@s9s_mb_2u_lib.s9s_mb_2u(sch_1):page489_i5@pure_quanta.q_res(chips)"
			("LOCATION" "R335")
		)
		("@s9s_mb_2u_lib.s9s_mb_2u(sch_1):page489_i7@pure_quanta.q_res(chips)"
			("LOCATION" "R515")
		)
		("@s9s_mb_2u_lib.s9s_mb_2u(sch_1):page489_i24@pure_quanta.q_res(chips)"
			("LOCATION" "R625")
		)
		("@s9s_mb_2u_lib.s9s_mb_2u(sch_1):page489_i26@pure_quanta.q_res(chips)"
			("LOCATION" "R626")
		)
		("@s9s_mb_2u_lib.s9s_mb_2u(sch_1):page489_i14@pure_quanta.q_res(chips)"
			("LOCATION" "R627")
		)
		("@s9s_mb_2u_lib.s9s_mb_2u(sch_1):page489_i17@pure_quanta.q_res(chips)"
			("LOCATION" "R628")
		)
		("@s9s_mb_2u_lib.s9s_mb_2u(sch_1):page489_i13@pure_quanta.q_res(chips)"
			("LOCATION" "R629")
		)
		("@s9s_mb_2u_lib.s9s_mb_2u(sch_1):page489_i15@pure_quanta.q_res(chips)"
			("LOCATION" "R630")
		)
		("@s9s_mb_2u_lib.s9s_mb_2u(sch_1):page489_i32@pure_quanta.q_res(chips)"
			("LOCATION" "R650")
		)
		("@s9s_mb_2u_lib.s9s_mb_2u(sch_1):page489_i31@pure_quanta.q_res(chips)"
			("LOCATION" "R997")
		)
		("@s9s_mb_2u_lib.s9s_mb_2u(sch_1):page489_i59@pure_quanta.q_res(chips)"
			("LOCATION" "R998")
		)
		("@s9s_mb_2u_lib.s9s_mb_2u(sch_1):page489_i70@pure_quanta.q_res(chips)"
			("LOCATION" "R999")
		)
		("@s9s_mb_2u_lib.s9s_mb_2u(sch_1):page489_i57@pure_quanta.q_res(chips)"
			("LOCATION" "R1000")
		)
		("@s9s_mb_2u_lib.s9s_mb_2u(sch_1):page489_i69@pure_quanta.q_res(chips)"
			("LOCATION" "R1001")
		)
		("@s9s_mb_2u_lib.s9s_mb_2u(sch_1):page489_i51@pure_quanta.q_res(chips)"
			("LOCATION" "R1002")
		)
		("@s9s_mb_2u_lib.s9s_mb_2u(sch_1):page489_i68@pure_quanta.q_res(chips)"
			("LOCATION" "R1003")
		)
		("@s9s_mb_2u_lib.s9s_mb_2u(sch_1):page489_i35@pure_quanta.q_res(chips)"
			("LOCATION" "R1004")
		)
		("@s9s_mb_2u_lib.s9s_mb_2u(sch_1):page489_i36@pure_quanta.q_res(chips)"
			("LOCATION" "R1005")
		)
		("@s9s_mb_2u_lib.s9s_mb_2u(sch_1):page489_i52@pure_quanta.q_res(chips)"
			("LOCATION" "R1006")
		)
		("@s9s_mb_2u_lib.s9s_mb_2u(sch_1):page489_i65@pure_quanta.q_res(chips)"
			("LOCATION" "R1007")
		)
		("@s9s_mb_2u_lib.s9s_mb_2u(sch_1):page518_i86@pure_quanta.conn3_hfk1030g000laf(chips)"
			("LOCATION" "JP8")
		)
		("@s9s_mb_2u_lib.s9s_mb_2u(sch_1):page518_i77@pure_quanta.q_res(chips)"
			("LOCATION" "R453")
		)
		("@s9s_mb_2u_lib.s9s_mb_2u(sch_1):page518_i4@pure_quanta.q_res(chips)"
			("LOCATION" "R494")
		)
		("@s9s_mb_2u_lib.s9s_mb_2u(sch_1):page518_i63@pure_quanta.q_res(chips)"
			("LOCATION" "R696")
		)
		("@s9s_mb_2u_lib.s9s_mb_2u(sch_1):page518_i66@pure_quanta.q_res(chips)"
			("LOCATION" "R697")
		)
		("@s9s_mb_2u_lib.s9s_mb_2u(sch_1):page518_i68@pure_quanta.q_res(chips)"
			("LOCATION" "R989")
		)
		("@s9s_mb_2u_lib.s9s_mb_2u(sch_1):page518_i41@pure_quanta.q_res(chips)"
			("LOCATION" "R1024")
		)
		("@s9s_mb_2u_lib.s9s_mb_2u(sch_1):page518_i38@pure_quanta.q_res(chips)"
			("LOCATION" "R1025")
		)
		("@s9s_mb_2u_lib.s9s_mb_2u(sch_1):page518_i37@pure_quanta.q_res(chips)"
			("LOCATION" "R1026")
		)
		("@s9s_mb_2u_lib.s9s_mb_2u(sch_1):page518_i50@pure_quanta.q_res(chips)"
			("LOCATION" "R1197")
		)
		("@s9s_mb_2u_lib.s9s_mb_2u(sch_1):page518_i48@pure_quanta.q_res(chips)"
			("LOCATION" "R1198")
		)
		("@s9s_mb_2u_lib.s9s_mb_2u(sch_1):page518_i60@pure_quanta.q_res(chips)"
			("LOCATION" "R1200")
		)
		("@s9s_mb_2u_lib.s9s_mb_2u(sch_1):page518_i58@pure_quanta.q_res(chips)"
			("LOCATION" "R1201")
		)
		("@s9s_mb_2u_lib.s9s_mb_2u(sch_1):page518_i75@pure_quanta.q_res(chips)"
			("LOCATION" "R1485")
		)
		("@s9s_mb_2u_lib.s9s_mb_2u(sch_1):page518_i74@pure_quanta.q_res(chips)"
			("LOCATION" "R1486")
		)
		("@s9s_mb_2u_lib.s9s_mb_2u(sch_1):page518_i82@pure_quanta.q_res(chips)"
			("LOCATION" "R1675")
		)
		("@s9s_mb_2u_lib.s9s_mb_2u(sch_1):page518_i94@pure_quanta.q_res(chips)"
			("LOCATION" "R1676")
		)
		("@s9s_mb_2u_lib.s9s_mb_2u(sch_1):page518_i89@pure_quanta.q_res(chips)"
			("LOCATION" "R1736")
		)
		("@s9s_mb_2u_lib.s9s_mb_2u(sch_1):page518_i36@pure_quanta.emmitsburg_rev0p9(chips)"
			("LOCATION" "U4")
		)
		("@s9s_mb_2u_lib.s9s_mb_2u(sch_1):page444_i20@pure_quanta.q_cap(chips)"
			("LOCATION" "PC175")
		)
		("@s9s_mb_2u_lib.s9s_mb_2u(sch_1):page444_i17@pure_quanta.q_cap(chips)"
			("LOCATION" "PC176")
		)
		("@s9s_mb_2u_lib.s9s_mb_2u(sch_1):page444_i16@pure_quanta.q_cap(chips)"
			("LOCATION" "PC177")
		)
		("@s9s_mb_2u_lib.s9s_mb_2u(sch_1):page444_i50@pure_quanta.q_cap(chips)"
			("LOCATION" "PC178")
		)
		("@s9s_mb_2u_lib.s9s_mb_2u(sch_1):page444_i15@pure_quanta.q_cap(chips)"
			("LOCATION" "PC179")
		)
		("@s9s_mb_2u_lib.s9s_mb_2u(sch_1):page444_i14@pure_quanta.q_cap(chips)"
			("LOCATION" "PC180")
		)
		("@s9s_mb_2u_lib.s9s_mb_2u(sch_1):page444_i8@pure_quanta.q_cap(chips)"
			("LOCATION" "PC181")
		)
		("@s9s_mb_2u_lib.s9s_mb_2u(sch_1):page444_i6@pure_quanta.q_cap(chips)"
			("LOCATION" "PC184")
		)
		("@s9s_mb_2u_lib.s9s_mb_2u(sch_1):page444_i5@pure_quanta.q_cap(chips)"
			("LOCATION" "PC186")
		)
		("@s9s_mb_2u_lib.s9s_mb_2u(sch_1):page444_i42@pure_quanta.q_capp(chips)"
			("LOCATION" "PC1900")
		)
		("@s9s_mb_2u_lib.s9s_mb_2u(sch_1):page444_i41@pure_quanta.q_capp(chips)"
			("LOCATION" "PC2180")
		)
		("@s9s_mb_2u_lib.s9s_mb_2u(sch_1):page444_i21@pure_quanta.q_inductor(chips)"
			("LOCATION" "PL3")
		)
		("@s9s_mb_2u_lib.s9s_mb_2u(sch_1):page444_i19@pure_quanta.q_res(chips)"
			("LOCATION" "PR97")
		)
		("@s9s_mb_2u_lib.s9s_mb_2u(sch_1):page444_i52@pure_quanta.q_res(chips)"
			("LOCATION" "PR1709")
		)
		("@s9s_mb_2u_lib.s9s_mb_2u(sch_1):page442_i151@pure_quanta.q_cap(chips)"
			("LOCATION" "PC187")
		)
		("@s9s_mb_2u_lib.s9s_mb_2u(sch_1):page442_i164@pure_quanta.q_cap(chips)"
			("LOCATION" "PC188")
		)
		("@s9s_mb_2u_lib.s9s_mb_2u(sch_1):page442_i111@pure_quanta.q_cap(chips)"
			("LOCATION" "PC189_P0_1")
		)
		("@s9s_mb_2u_lib.s9s_mb_2u(sch_1):page442_i171@pure_quanta.q_cap(chips)"
			("LOCATION" "PC190_P0_2")
		)
		("@s9s_mb_2u_lib.s9s_mb_2u(sch_1):page442_i112@pure_quanta.q_cap(chips)"
			("LOCATION" "PC191_P0_1")
		)
		("@s9s_mb_2u_lib.s9s_mb_2u(sch_1):page442_i170@pure_quanta.q_cap(chips)"
			("LOCATION" "PC192_P0_2")
		)
		("@s9s_mb_2u_lib.s9s_mb_2u(sch_1):page442_i234@pure_quanta.q_cap(chips)"
			("LOCATION" "PC193")
		)
		("@s9s_mb_2u_lib.s9s_mb_2u(sch_1):page442_i235@pure_quanta.q_cap(chips)"
			("LOCATION" "PC194")
		)
		("@s9s_mb_2u_lib.s9s_mb_2u(sch_1):page442_i113@pure_quanta.q_cap(chips)"
			("LOCATION" "PC195_P0_1")
		)
		("@s9s_mb_2u_lib.s9s_mb_2u(sch_1):page442_i172@pure_quanta.q_cap(chips)"
			("LOCATION" "PC196_P0_2")
		)
		("@s9s_mb_2u_lib.s9s_mb_2u(sch_1):page442_i115@pure_quanta.q_cap(chips)"
			("LOCATION" "PC197_P0_1")
		)
		("@s9s_mb_2u_lib.s9s_mb_2u(sch_1):page442_i173@pure_quanta.q_cap(chips)"
			("LOCATION" "PC198_P0_2")
		)
		("@s9s_mb_2u_lib.s9s_mb_2u(sch_1):page442_i105@pure_quanta.q_cap(chips)"
			("LOCATION" "PC199_P0_1")
		)
		("@s9s_mb_2u_lib.s9s_mb_2u(sch_1):page442_i125@pure_quanta.q_cap(chips)"
			("LOCATION" "PC202_P0_1")
		)
		("@s9s_mb_2u_lib.s9s_mb_2u(sch_1):page442_i177@pure_quanta.q_cap(chips)"
			("LOCATION" "PC203_P0_2")
		)
		("@s9s_mb_2u_lib.s9s_mb_2u(sch_1):page442_i126@pure_quanta.q_cap(chips)"
			("LOCATION" "PC204_P0_1")
		)
		("@s9s_mb_2u_lib.s9s_mb_2u(sch_1):page442_i178@pure_quanta.q_cap(chips)"
			("LOCATION" "PC205_P0_2")
		)
		("@s9s_mb_2u_lib.s9s_mb_2u(sch_1):page442_i142@pure_quanta.q_capp(chips)"
			("LOCATION" "PC207")
		)
		("@s9s_mb_2u_lib.s9s_mb_2u(sch_1):page442_i143@pure_quanta.q_capp(chips)"
			("LOCATION" "PC208")
		)
		("@s9s_mb_2u_lib.s9s_mb_2u(sch_1):page442_i214@pure_quanta.q_capp(chips)"
			("LOCATION" "PC1573")
		)
		("@s9s_mb_2u_lib.s9s_mb_2u(sch_1):page442_i211@pure_quanta.q_capp(chips)"
			("LOCATION" "PC1574")
		)
		("@s9s_mb_2u_lib.s9s_mb_2u(sch_1):page442_i219@pure_quanta.q_capp(chips)"
			("LOCATION" "PC1575")
		)
		("@s9s_mb_2u_lib.s9s_mb_2u(sch_1):page442_i212@pure_quanta.q_capp(chips)"
			("LOCATION" "PC1576")
		)
		("@s9s_mb_2u_lib.s9s_mb_2u(sch_1):page442_i213@pure_quanta.q_capp(chips)"
			("LOCATION" "PC1579")
		)
		("@s9s_mb_2u_lib.s9s_mb_2u(sch_1):page442_i150@pure_quanta.q_inductor(chips)"
			("LOCATION" "PL4")
		)
		("@s9s_mb_2u_lib.s9s_mb_2u(sch_1):page442_i182@pure_quanta.q_inductor(chips)"
			("LOCATION" "PL5")
		)
		("@s9s_mb_2u_lib.s9s_mb_2u(sch_1):page442_i141@pure_quanta.q_inductor(chips)"
			("LOCATION" "PL6")
		)
		("@s9s_mb_2u_lib.s9s_mb_2u(sch_1):page442_i154@pure_quanta.q_res(chips)"
			("LOCATION" "PR101")
		)
		("@s9s_mb_2u_lib.s9s_mb_2u(sch_1):page442_i165@pure_quanta.q_res(chips)"
			("LOCATION" "PR102")
		)
		("@s9s_mb_2u_lib.s9s_mb_2u(sch_1):page442_i239@pure_quanta.q_res(chips)"
			("LOCATION" "PR1707")
		)
		("@s9s_mb_2u_lib.s9s_mb_2u(sch_1):page442_i238@pure_quanta.q_res(chips)"
			("LOCATION" "PR1708")
		)
		("@s9s_mb_2u_lib.s9s_mb_2u(sch_1):page435_i153@pure_quanta.q_capp(chips)"
			("LOCATION" "PC189")
		)
		("@s9s_mb_2u_lib.s9s_mb_2u(sch_1):page435_i106@pure_quanta.q_cap(chips)"
			("LOCATION" "PC556")
		)
		("@s9s_mb_2u_lib.s9s_mb_2u(sch_1):page435_i99@pure_quanta.q_cap(chips)"
			("LOCATION" "PC557")
		)
		("@s9s_mb_2u_lib.s9s_mb_2u(sch_1):page435_i110@pure_quanta.q_cap(chips)"
			("LOCATION" "PC558_P1_2")
		)
		("@s9s_mb_2u_lib.s9s_mb_2u(sch_1):page435_i103@pure_quanta.q_cap(chips)"
			("LOCATION" "PC559_P1_1")
		)
		("@s9s_mb_2u_lib.s9s_mb_2u(sch_1):page435_i127@pure_quanta.q_cap(chips)"
			("LOCATION" "PC560_P1_2")
		)
		("@s9s_mb_2u_lib.s9s_mb_2u(sch_1):page435_i38@pure_quanta.q_cap(chips)"
			("LOCATION" "PC561_P1_1")
		)
		("@s9s_mb_2u_lib.s9s_mb_2u(sch_1):page435_i126@pure_quanta.q_cap(chips)"
			("LOCATION" "PC562_P1_2")
		)
		("@s9s_mb_2u_lib.s9s_mb_2u(sch_1):page435_i39@pure_quanta.q_cap(chips)"
			("LOCATION" "PC563_P1_1")
		)
		("@s9s_mb_2u_lib.s9s_mb_2u(sch_1):page435_i157@pure_quanta.q_cap(chips)"
			("LOCATION" "PC564")
		)
		("@s9s_mb_2u_lib.s9s_mb_2u(sch_1):page435_i162@pure_quanta.q_cap(chips)"
			("LOCATION" "PC565")
		)
		("@s9s_mb_2u_lib.s9s_mb_2u(sch_1):page435_i125@pure_quanta.q_cap(chips)"
			("LOCATION" "PC566_P1_2")
		)
		("@s9s_mb_2u_lib.s9s_mb_2u(sch_1):page435_i41@pure_quanta.q_cap(chips)"
			("LOCATION" "PC567_P1_1")
		)
		("@s9s_mb_2u_lib.s9s_mb_2u(sch_1):page435_i123@pure_quanta.q_cap(chips)"
			("LOCATION" "PC568_P1_2")
		)
		("@s9s_mb_2u_lib.s9s_mb_2u(sch_1):page435_i42@pure_quanta.q_cap(chips)"
			("LOCATION" "PC569_P1_1")
		)
		("@s9s_mb_2u_lib.s9s_mb_2u(sch_1):page435_i122@pure_quanta.q_cap(chips)"
			("LOCATION" "PC570_P1_2")
		)
		("@s9s_mb_2u_lib.s9s_mb_2u(sch_1):page435_i68@pure_quanta.q_cap(chips)"
			("LOCATION" "PC571_P1_1")
		)
		("@s9s_mb_2u_lib.s9s_mb_2u(sch_1):page435_i32@pure_quanta.q_cap(chips)"
			("LOCATION" "PC572_P1_1")
		)
		("@s9s_mb_2u_lib.s9s_mb_2u(sch_1):page435_i52@pure_quanta.q_cap(chips)"
			("LOCATION" "PC574_P1_1")
		)
		("@s9s_mb_2u_lib.s9s_mb_2u(sch_1):page435_i119@pure_quanta.q_cap(chips)"
			("LOCATION" "PC575_P1_2")
		)
		("@s9s_mb_2u_lib.s9s_mb_2u(sch_1):page435_i53@pure_quanta.q_cap(chips)"
			("LOCATION" "PC576_P1_1")
		)
		("@s9s_mb_2u_lib.s9s_mb_2u(sch_1):page435_i131@pure_quanta.q_cap(chips)"
			("LOCATION" "PC577_P1_2")
		)
		("@s9s_mb_2u_lib.s9s_mb_2u(sch_1):page435_i54@pure_quanta.q_cap(chips)"
			("LOCATION" "PC578_P1_1")
		)
		("@s9s_mb_2u_lib.s9s_mb_2u(sch_1):page435_i73@pure_quanta.q_capp(chips)"
			("LOCATION" "PC579")
		)
		("@s9s_mb_2u_lib.s9s_mb_2u(sch_1):page435_i56@pure_quanta.q_capp(chips)"
			("LOCATION" "PC580")
		)
		("@s9s_mb_2u_lib.s9s_mb_2u(sch_1):page435_i74@pure_quanta.q_capp(chips)"
			("LOCATION" "PC582")
		)
		("@s9s_mb_2u_lib.s9s_mb_2u(sch_1):page435_i63@pure_quanta.q_capp(chips)"
			("LOCATION" "PC583")
		)
		("@s9s_mb_2u_lib.s9s_mb_2u(sch_1):page435_i75@pure_quanta.q_capp(chips)"
			("LOCATION" "PC585")
		)
		("@s9s_mb_2u_lib.s9s_mb_2u(sch_1):page435_i65@pure_quanta.q_capp(chips)"
			("LOCATION" "PC586")
		)
		("@s9s_mb_2u_lib.s9s_mb_2u(sch_1):page435_i59@pure_quanta.q_capp(chips)"
			("LOCATION" "PC587")
		)
		("@s9s_mb_2u_lib.s9s_mb_2u(sch_1):page435_i77@pure_quanta.q_capp(chips)"
			("LOCATION" "PC588")
		)
		("@s9s_mb_2u_lib.s9s_mb_2u(sch_1):page435_i66@pure_quanta.q_capp(chips)"
			("LOCATION" "PC589")
		)
		("@s9s_mb_2u_lib.s9s_mb_2u(sch_1):page435_i60@pure_quanta.q_capp(chips)"
			("LOCATION" "PC590")
		)
		("@s9s_mb_2u_lib.s9s_mb_2u(sch_1):page435_i163@pure_quanta.q_capp(chips)"
			("LOCATION" "PC1990")
		)
		("@s9s_mb_2u_lib.s9s_mb_2u(sch_1):page435_i128@pure_quanta.q_inductor(chips)"
			("LOCATION" "PL30")
		)
		("@s9s_mb_2u_lib.s9s_mb_2u(sch_1):page435_i40@pure_quanta.q_inductor(chips)"
			("LOCATION" "PL31")
		)
		("@s9s_mb_2u_lib.s9s_mb_2u(sch_1):page435_i72@pure_quanta.q_inductor(chips)"
			("LOCATION" "PL32")
		)
		("@s9s_mb_2u_lib.s9s_mb_2u(sch_1):page435_i113@pure_quanta.q_res(chips)"
			("LOCATION" "PR325")
		)
		("@s9s_mb_2u_lib.s9s_mb_2u(sch_1):page435_i93@pure_quanta.q_res(chips)"
			("LOCATION" "PR326")
		)
		("@s9s_mb_2u_lib.s9s_mb_2u(sch_1):page435_i107@pure_quanta.q_res(chips)"
			("LOCATION" "PR327")
		)
		("@s9s_mb_2u_lib.s9s_mb_2u(sch_1):page435_i100@pure_quanta.q_res(chips)"
			("LOCATION" "PR328")
		)
		("@s9s_mb_2u_lib.s9s_mb_2u(sch_1):page440_i318@pure_quanta.q_cap(chips)"
			("LOCATION" "PC214")
		)
		("@s9s_mb_2u_lib.s9s_mb_2u(sch_1):page440_i218@pure_quanta.q_cap(chips)"
			("LOCATION" "PC217")
		)
		("@s9s_mb_2u_lib.s9s_mb_2u(sch_1):page440_i219@pure_quanta.q_cap(chips)"
			("LOCATION" "PC218")
		)
		("@s9s_mb_2u_lib.s9s_mb_2u(sch_1):page440_i302@pure_quanta.q_cap(chips)"
			("LOCATION" "PC219")
		)
		("@s9s_mb_2u_lib.s9s_mb_2u(sch_1):page440_i307@pure_quanta.q_cap(chips)"
			("LOCATION" "PC220")
		)
		("@s9s_mb_2u_lib.s9s_mb_2u(sch_1):page440_i313@pure_quanta.q_cap(chips)"
			("LOCATION" "PC221")
		)
		("@s9s_mb_2u_lib.s9s_mb_2u(sch_1):page440_i333@pure_quanta.q_cap(chips)"
			("LOCATION" "PC223")
		)
		("@s9s_mb_2u_lib.s9s_mb_2u(sch_1):page440_i334@pure_quanta.q_cap(chips)"
			("LOCATION" "PC225")
		)
		("@s9s_mb_2u_lib.s9s_mb_2u(sch_1):page440_i339@pure_quanta.q_cap(chips)"
			("LOCATION" "PC1372")
		)
		("@s9s_mb_2u_lib.s9s_mb_2u(sch_1):page440_i253@pure_quanta.q_short(chips)"
			("LOCATION" "PJ45")
		)
		("@s9s_mb_2u_lib.s9s_mb_2u(sch_1):page440_i262@pure_quanta.q_short(chips)"
			("LOCATION" "PJ46")
		)
		("@s9s_mb_2u_lib.s9s_mb_2u(sch_1):page440_i322@pure_quanta.q_res(chips)"
			("LOCATION" "PR105")
		)
		("@s9s_mb_2u_lib.s9s_mb_2u(sch_1):page440_i320@pure_quanta.q_res(chips)"
			("LOCATION" "PR107")
		)
		("@s9s_mb_2u_lib.s9s_mb_2u(sch_1):page440_i314@pure_quanta.q_res(chips)"
			("LOCATION" "PR108")
		)
		("@s9s_mb_2u_lib.s9s_mb_2u(sch_1):page440_i216@pure_quanta.q_res(chips)"
			("LOCATION" "PR109")
		)
		("@s9s_mb_2u_lib.s9s_mb_2u(sch_1):page440_i215@pure_quanta.q_res(chips)"
			("LOCATION" "PR110")
		)
		("@s9s_mb_2u_lib.s9s_mb_2u(sch_1):page440_i214@pure_quanta.q_res(chips)"
			("LOCATION" "PR111")
		)
		("@s9s_mb_2u_lib.s9s_mb_2u(sch_1):page440_i222@pure_quanta.q_res(chips)"
			("LOCATION" "PR112")
		)
		("@s9s_mb_2u_lib.s9s_mb_2u(sch_1):page440_i223@pure_quanta.q_res(chips)"
			("LOCATION" "PR113")
		)
		("@s9s_mb_2u_lib.s9s_mb_2u(sch_1):page440_i213@pure_quanta.q_res(chips)"
			("LOCATION" "PR114")
		)
		("@s9s_mb_2u_lib.s9s_mb_2u(sch_1):page440_i226@pure_quanta.q_res(chips)"
			("LOCATION" "PR115")
		)
		("@s9s_mb_2u_lib.s9s_mb_2u(sch_1):page440_i227@pure_quanta.q_res(chips)"
			("LOCATION" "PR116")
		)
		("@s9s_mb_2u_lib.s9s_mb_2u(sch_1):page440_i306@pure_quanta.q_res(chips)"
			("LOCATION" "PR117")
		)
		("@s9s_mb_2u_lib.s9s_mb_2u(sch_1):page440_i304@pure_quanta.q_res(chips)"
			("LOCATION" "PR118")
		)
		("@s9s_mb_2u_lib.s9s_mb_2u(sch_1):page440_i301@pure_quanta.q_res(chips)"
			("LOCATION" "PR119")
		)
		("@s9s_mb_2u_lib.s9s_mb_2u(sch_1):page440_i250@pure_quanta.q_res(chips)"
			("LOCATION" "PR120")
		)
		("@s9s_mb_2u_lib.s9s_mb_2u(sch_1):page440_i259@pure_quanta.q_res(chips)"
			("LOCATION" "PR121")
		)
		("@s9s_mb_2u_lib.s9s_mb_2u(sch_1):page440_i317@pure_quanta.q_res(chips)"
			("LOCATION" "PR122")
		)
		("@s9s_mb_2u_lib.s9s_mb_2u(sch_1):page440_i316@pure_quanta.q_res(chips)"
			("LOCATION" "PR123")
		)
		("@s9s_mb_2u_lib.s9s_mb_2u(sch_1):page440_i335@pure_quanta.q_res(chips)"
			("LOCATION" "PR130")
		)
		("@s9s_mb_2u_lib.s9s_mb_2u(sch_1):page440_i386@pure_quanta.q_res(chips)"
			("LOCATION" "PR131")
		)
		("@s9s_mb_2u_lib.s9s_mb_2u(sch_1):page440_i256@pure_quanta.q_res(chips)"
			("LOCATION" "PR519")
		)
		("@s9s_mb_2u_lib.s9s_mb_2u(sch_1):page440_i265@pure_quanta.q_res(chips)"
			("LOCATION" "PR520")
		)
		("@s9s_mb_2u_lib.s9s_mb_2u(sch_1):page440_i252@pure_quanta.q_res(chips)"
			("LOCATION" "PR521")
		)
		("@s9s_mb_2u_lib.s9s_mb_2u(sch_1):page440_i261@pure_quanta.q_res(chips)"
			("LOCATION" "PR522")
		)
		("@s9s_mb_2u_lib.s9s_mb_2u(sch_1):page440_i297@pure_quanta.q_res(chips)"
			("LOCATION" "PR523")
		)
		("@s9s_mb_2u_lib.s9s_mb_2u(sch_1):page440_i298@pure_quanta.q_res(chips)"
			("LOCATION" "PR524")
		)
		("@s9s_mb_2u_lib.s9s_mb_2u(sch_1):page440_i411@pure_quanta.q_res(chips)"
			("LOCATION" "R561")
		)
		("@s9s_mb_2u_lib.s9s_mb_2u(sch_1):page440_i409@pure_quanta.q_res(chips)"
			("LOCATION" "R1766")
		)
		("@s9s_mb_2u_lib.s9s_mb_2u(sch_1):page438_i9@pure_quanta.q_cap(chips)"
			("LOCATION" "PC226")
		)
		("@s9s_mb_2u_lib.s9s_mb_2u(sch_1):page438_i21@pure_quanta.q_cap(chips)"
			("LOCATION" "PC227")
		)
		("@s9s_mb_2u_lib.s9s_mb_2u(sch_1):page438_i11@pure_quanta.q_cap(chips)"
			("LOCATION" "PC228_P0_8")
		)
		("@s9s_mb_2u_lib.s9s_mb_2u(sch_1):page438_i23@pure_quanta.q_cap(chips)"
			("LOCATION" "PC229_P0_7")
		)
		("@s9s_mb_2u_lib.s9s_mb_2u(sch_1):page438_i29@pure_quanta.q_cap(chips)"
			("LOCATION" "PC230_P0_8")
		)
		("@s9s_mb_2u_lib.s9s_mb_2u(sch_1):page438_i44@pure_quanta.q_cap(chips)"
			("LOCATION" "PC231_P0_7")
		)
		("@s9s_mb_2u_lib.s9s_mb_2u(sch_1):page438_i30@pure_quanta.q_cap(chips)"
			("LOCATION" "PC232_P0_8")
		)
		("@s9s_mb_2u_lib.s9s_mb_2u(sch_1):page438_i46@pure_quanta.q_cap(chips)"
			("LOCATION" "PC233_P0_7")
		)
		("@s9s_mb_2u_lib.s9s_mb_2u(sch_1):page438_i81@pure_quanta.q_cap(chips)"
			("LOCATION" "PC234")
		)
		("@s9s_mb_2u_lib.s9s_mb_2u(sch_1):page438_i80@pure_quanta.q_cap(chips)"
			("LOCATION" "PC235")
		)
		("@s9s_mb_2u_lib.s9s_mb_2u(sch_1):page438_i33@pure_quanta.q_cap(chips)"
			("LOCATION" "PC236_P0_8")
		)
		("@s9s_mb_2u_lib.s9s_mb_2u(sch_1):page438_i49@pure_quanta.q_cap(chips)"
			("LOCATION" "PC237_P0_7")
		)
		("@s9s_mb_2u_lib.s9s_mb_2u(sch_1):page438_i34@pure_quanta.q_cap(chips)"
			("LOCATION" "PC238_P0_8")
		)
		("@s9s_mb_2u_lib.s9s_mb_2u(sch_1):page438_i50@pure_quanta.q_cap(chips)"
			("LOCATION" "PC239_P0_7")
		)
		("@s9s_mb_2u_lib.s9s_mb_2u(sch_1):page438_i35@pure_quanta.q_cap(chips)"
			("LOCATION" "PC240_P0_8")
		)
		("@s9s_mb_2u_lib.s9s_mb_2u(sch_1):page438_i51@pure_quanta.q_cap(chips)"
			("LOCATION" "PC241_P0_7")
		)
		("@s9s_mb_2u_lib.s9s_mb_2u(sch_1):page438_i37@pure_quanta.q_cap(chips)"
			("LOCATION" "PC242_P0_8")
		)
		("@s9s_mb_2u_lib.s9s_mb_2u(sch_1):page438_i52@pure_quanta.q_cap(chips)"
			("LOCATION" "PC243_P0_7")
		)
		("@s9s_mb_2u_lib.s9s_mb_2u(sch_1):page438_i39@pure_quanta.q_cap(chips)"
			("LOCATION" "PC244_P0_8")
		)
		("@s9s_mb_2u_lib.s9s_mb_2u(sch_1):page438_i53@pure_quanta.q_cap(chips)"
			("LOCATION" "PC245_P0_7")
		)
		("@s9s_mb_2u_lib.s9s_mb_2u(sch_1):page438_i41@pure_quanta.q_cap(chips)"
			("LOCATION" "PC246_P0_8")
		)
		("@s9s_mb_2u_lib.s9s_mb_2u(sch_1):page438_i55@pure_quanta.q_cap(chips)"
			("LOCATION" "PC247_P0_7")
		)
		("@s9s_mb_2u_lib.s9s_mb_2u(sch_1):page438_i32@pure_quanta.q_inductor(chips)"
			("LOCATION" "PL7")
		)
		("@s9s_mb_2u_lib.s9s_mb_2u(sch_1):page438_i48@pure_quanta.q_inductor(chips)"
			("LOCATION" "PL8")
		)
		("@s9s_mb_2u_lib.s9s_mb_2u(sch_1):page438_i85@pure_quanta.q_res(chips)"
			("LOCATION" "PR132")
		)
		("@s9s_mb_2u_lib.s9s_mb_2u(sch_1):page438_i84@pure_quanta.q_res(chips)"
			("LOCATION" "PR133")
		)
		("@s9s_mb_2u_lib.s9s_mb_2u(sch_1):page438_i10@pure_quanta.q_res(chips)"
			("LOCATION" "PR134")
		)
		("@s9s_mb_2u_lib.s9s_mb_2u(sch_1):page438_i22@pure_quanta.q_res(chips)"
			("LOCATION" "PR135")
		)
		("@s9s_mb_2u_lib.s9s_mb_2u(sch_1):page437_i18@pure_quanta.q_cap(chips)"
			("LOCATION" "PC248")
		)
		("@s9s_mb_2u_lib.s9s_mb_2u(sch_1):page437_i31@pure_quanta.q_cap(chips)"
			("LOCATION" "PC249")
		)
		("@s9s_mb_2u_lib.s9s_mb_2u(sch_1):page437_i26@pure_quanta.q_cap(chips)"
			("LOCATION" "PC250_P0_6")
		)
		("@s9s_mb_2u_lib.s9s_mb_2u(sch_1):page437_i35@pure_quanta.q_cap(chips)"
			("LOCATION" "PC251_P0_5")
		)
		("@s9s_mb_2u_lib.s9s_mb_2u(sch_1):page437_i37@pure_quanta.q_cap(chips)"
			("LOCATION" "PC252_P0_6")
		)
		("@s9s_mb_2u_lib.s9s_mb_2u(sch_1):page437_i43@pure_quanta.q_cap(chips)"
			("LOCATION" "PC253_P0_5")
		)
		("@s9s_mb_2u_lib.s9s_mb_2u(sch_1):page437_i38@pure_quanta.q_cap(chips)"
			("LOCATION" "PC254_P0_6")
		)
		("@s9s_mb_2u_lib.s9s_mb_2u(sch_1):page437_i44@pure_quanta.q_cap(chips)"
			("LOCATION" "PC255_P0_5")
		)
		("@s9s_mb_2u_lib.s9s_mb_2u(sch_1):page437_i80@pure_quanta.q_cap(chips)"
			("LOCATION" "PC256")
		)
		("@s9s_mb_2u_lib.s9s_mb_2u(sch_1):page437_i79@pure_quanta.q_cap(chips)"
			("LOCATION" "PC257")
		)
		("@s9s_mb_2u_lib.s9s_mb_2u(sch_1):page437_i39@pure_quanta.q_cap(chips)"
			("LOCATION" "PC258_P0_6")
		)
		("@s9s_mb_2u_lib.s9s_mb_2u(sch_1):page437_i45@pure_quanta.q_cap(chips)"
			("LOCATION" "PC259_P0_5")
		)
		("@s9s_mb_2u_lib.s9s_mb_2u(sch_1):page437_i46@pure_quanta.q_cap(chips)"
			("LOCATION" "PC260_P0_6")
		)
		("@s9s_mb_2u_lib.s9s_mb_2u(sch_1):page437_i51@pure_quanta.q_cap(chips)"
			("LOCATION" "PC261_P0_5")
		)
		("@s9s_mb_2u_lib.s9s_mb_2u(sch_1):page437_i47@pure_quanta.q_cap(chips)"
			("LOCATION" "PC262_P0_6")
		)
		("@s9s_mb_2u_lib.s9s_mb_2u(sch_1):page437_i52@pure_quanta.q_cap(chips)"
			("LOCATION" "PC263_P0_5")
		)
		("@s9s_mb_2u_lib.s9s_mb_2u(sch_1):page437_i14@pure_quanta.q_cap(chips)"
			("LOCATION" "PC266_P0_6")
		)
		("@s9s_mb_2u_lib.s9s_mb_2u(sch_1):page437_i55@pure_quanta.q_cap(chips)"
			("LOCATION" "PC267_P0_5")
		)
		("@s9s_mb_2u_lib.s9s_mb_2u(sch_1):page437_i15@pure_quanta.q_cap(chips)"
			("LOCATION" "PC268_P0_6")
		)
		("@s9s_mb_2u_lib.s9s_mb_2u(sch_1):page437_i56@pure_quanta.q_cap(chips)"
			("LOCATION" "PC269_P0_5")
		)
		("@s9s_mb_2u_lib.s9s_mb_2u(sch_1):page437_i12@pure_quanta.q_inductor(chips)"
			("LOCATION" "PL9")
		)
		("@s9s_mb_2u_lib.s9s_mb_2u(sch_1):page437_i40@pure_quanta.q_inductor(chips)"
			("LOCATION" "PL10")
		)
		("@s9s_mb_2u_lib.s9s_mb_2u(sch_1):page437_i83@pure_quanta.q_res(chips)"
			("LOCATION" "PR138")
		)
		("@s9s_mb_2u_lib.s9s_mb_2u(sch_1):page437_i84@pure_quanta.q_res(chips)"
			("LOCATION" "PR139")
		)
		("@s9s_mb_2u_lib.s9s_mb_2u(sch_1):page437_i19@pure_quanta.q_res(chips)"
			("LOCATION" "PR140")
		)
		("@s9s_mb_2u_lib.s9s_mb_2u(sch_1):page437_i32@pure_quanta.q_res(chips)"
			("LOCATION" "PR141")
		)
		("@s9s_mb_2u_lib.s9s_mb_2u(sch_1):page436_i8@pure_quanta.q_cap(chips)"
			("LOCATION" "PC270")
		)
		("@s9s_mb_2u_lib.s9s_mb_2u(sch_1):page436_i18@pure_quanta.q_cap(chips)"
			("LOCATION" "PC271")
		)
		("@s9s_mb_2u_lib.s9s_mb_2u(sch_1):page436_i24@pure_quanta.q_cap(chips)"
			("LOCATION" "PC272_P0_4")
		)
		("@s9s_mb_2u_lib.s9s_mb_2u(sch_1):page436_i40@pure_quanta.q_cap(chips)"
			("LOCATION" "PC273_P0_3")
		)
		("@s9s_mb_2u_lib.s9s_mb_2u(sch_1):page436_i27@pure_quanta.q_cap(chips)"
			("LOCATION" "PC274_P0_4")
		)
		("@s9s_mb_2u_lib.s9s_mb_2u(sch_1):page436_i43@pure_quanta.q_cap(chips)"
			("LOCATION" "PC275_P0_3")
		)
		("@s9s_mb_2u_lib.s9s_mb_2u(sch_1):page436_i32@pure_quanta.q_cap(chips)"
			("LOCATION" "PC276_P0_4")
		)
		("@s9s_mb_2u_lib.s9s_mb_2u(sch_1):page436_i44@pure_quanta.q_cap(chips)"
			("LOCATION" "PC277_P0_3")
		)
		("@s9s_mb_2u_lib.s9s_mb_2u(sch_1):page436_i93@pure_quanta.q_cap(chips)"
			("LOCATION" "PC278")
		)
		("@s9s_mb_2u_lib.s9s_mb_2u(sch_1):page436_i92@pure_quanta.q_cap(chips)"
			("LOCATION" "PC279")
		)
		("@s9s_mb_2u_lib.s9s_mb_2u(sch_1):page436_i33@pure_quanta.q_cap(chips)"
			("LOCATION" "PC280_P0_4")
		)
		("@s9s_mb_2u_lib.s9s_mb_2u(sch_1):page436_i45@pure_quanta.q_cap(chips)"
			("LOCATION" "PC281_P0_3")
		)
		("@s9s_mb_2u_lib.s9s_mb_2u(sch_1):page436_i34@pure_quanta.q_cap(chips)"
			("LOCATION" "PC282_P0_4")
		)
		("@s9s_mb_2u_lib.s9s_mb_2u(sch_1):page436_i47@pure_quanta.q_cap(chips)"
			("LOCATION" "PC283_P0_3")
		)
		("@s9s_mb_2u_lib.s9s_mb_2u(sch_1):page436_i35@pure_quanta.q_cap(chips)"
			("LOCATION" "PC284_P0_4")
		)
		("@s9s_mb_2u_lib.s9s_mb_2u(sch_1):page436_i48@pure_quanta.q_cap(chips)"
			("LOCATION" "PC285_P0_3")
		)
		("@s9s_mb_2u_lib.s9s_mb_2u(sch_1):page436_i51@pure_quanta.q_cap(chips)"
			("LOCATION" "PC288_P0_4")
		)
		("@s9s_mb_2u_lib.s9s_mb_2u(sch_1):page436_i57@pure_quanta.q_cap(chips)"
			("LOCATION" "PC289_P0_3")
		)
		("@s9s_mb_2u_lib.s9s_mb_2u(sch_1):page436_i52@pure_quanta.q_cap(chips)"
			("LOCATION" "PC290_P0_4")
		)
		("@s9s_mb_2u_lib.s9s_mb_2u(sch_1):page436_i58@pure_quanta.q_cap(chips)"
			("LOCATION" "PC291_P0_3")
		)
		("@s9s_mb_2u_lib.s9s_mb_2u(sch_1):page436_i30@pure_quanta.q_inductor(chips)"
			("LOCATION" "PL11")
		)
		("@s9s_mb_2u_lib.s9s_mb_2u(sch_1):page436_i42@pure_quanta.q_inductor(chips)"
			("LOCATION" "PL112")
		)
		("@s9s_mb_2u_lib.s9s_mb_2u(sch_1):page436_i98@pure_quanta.q_res(chips)"
			("LOCATION" "PR144")
		)
		("@s9s_mb_2u_lib.s9s_mb_2u(sch_1):page436_i97@pure_quanta.q_res(chips)"
			("LOCATION" "PR145")
		)
		("@s9s_mb_2u_lib.s9s_mb_2u(sch_1):page436_i99@pure_quanta.q_res(chips)"
			("LOCATION" "PR146")
		)
		("@s9s_mb_2u_lib.s9s_mb_2u(sch_1):page436_i19@pure_quanta.q_res(chips)"
			("LOCATION" "PR147")
		)
		("@s9s_mb_2u_lib.s9s_mb_2u(sch_1):page585_i106@pure_quanta.q_cap(chips)"
			("LOCATION" "PC292")
		)
		("@s9s_mb_2u_lib.s9s_mb_2u(sch_1):page585_i99@pure_quanta.q_cap(chips)"
			("LOCATION" "PC293")
		)
		("@s9s_mb_2u_lib.s9s_mb_2u(sch_1):page585_i110@pure_quanta.q_cap(chips)"
			("LOCATION" "PC294_P0_2")
		)
		("@s9s_mb_2u_lib.s9s_mb_2u(sch_1):page585_i103@pure_quanta.q_cap(chips)"
			("LOCATION" "PC295_P0_1")
		)
		("@s9s_mb_2u_lib.s9s_mb_2u(sch_1):page585_i127@pure_quanta.q_cap(chips)"
			("LOCATION" "PC296_P0_2")
		)
		("@s9s_mb_2u_lib.s9s_mb_2u(sch_1):page585_i38@pure_quanta.q_cap(chips)"
			("LOCATION" "PC297_P0_1")
		)
		("@s9s_mb_2u_lib.s9s_mb_2u(sch_1):page585_i126@pure_quanta.q_cap(chips)"
			("LOCATION" "PC298_P0_2")
		)
		("@s9s_mb_2u_lib.s9s_mb_2u(sch_1):page585_i39@pure_quanta.q_cap(chips)"
			("LOCATION" "PC299_P0_1")
		)
		("@s9s_mb_2u_lib.s9s_mb_2u(sch_1):page585_i161@pure_quanta.q_cap(chips)"
			("LOCATION" "PC300")
		)
		("@s9s_mb_2u_lib.s9s_mb_2u(sch_1):page585_i162@pure_quanta.q_cap(chips)"
			("LOCATION" "PC301")
		)
		("@s9s_mb_2u_lib.s9s_mb_2u(sch_1):page585_i125@pure_quanta.q_cap(chips)"
			("LOCATION" "PC302_P0_2")
		)
		("@s9s_mb_2u_lib.s9s_mb_2u(sch_1):page585_i41@pure_quanta.q_cap(chips)"
			("LOCATION" "PC303_P0_1")
		)
		("@s9s_mb_2u_lib.s9s_mb_2u(sch_1):page585_i123@pure_quanta.q_cap(chips)"
			("LOCATION" "PC304_P0_2")
		)
		("@s9s_mb_2u_lib.s9s_mb_2u(sch_1):page585_i42@pure_quanta.q_cap(chips)"
			("LOCATION" "PC305_P0_1")
		)
		("@s9s_mb_2u_lib.s9s_mb_2u(sch_1):page585_i122@pure_quanta.q_cap(chips)"
			("LOCATION" "PC306_P0_2")
		)
		("@s9s_mb_2u_lib.s9s_mb_2u(sch_1):page585_i68@pure_quanta.q_cap(chips)"
			("LOCATION" "PC307_P0_1")
		)
		("@s9s_mb_2u_lib.s9s_mb_2u(sch_1):page585_i32@pure_quanta.q_cap(chips)"
			("LOCATION" "PC308_P0_1")
		)
		("@s9s_mb_2u_lib.s9s_mb_2u(sch_1):page585_i52@pure_quanta.q_cap(chips)"
			("LOCATION" "PC310_P0_1")
		)
		("@s9s_mb_2u_lib.s9s_mb_2u(sch_1):page585_i119@pure_quanta.q_cap(chips)"
			("LOCATION" "PC311_P0_2")
		)
		("@s9s_mb_2u_lib.s9s_mb_2u(sch_1):page585_i53@pure_quanta.q_cap(chips)"
			("LOCATION" "PC312_P0_1")
		)
		("@s9s_mb_2u_lib.s9s_mb_2u(sch_1):page585_i131@pure_quanta.q_cap(chips)"
			("LOCATION" "PC313_P0_2")
		)
		("@s9s_mb_2u_lib.s9s_mb_2u(sch_1):page585_i54@pure_quanta.q_cap(chips)"
			("LOCATION" "PC314_P0_1")
		)
		("@s9s_mb_2u_lib.s9s_mb_2u(sch_1):page585_i73@pure_quanta.q_capp(chips)"
			("LOCATION" "PC315")
		)
		("@s9s_mb_2u_lib.s9s_mb_2u(sch_1):page585_i56@pure_quanta.q_capp(chips)"
			("LOCATION" "PC316")
		)
		("@s9s_mb_2u_lib.s9s_mb_2u(sch_1):page585_i74@pure_quanta.q_capp(chips)"
			("LOCATION" "PC318")
		)
		("@s9s_mb_2u_lib.s9s_mb_2u(sch_1):page585_i63@pure_quanta.q_capp(chips)"
			("LOCATION" "PC319")
		)
		("@s9s_mb_2u_lib.s9s_mb_2u(sch_1):page585_i75@pure_quanta.q_capp(chips)"
			("LOCATION" "PC321")
		)
		("@s9s_mb_2u_lib.s9s_mb_2u(sch_1):page585_i65@pure_quanta.q_capp(chips)"
			("LOCATION" "PC322")
		)
		("@s9s_mb_2u_lib.s9s_mb_2u(sch_1):page585_i59@pure_quanta.q_capp(chips)"
			("LOCATION" "PC323")
		)
		("@s9s_mb_2u_lib.s9s_mb_2u(sch_1):page585_i77@pure_quanta.q_capp(chips)"
			("LOCATION" "PC324")
		)
		("@s9s_mb_2u_lib.s9s_mb_2u(sch_1):page585_i66@pure_quanta.q_capp(chips)"
			("LOCATION" "PC325")
		)
		("@s9s_mb_2u_lib.s9s_mb_2u(sch_1):page585_i60@pure_quanta.q_capp(chips)"
			("LOCATION" "PC326")
		)
		("@s9s_mb_2u_lib.s9s_mb_2u(sch_1):page585_i153@pure_quanta.q_capp(chips)"
			("LOCATION" "PC1920")
		)
		("@s9s_mb_2u_lib.s9s_mb_2u(sch_1):page585_i163@pure_quanta.q_capp(chips)"
			("LOCATION" "PC2336")
		)
		("@s9s_mb_2u_lib.s9s_mb_2u(sch_1):page585_i128@pure_quanta.q_inductor(chips)"
			("LOCATION" "PL13")
		)
		("@s9s_mb_2u_lib.s9s_mb_2u(sch_1):page585_i72@pure_quanta.q_inductor(chips)"
			("LOCATION" "PL15")
		)
		("@s9s_mb_2u_lib.s9s_mb_2u(sch_1):page585_i40@pure_quanta.q_inductor(chips)"
			("LOCATION" "PL114")
		)
		("@s9s_mb_2u_lib.s9s_mb_2u(sch_1):page585_i167@pure_quanta.q_res(chips)"
			("LOCATION" "PR150")
		)
		("@s9s_mb_2u_lib.s9s_mb_2u(sch_1):page585_i166@pure_quanta.q_res(chips)"
			("LOCATION" "PR151")
		)
		("@s9s_mb_2u_lib.s9s_mb_2u(sch_1):page585_i107@pure_quanta.q_res(chips)"
			("LOCATION" "PR152")
		)
		("@s9s_mb_2u_lib.s9s_mb_2u(sch_1):page585_i100@pure_quanta.q_res(chips)"
			("LOCATION" "PR153")
		)
		("@s9s_mb_2u_lib.s9s_mb_2u(sch_1):page575_i41@pure_quanta.q_capp(chips)"
			("LOCATION" "PC366")
		)
		("@s9s_mb_2u_lib.s9s_mb_2u(sch_1):page575_i40@pure_quanta.q_cap(chips)"
			("LOCATION" "PC367")
		)
		("@s9s_mb_2u_lib.s9s_mb_2u(sch_1):page575_i39@pure_quanta.q_cap(chips)"
			("LOCATION" "PC368")
		)
		("@s9s_mb_2u_lib.s9s_mb_2u(sch_1):page575_i37@pure_quanta.q_cap(chips)"
			("LOCATION" "PC369")
		)
		("@s9s_mb_2u_lib.s9s_mb_2u(sch_1):page575_i6@pure_quanta.q_cap(chips)"
			("LOCATION" "PC370")
		)
		("@s9s_mb_2u_lib.s9s_mb_2u(sch_1):page575_i5@pure_quanta.q_cap(chips)"
			("LOCATION" "PC371")
		)
		("@s9s_mb_2u_lib.s9s_mb_2u(sch_1):page575_i3@pure_quanta.q_capp(chips)"
			("LOCATION" "PC372")
		)
		("@s9s_mb_2u_lib.s9s_mb_2u(sch_1):page575_i46@pure_quanta.q_cap(chips)"
			("LOCATION" "PC1179")
		)
		("@s9s_mb_2u_lib.s9s_mb_2u(sch_1):page575_i31@pure_quanta.q_cap(chips)"
			("LOCATION" "PC1181")
		)
		("@s9s_mb_2u_lib.s9s_mb_2u(sch_1):page575_i8@pure_quanta.q_cap(chips)"
			("LOCATION" "PC1188")
		)
		("@s9s_mb_2u_lib.s9s_mb_2u(sch_1):page575_i49@pure_quanta.q_capp(chips)"
			("LOCATION" "PC1377")
		)
		("@s9s_mb_2u_lib.s9s_mb_2u(sch_1):page575_i55@pure_quanta.q_cap(chips)"
			("LOCATION" "PC1378")
		)
		("@s9s_mb_2u_lib.s9s_mb_2u(sch_1):page575_i33@pure_quanta.q_cap(chips)"
			("LOCATION" "PC1382")
		)
		("@s9s_mb_2u_lib.s9s_mb_2u(sch_1):page575_i29@pure_quanta.q_cap(chips)"
			("LOCATION" "PC1383")
		)
		("@s9s_mb_2u_lib.s9s_mb_2u(sch_1):page575_i26@pure_quanta.q_cap(chips)"
			("LOCATION" "PC1384")
		)
		("@s9s_mb_2u_lib.s9s_mb_2u(sch_1):page575_i21@pure_quanta.q_cap(chips)"
			("LOCATION" "PC1385")
		)
		("@s9s_mb_2u_lib.s9s_mb_2u(sch_1):page575_i4@pure_quanta.q_cap(chips)"
			("LOCATION" "PC1386")
		)
		("@s9s_mb_2u_lib.s9s_mb_2u(sch_1):page575_i12@pure_quanta.q_capp(chips)"
			("LOCATION" "PC1387")
		)
		("@s9s_mb_2u_lib.s9s_mb_2u(sch_1):page575_i71@pure_quanta.q_capp(chips)"
			("LOCATION" "PC1410")
		)
		("@s9s_mb_2u_lib.s9s_mb_2u(sch_1):page575_i11@pure_quanta.q_capp(chips)"
			("LOCATION" "PC2190")
		)
		("@s9s_mb_2u_lib.s9s_mb_2u(sch_1):page575_i66@pure_quanta.q_cap(chips)"
			("LOCATION" "PC3170")
		)
		("@s9s_mb_2u_lib.s9s_mb_2u(sch_1):page575_i68@pure_quanta.q_cap(chips)"
			("LOCATION" "PC3172")
		)
		("@s9s_mb_2u_lib.s9s_mb_2u(sch_1):page575_i47@pure_quanta.q_inductor(chips)"
			("LOCATION" "PL39")
		)
		("@s9s_mb_2u_lib.s9s_mb_2u(sch_1):page575_i16@pure_quanta.q_inductor(chips)"
			("LOCATION" "PL40")
		)
		("@s9s_mb_2u_lib.s9s_mb_2u(sch_1):page575_i2@pure_quanta.q_inductor(chips)"
			("LOCATION" "PL41")
		)
		("@s9s_mb_2u_lib.s9s_mb_2u(sch_1):page575_i70@pure_quanta.q_res(chips)"
			("LOCATION" "PR443")
		)
		("@s9s_mb_2u_lib.s9s_mb_2u(sch_1):page575_i52@pure_quanta.q_res(chips)"
			("LOCATION" "PR505")
		)
		("@s9s_mb_2u_lib.s9s_mb_2u(sch_1):page575_i58@pure_quanta.q_res(chips)"
			("LOCATION" "PR547")
		)
		("@s9s_mb_2u_lib.s9s_mb_2u(sch_1):page575_i60@pure_quanta.q_res(chips)"
			("LOCATION" "PR548")
		)
		("@s9s_mb_2u_lib.s9s_mb_2u(sch_1):page575_i63@pure_quanta.q_res(chips)"
			("LOCATION" "PR549")
		)
		("@s9s_mb_2u_lib.s9s_mb_2u(sch_1):page575_i64@pure_quanta.q_res(chips)"
			("LOCATION" "PR550")
		)
		("@s9s_mb_2u_lib.s9s_mb_2u(sch_1):page575_i51@pure_quanta.q_res(chips)"
			("LOCATION" "PR551")
		)
		("@s9s_mb_2u_lib.s9s_mb_2u(sch_1):page575_i53@pure_quanta.q_res(chips)"
			("LOCATION" "PR552")
		)
		("@s9s_mb_2u_lib.s9s_mb_2u(sch_1):page575_i35@pure_quanta.q_res(chips)"
			("LOCATION" "PR553")
		)
		("@s9s_mb_2u_lib.s9s_mb_2u(sch_1):page575_i23@pure_quanta.q_res(chips)"
			("LOCATION" "PR554")
		)
		("@s9s_mb_2u_lib.s9s_mb_2u(sch_1):page575_i24@pure_quanta.q_res(chips)"
			("LOCATION" "PR555")
		)
		("@s9s_mb_2u_lib.s9s_mb_2u(sch_1):page575_i13@pure_quanta.q_res(chips)"
			("LOCATION" "PR556")
		)
		("@s9s_mb_2u_lib.s9s_mb_2u(sch_1):page575_i15@pure_quanta.q_res(chips)"
			("LOCATION" "PR557")
		)
		("@s9s_mb_2u_lib.s9s_mb_2u(sch_1):page575_i32@pure_quanta.tps51225rukr(chips)"
			("LOCATION" "PU16")
		)
		("@s9s_mb_2u_lib.s9s_mb_2u(sch_1):page575_i43@pure_quanta.mosfet_nch_dual_1d1s(chips)"
			("LOCATION" "PU47")
		)
		("@s9s_mb_2u_lib.s9s_mb_2u(sch_1):page575_i20@pure_quanta.mosfet_nch_dual_1d1s(chips)"
			("LOCATION" "PU48")
		)
		("@s9s_mb_2u_lib.s9s_mb_2u(sch_1):page603_i134@pure_quanta.q_cap(chips)"
			("LOCATION" "PC373")
		)
		("@s9s_mb_2u_lib.s9s_mb_2u(sch_1):page603_i123@pure_quanta.q_cap(chips)"
			("LOCATION" "PC374")
		)
		("@s9s_mb_2u_lib.s9s_mb_2u(sch_1):page603_i122@pure_quanta.q_cap(chips)"
			("LOCATION" "PC375")
		)
		("@s9s_mb_2u_lib.s9s_mb_2u(sch_1):page603_i167@pure_quanta.q_cap(chips)"
			("LOCATION" "PC376")
		)
		("@s9s_mb_2u_lib.s9s_mb_2u(sch_1):page603_i120@pure_quanta.q_cap(chips)"
			("LOCATION" "PC377")
		)
		("@s9s_mb_2u_lib.s9s_mb_2u(sch_1):page603_i119@pure_quanta.q_cap(chips)"
			("LOCATION" "PC378")
		)
		("@s9s_mb_2u_lib.s9s_mb_2u(sch_1):page603_i128@pure_quanta.q_cap(chips)"
			("LOCATION" "PC379")
		)
		("@s9s_mb_2u_lib.s9s_mb_2u(sch_1):page603_i126@pure_quanta.q_cap(chips)"
			("LOCATION" "PC381")
		)
		("@s9s_mb_2u_lib.s9s_mb_2u(sch_1):page603_i125@pure_quanta.q_cap(chips)"
			("LOCATION" "PC382")
		)
		("@s9s_mb_2u_lib.s9s_mb_2u(sch_1):page603_i145@pure_quanta.q_capp(chips)"
			("LOCATION" "PC384")
		)
		("@s9s_mb_2u_lib.s9s_mb_2u(sch_1):page603_i147@pure_quanta.q_capp(chips)"
			("LOCATION" "PC385")
		)
		("@s9s_mb_2u_lib.s9s_mb_2u(sch_1):page603_i158@pure_quanta.q_capp(chips)"
			("LOCATION" "PC1940")
		)
		("@s9s_mb_2u_lib.s9s_mb_2u(sch_1):page603_i129@pure_quanta.q_inductor(chips)"
			("LOCATION" "PL17")
		)
		("@s9s_mb_2u_lib.s9s_mb_2u(sch_1):page603_i132@pure_quanta.q_res(chips)"
			("LOCATION" "PR200")
		)
		("@s9s_mb_2u_lib.s9s_mb_2u(sch_1):page603_i169@pure_quanta.q_res(chips)"
			("LOCATION" "PR1746")
		)
		("@s9s_mb_2u_lib.s9s_mb_2u(sch_1):page602_i132@pure_quanta.q_cap(chips)"
			("LOCATION" "PC388")
		)
		("@s9s_mb_2u_lib.s9s_mb_2u(sch_1):page602_i139@pure_quanta.q_cap(chips)"
			("LOCATION" "PC391")
		)
		("@s9s_mb_2u_lib.s9s_mb_2u(sch_1):page602_i157@pure_quanta.q_cap(chips)"
			("LOCATION" "PC394")
		)
		("@s9s_mb_2u_lib.s9s_mb_2u(sch_1):page602_i156@pure_quanta.q_cap(chips)"
			("LOCATION" "PC1289")
		)
		("@s9s_mb_2u_lib.s9s_mb_2u(sch_1):page602_i186@pure_quanta.q_cap(chips)"
			("LOCATION" "PC1336")
		)
		("@s9s_mb_2u_lib.s9s_mb_2u(sch_1):page602_i188@pure_quanta.q_cap(chips)"
			("LOCATION" "PC1337")
		)
		("@s9s_mb_2u_lib.s9s_mb_2u(sch_1):page602_i95@pure_quanta.q_short(chips)"
			("LOCATION" "PJ48")
		)
		("@s9s_mb_2u_lib.s9s_mb_2u(sch_1):page602_i84@pure_quanta.q_res(chips)"
			("LOCATION" "PR202")
		)
		("@s9s_mb_2u_lib.s9s_mb_2u(sch_1):page602_i129@pure_quanta.q_res(chips)"
			("LOCATION" "PR206")
		)
		("@s9s_mb_2u_lib.s9s_mb_2u(sch_1):page602_i126@pure_quanta.q_res(chips)"
			("LOCATION" "PR207")
		)
		("@s9s_mb_2u_lib.s9s_mb_2u(sch_1):page602_i128@pure_quanta.q_res(chips)"
			("LOCATION" "PR208")
		)
		("@s9s_mb_2u_lib.s9s_mb_2u(sch_1):page602_i127@pure_quanta.q_res(chips)"
			("LOCATION" "PR209")
		)
		("@s9s_mb_2u_lib.s9s_mb_2u(sch_1):page602_i125@pure_quanta.q_res(chips)"
			("LOCATION" "PR210")
		)
		("@s9s_mb_2u_lib.s9s_mb_2u(sch_1):page602_i124@pure_quanta.q_res(chips)"
			("LOCATION" "PR211")
		)
		("@s9s_mb_2u_lib.s9s_mb_2u(sch_1):page602_i121@pure_quanta.q_res(chips)"
			("LOCATION" "PR212")
		)
		("@s9s_mb_2u_lib.s9s_mb_2u(sch_1):page602_i122@pure_quanta.q_res(chips)"
			("LOCATION" "PR213")
		)
		("@s9s_mb_2u_lib.s9s_mb_2u(sch_1):page602_i103@pure_quanta.q_res(chips)"
			("LOCATION" "PR214")
		)
		("@s9s_mb_2u_lib.s9s_mb_2u(sch_1):page602_i112@pure_quanta.q_res(chips)"
			("LOCATION" "PR215")
		)
		("@s9s_mb_2u_lib.s9s_mb_2u(sch_1):page602_i119@pure_quanta.q_res(chips)"
			("LOCATION" "PR216")
		)
		("@s9s_mb_2u_lib.s9s_mb_2u(sch_1):page602_i113@pure_quanta.q_res(chips)"
			("LOCATION" "PR217")
		)
		("@s9s_mb_2u_lib.s9s_mb_2u(sch_1):page602_i106@pure_quanta.q_res(chips)"
			("LOCATION" "PR218")
		)
		("@s9s_mb_2u_lib.s9s_mb_2u(sch_1):page602_i158@pure_quanta.q_res(chips)"
			("LOCATION" "PR220")
		)
		("@s9s_mb_2u_lib.s9s_mb_2u(sch_1):page602_i144@pure_quanta.q_res(chips)"
			("LOCATION" "PR223")
		)
		("@s9s_mb_2u_lib.s9s_mb_2u(sch_1):page602_i94@pure_quanta.q_res(chips)"
			("LOCATION" "PR558")
		)
		("@s9s_mb_2u_lib.s9s_mb_2u(sch_1):page602_i96@pure_quanta.q_res(chips)"
			("LOCATION" "PR559")
		)
		("@s9s_mb_2u_lib.s9s_mb_2u(sch_1):page602_i193@pure_quanta.q_res(chips)"
			("LOCATION" "PR1315")
		)
		("@s9s_mb_2u_lib.s9s_mb_2u(sch_1):page602_i191@pure_quanta.q_res(chips)"
			("LOCATION" "PR1718")
		)
		("@s9s_mb_2u_lib.s9s_mb_2u(sch_1):page602_i192@pure_quanta.q_res(chips)"
			("LOCATION" "PR1747")
		)
		("@s9s_mb_2u_lib.s9s_mb_2u(sch_1):page598_i51@pure_quanta.q_cap(chips)"
			("LOCATION" "PC395")
		)
		("@s9s_mb_2u_lib.s9s_mb_2u(sch_1):page598_i62@pure_quanta.q_cap(chips)"
			("LOCATION" "PC396")
		)
		("@s9s_mb_2u_lib.s9s_mb_2u(sch_1):page598_i27@pure_quanta.q_cap(chips)"
			("LOCATION" "PC397_P1_1")
		)
		("@s9s_mb_2u_lib.s9s_mb_2u(sch_1):page598_i41@pure_quanta.q_cap(chips)"
			("LOCATION" "PC398_P1_2")
		)
		("@s9s_mb_2u_lib.s9s_mb_2u(sch_1):page598_i26@pure_quanta.q_cap(chips)"
			("LOCATION" "PC399_P1_1")
		)
		("@s9s_mb_2u_lib.s9s_mb_2u(sch_1):page598_i40@pure_quanta.q_cap(chips)"
			("LOCATION" "PC400_P1_2")
		)
		("@s9s_mb_2u_lib.s9s_mb_2u(sch_1):page598_i97@pure_quanta.q_cap(chips)"
			("LOCATION" "PC401")
		)
		("@s9s_mb_2u_lib.s9s_mb_2u(sch_1):page598_i98@pure_quanta.q_cap(chips)"
			("LOCATION" "PC402")
		)
		("@s9s_mb_2u_lib.s9s_mb_2u(sch_1):page598_i25@pure_quanta.q_cap(chips)"
			("LOCATION" "PC403_P1_1")
		)
		("@s9s_mb_2u_lib.s9s_mb_2u(sch_1):page598_i37@pure_quanta.q_cap(chips)"
			("LOCATION" "PC404_P1_2")
		)
		("@s9s_mb_2u_lib.s9s_mb_2u(sch_1):page598_i24@pure_quanta.q_cap(chips)"
			("LOCATION" "PC405_P1_1")
		)
		("@s9s_mb_2u_lib.s9s_mb_2u(sch_1):page598_i36@pure_quanta.q_cap(chips)"
			("LOCATION" "PC406_P1_2")
		)
		("@s9s_mb_2u_lib.s9s_mb_2u(sch_1):page598_i13@pure_quanta.q_cap(chips)"
			("LOCATION" "PC410_P1_1")
		)
		("@s9s_mb_2u_lib.s9s_mb_2u(sch_1):page598_i20@pure_quanta.q_cap(chips)"
			("LOCATION" "PC411_P1_2")
		)
		("@s9s_mb_2u_lib.s9s_mb_2u(sch_1):page598_i12@pure_quanta.q_cap(chips)"
			("LOCATION" "PC412_P1_1")
		)
		("@s9s_mb_2u_lib.s9s_mb_2u(sch_1):page598_i19@pure_quanta.q_cap(chips)"
			("LOCATION" "PC413_P1_2")
		)
		("@s9s_mb_2u_lib.s9s_mb_2u(sch_1):page598_i16@pure_quanta.q_capp(chips)"
			("LOCATION" "PC414")
		)
		("@s9s_mb_2u_lib.s9s_mb_2u(sch_1):page598_i15@pure_quanta.q_capp(chips)"
			("LOCATION" "PC415")
		)
		("@s9s_mb_2u_lib.s9s_mb_2u(sch_1):page598_i9@pure_quanta.q_capp(chips)"
			("LOCATION" "PC416")
		)
		("@s9s_mb_2u_lib.s9s_mb_2u(sch_1):page598_i2@pure_quanta.q_capp(chips)"
			("LOCATION" "PC417")
		)
		("@s9s_mb_2u_lib.s9s_mb_2u(sch_1):page598_i7@pure_quanta.q_capp(chips)"
			("LOCATION" "PC418")
		)
		("@s9s_mb_2u_lib.s9s_mb_2u(sch_1):page598_i28@pure_quanta.q_cap(chips)"
			("LOCATION" "PC1242_P1_1")
		)
		("@s9s_mb_2u_lib.s9s_mb_2u(sch_1):page598_i46@pure_quanta.q_cap(chips)"
			("LOCATION" "PC1243_P1_2")
		)
		("@s9s_mb_2u_lib.s9s_mb_2u(sch_1):page598_i86@pure_quanta.q_capp(chips)"
			("LOCATION" "PC2171")
		)
		("@s9s_mb_2u_lib.s9s_mb_2u(sch_1):page598_i84@pure_quanta.q_inductor(chips)"
			("LOCATION" "PL18")
		)
		("@s9s_mb_2u_lib.s9s_mb_2u(sch_1):page598_i85@pure_quanta.q_inductor(chips)"
			("LOCATION" "PL19")
		)
		("@s9s_mb_2u_lib.s9s_mb_2u(sch_1):page598_i4@pure_quanta.q_inductor(chips)"
			("LOCATION" "PL43")
		)
		("@s9s_mb_2u_lib.s9s_mb_2u(sch_1):page598_i67@pure_quanta.q_res(chips)"
			("LOCATION" "PR224")
		)
		("@s9s_mb_2u_lib.s9s_mb_2u(sch_1):page598_i57@pure_quanta.q_res(chips)"
			("LOCATION" "PR225")
		)
		("@s9s_mb_2u_lib.s9s_mb_2u(sch_1):page598_i50@pure_quanta.q_res(chips)"
			("LOCATION" "PR226")
		)
		("@s9s_mb_2u_lib.s9s_mb_2u(sch_1):page598_i60@pure_quanta.q_res(chips)"
			("LOCATION" "PR227")
		)
		("@s9s_mb_2u_lib.s9s_mb_2u(sch_1):page663_i35@pure_quanta.q_cap(chips)"
			("LOCATION" "PC407_P1_5")
		)
		("@s9s_mb_2u_lib.s9s_mb_2u(sch_1):page663_i26@pure_quanta.q_cap(chips)"
			("LOCATION" "PC2379")
		)
		("@s9s_mb_2u_lib.s9s_mb_2u(sch_1):page663_i23@pure_quanta.q_cap(chips)"
			("LOCATION" "PC2380")
		)
		("@s9s_mb_2u_lib.s9s_mb_2u(sch_1):page663_i18@pure_quanta.q_cap(chips)"
			("LOCATION" "PC2381_P1_5")
		)
		("@s9s_mb_2u_lib.s9s_mb_2u(sch_1):page663_i17@pure_quanta.q_cap(chips)"
			("LOCATION" "PC2382_P1_5")
		)
		("@s9s_mb_2u_lib.s9s_mb_2u(sch_1):page663_i16@pure_quanta.q_cap(chips)"
			("LOCATION" "PC2383_P1_5")
		)
		("@s9s_mb_2u_lib.s9s_mb_2u(sch_1):page663_i15@pure_quanta.q_cap(chips)"
			("LOCATION" "PC2384_P1_5")
		)
		("@s9s_mb_2u_lib.s9s_mb_2u(sch_1):page663_i14@pure_quanta.q_cap(chips)"
			("LOCATION" "PC2385_P1_5")
		)
		("@s9s_mb_2u_lib.s9s_mb_2u(sch_1):page663_i20@pure_quanta.q_cap(chips)"
			("LOCATION" "PC2386")
		)
		("@s9s_mb_2u_lib.s9s_mb_2u(sch_1):page663_i10@pure_quanta.q_cap(chips)"
			("LOCATION" "PC2394_P1_5")
		)
		("@s9s_mb_2u_lib.s9s_mb_2u(sch_1):page663_i9@pure_quanta.q_cap(chips)"
			("LOCATION" "PC2395_P1_5")
		)
		("@s9s_mb_2u_lib.s9s_mb_2u(sch_1):page663_i5@pure_quanta.q_capp(chips)"
			("LOCATION" "PC2401")
		)
		("@s9s_mb_2u_lib.s9s_mb_2u(sch_1):page663_i3@pure_quanta.q_capp(chips)"
			("LOCATION" "PC2402")
		)
		("@s9s_mb_2u_lib.s9s_mb_2u(sch_1):page663_i11@pure_quanta.q_inductor(chips)"
			("LOCATION" "PL58")
		)
		("@s9s_mb_2u_lib.s9s_mb_2u(sch_1):page663_i33@pure_quanta.q_res(chips)"
			("LOCATION" "PR1891")
		)
		("@s9s_mb_2u_lib.s9s_mb_2u(sch_1):page663_i25@pure_quanta.q_res(chips)"
			("LOCATION" "PR1892")
		)
		("@s9s_mb_2u_lib.s9s_mb_2u(sch_1):page663_i12@pure_quanta.q_res(chips)"
			("LOCATION" "PR1894")
		)
		("@s9s_mb_2u_lib.s9s_mb_2u(sch_1):page599_i105@pure_quanta.q_cap(chips)"
			("LOCATION" "PC408_P1_4")
		)
		("@s9s_mb_2u_lib.s9s_mb_2u(sch_1):page599_i19@pure_quanta.q_cap(chips)"
			("LOCATION" "PC1191")
		)
		("@s9s_mb_2u_lib.s9s_mb_2u(sch_1):page599_i7@pure_quanta.q_cap(chips)"
			("LOCATION" "PC1192")
		)
		("@s9s_mb_2u_lib.s9s_mb_2u(sch_1):page599_i44@pure_quanta.q_cap(chips)"
			("LOCATION" "PC1193_P1_3")
		)
		("@s9s_mb_2u_lib.s9s_mb_2u(sch_1):page599_i27@pure_quanta.q_cap(chips)"
			("LOCATION" "PC1194_P1_4")
		)
		("@s9s_mb_2u_lib.s9s_mb_2u(sch_1):page599_i45@pure_quanta.q_cap(chips)"
			("LOCATION" "PC1195_P1_3")
		)
		("@s9s_mb_2u_lib.s9s_mb_2u(sch_1):page599_i32@pure_quanta.q_cap(chips)"
			("LOCATION" "PC1196_P1_4")
		)
		("@s9s_mb_2u_lib.s9s_mb_2u(sch_1):page599_i103@pure_quanta.q_cap(chips)"
			("LOCATION" "PC1197")
		)
		("@s9s_mb_2u_lib.s9s_mb_2u(sch_1):page599_i104@pure_quanta.q_cap(chips)"
			("LOCATION" "PC1198")
		)
		("@s9s_mb_2u_lib.s9s_mb_2u(sch_1):page599_i46@pure_quanta.q_cap(chips)"
			("LOCATION" "PC1199_P1_3")
		)
		("@s9s_mb_2u_lib.s9s_mb_2u(sch_1):page599_i33@pure_quanta.q_cap(chips)"
			("LOCATION" "PC1200_P1_4")
		)
		("@s9s_mb_2u_lib.s9s_mb_2u(sch_1):page599_i89@pure_quanta.q_capp(chips)"
			("LOCATION" "PC1201")
		)
		("@s9s_mb_2u_lib.s9s_mb_2u(sch_1):page599_i47@pure_quanta.q_cap(chips)"
			("LOCATION" "PC1201_P1_3")
		)
		("@s9s_mb_2u_lib.s9s_mb_2u(sch_1):page599_i35@pure_quanta.q_cap(chips)"
			("LOCATION" "PC1202_P1_4")
		)
		("@s9s_mb_2u_lib.s9s_mb_2u(sch_1):page599_i87@pure_quanta.q_capp(chips)"
			("LOCATION" "PC1203")
		)
		("@s9s_mb_2u_lib.s9s_mb_2u(sch_1):page599_i42@pure_quanta.q_cap(chips)"
			("LOCATION" "PC1203_P1_3")
		)
		("@s9s_mb_2u_lib.s9s_mb_2u(sch_1):page599_i86@pure_quanta.q_capp(chips)"
			("LOCATION" "PC1204")
		)
		("@s9s_mb_2u_lib.s9s_mb_2u(sch_1):page599_i43@pure_quanta.q_cap(chips)"
			("LOCATION" "PC1204_P1_3")
		)
		("@s9s_mb_2u_lib.s9s_mb_2u(sch_1):page599_i85@pure_quanta.q_capp(chips)"
			("LOCATION" "PC1205")
		)
		("@s9s_mb_2u_lib.s9s_mb_2u(sch_1):page599_i57@pure_quanta.q_cap(chips)"
			("LOCATION" "PC1206_P1_3")
		)
		("@s9s_mb_2u_lib.s9s_mb_2u(sch_1):page599_i50@pure_quanta.q_cap(chips)"
			("LOCATION" "PC1207_P1_4")
		)
		("@s9s_mb_2u_lib.s9s_mb_2u(sch_1):page599_i59@pure_quanta.q_cap(chips)"
			("LOCATION" "PC1208_P1_3")
		)
		("@s9s_mb_2u_lib.s9s_mb_2u(sch_1):page599_i51@pure_quanta.q_cap(chips)"
			("LOCATION" "PC1209_P1_4")
		)
		("@s9s_mb_2u_lib.s9s_mb_2u(sch_1):page599_i67@pure_quanta.q_capp(chips)"
			("LOCATION" "PC1210")
		)
		("@s9s_mb_2u_lib.s9s_mb_2u(sch_1):page599_i24@pure_quanta.q_cap(chips)"
			("LOCATION" "PC1244_P1_3")
		)
		("@s9s_mb_2u_lib.s9s_mb_2u(sch_1):page599_i11@pure_quanta.q_cap(chips)"
			("LOCATION" "PC1245_P1_4")
		)
		("@s9s_mb_2u_lib.s9s_mb_2u(sch_1):page599_i92@pure_quanta.q_capp(chips)"
			("LOCATION" "PC2172")
		)
		("@s9s_mb_2u_lib.s9s_mb_2u(sch_1):page599_i90@pure_quanta.q_inductor(chips)"
			("LOCATION" "PL12")
		)
		("@s9s_mb_2u_lib.s9s_mb_2u(sch_1):page599_i65@pure_quanta.q_inductor(chips)"
			("LOCATION" "PL14")
		)
		("@s9s_mb_2u_lib.s9s_mb_2u(sch_1):page599_i91@pure_quanta.q_inductor(chips)"
			("LOCATION" "PL113")
		)
		("@s9s_mb_2u_lib.s9s_mb_2u(sch_1):page599_i2@pure_quanta.q_res(chips)"
			("LOCATION" "PR1304")
		)
		("@s9s_mb_2u_lib.s9s_mb_2u(sch_1):page599_i14@pure_quanta.q_res(chips)"
			("LOCATION" "PR1305")
		)
		("@s9s_mb_2u_lib.s9s_mb_2u(sch_1):page599_i21@pure_quanta.q_res(chips)"
			("LOCATION" "PR1306")
		)
		("@s9s_mb_2u_lib.s9s_mb_2u(sch_1):page599_i9@pure_quanta.q_res(chips)"
			("LOCATION" "PR1307")
		)
		("@s9s_mb_2u_lib.s9s_mb_2u(sch_1):page597_i192@pure_quanta.q_cap(chips)"
			("LOCATION" "PC419")
		)
		("@s9s_mb_2u_lib.s9s_mb_2u(sch_1):page597_i138@pure_quanta.q_cap(chips)"
			("LOCATION" "PC420")
		)
		("@s9s_mb_2u_lib.s9s_mb_2u(sch_1):page597_i142@pure_quanta.q_cap(chips)"
			("LOCATION" "PC421")
		)
		("@s9s_mb_2u_lib.s9s_mb_2u(sch_1):page597_i189@pure_quanta.q_cap(chips)"
			("LOCATION" "PC423")
		)
		("@s9s_mb_2u_lib.s9s_mb_2u(sch_1):page597_i174@pure_quanta.q_cap(chips)"
			("LOCATION" "PC424")
		)
		("@s9s_mb_2u_lib.s9s_mb_2u(sch_1):page597_i175@pure_quanta.q_cap(chips)"
			("LOCATION" "PC427")
		)
		("@s9s_mb_2u_lib.s9s_mb_2u(sch_1):page597_i173@pure_quanta.q_cap(chips)"
			("LOCATION" "PC1190")
		)
		("@s9s_mb_2u_lib.s9s_mb_2u(sch_1):page597_i129@pure_quanta.q_short(chips)"
			("LOCATION" "PJ49")
		)
		("@s9s_mb_2u_lib.s9s_mb_2u(sch_1):page597_i198@pure_quanta.q_res(chips)"
			("LOCATION" "PR228")
		)
		("@s9s_mb_2u_lib.s9s_mb_2u(sch_1):page597_i194@pure_quanta.q_res(chips)"
			("LOCATION" "PR230")
		)
		("@s9s_mb_2u_lib.s9s_mb_2u(sch_1):page597_i195@pure_quanta.q_res(chips)"
			("LOCATION" "PR231")
		)
		("@s9s_mb_2u_lib.s9s_mb_2u(sch_1):page597_i140@pure_quanta.q_res(chips)"
			("LOCATION" "PR232")
		)
		("@s9s_mb_2u_lib.s9s_mb_2u(sch_1):page597_i141@pure_quanta.q_res(chips)"
			("LOCATION" "PR233")
		)
		("@s9s_mb_2u_lib.s9s_mb_2u(sch_1):page597_i133@pure_quanta.q_res(chips)"
			("LOCATION" "PR234")
		)
		("@s9s_mb_2u_lib.s9s_mb_2u(sch_1):page597_i134@pure_quanta.q_res(chips)"
			("LOCATION" "PR235")
		)
		("@s9s_mb_2u_lib.s9s_mb_2u(sch_1):page597_i131@pure_quanta.q_res(chips)"
			("LOCATION" "PR236")
		)
		("@s9s_mb_2u_lib.s9s_mb_2u(sch_1):page597_i132@pure_quanta.q_res(chips)"
			("LOCATION" "PR237")
		)
		("@s9s_mb_2u_lib.s9s_mb_2u(sch_1):page597_i137@pure_quanta.q_res(chips)"
			("LOCATION" "PR238")
		)
		("@s9s_mb_2u_lib.s9s_mb_2u(sch_1):page597_i136@pure_quanta.q_res(chips)"
			("LOCATION" "PR239")
		)
		("@s9s_mb_2u_lib.s9s_mb_2u(sch_1):page597_i188@pure_quanta.q_res(chips)"
			("LOCATION" "PR240")
		)
		("@s9s_mb_2u_lib.s9s_mb_2u(sch_1):page597_i120@pure_quanta.q_res(chips)"
			("LOCATION" "PR241")
		)
		("@s9s_mb_2u_lib.s9s_mb_2u(sch_1):page597_i135@pure_quanta.q_res(chips)"
			("LOCATION" "PR242")
		)
		("@s9s_mb_2u_lib.s9s_mb_2u(sch_1):page597_i122@pure_quanta.q_res(chips)"
			("LOCATION" "PR243")
		)
		("@s9s_mb_2u_lib.s9s_mb_2u(sch_1):page597_i191@pure_quanta.q_res(chips)"
			("LOCATION" "PR244")
		)
		("@s9s_mb_2u_lib.s9s_mb_2u(sch_1):page597_i184@pure_quanta.q_res(chips)"
			("LOCATION" "PR248")
		)
		("@s9s_mb_2u_lib.s9s_mb_2u(sch_1):page597_i167@pure_quanta.q_res(chips)"
			("LOCATION" "PR249")
		)
		("@s9s_mb_2u_lib.s9s_mb_2u(sch_1):page597_i117@pure_quanta.q_res(chips)"
			("LOCATION" "PR560")
		)
		("@s9s_mb_2u_lib.s9s_mb_2u(sch_1):page597_i128@pure_quanta.q_res(chips)"
			("LOCATION" "PR561")
		)
		("@s9s_mb_2u_lib.s9s_mb_2u(sch_1):page597_i214@pure_quanta.q_res(chips)"
			("LOCATION" "PR1312")
		)
		("@s9s_mb_2u_lib.s9s_mb_2u(sch_1):page597_i215@pure_quanta.q_res(chips)"
			("LOCATION" "R1770")
		)
		("@s9s_mb_2u_lib.s9s_mb_2u(sch_1):page597_i216@pure_quanta.q_res(chips)"
			("LOCATION" "R1771")
		)
		("@s9s_mb_2u_lib.s9s_mb_2u(sch_1):page595_i20@pure_quanta.q_cap(chips)"
			("LOCATION" "PC428")
		)
		("@s9s_mb_2u_lib.s9s_mb_2u(sch_1):page595_i17@pure_quanta.q_cap(chips)"
			("LOCATION" "PC429")
		)
		("@s9s_mb_2u_lib.s9s_mb_2u(sch_1):page595_i16@pure_quanta.q_cap(chips)"
			("LOCATION" "PC430")
		)
		("@s9s_mb_2u_lib.s9s_mb_2u(sch_1):page595_i53@pure_quanta.q_cap(chips)"
			("LOCATION" "PC431")
		)
		("@s9s_mb_2u_lib.s9s_mb_2u(sch_1):page595_i15@pure_quanta.q_cap(chips)"
			("LOCATION" "PC432")
		)
		("@s9s_mb_2u_lib.s9s_mb_2u(sch_1):page595_i14@pure_quanta.q_cap(chips)"
			("LOCATION" "PC433")
		)
		("@s9s_mb_2u_lib.s9s_mb_2u(sch_1):page595_i8@pure_quanta.q_cap(chips)"
			("LOCATION" "PC434")
		)
		("@s9s_mb_2u_lib.s9s_mb_2u(sch_1):page595_i41@pure_quanta.q_cap(chips)"
			("LOCATION" "PC435")
		)
		("@s9s_mb_2u_lib.s9s_mb_2u(sch_1):page595_i6@pure_quanta.q_cap(chips)"
			("LOCATION" "PC437")
		)
		("@s9s_mb_2u_lib.s9s_mb_2u(sch_1):page595_i43@pure_quanta.q_capp(chips)"
			("LOCATION" "PC1930")
		)
		("@s9s_mb_2u_lib.s9s_mb_2u(sch_1):page595_i42@pure_quanta.q_capp(chips)"
			("LOCATION" "PC2199")
		)
		("@s9s_mb_2u_lib.s9s_mb_2u(sch_1):page595_i40@pure_quanta.q_inductor(chips)"
			("LOCATION" "PL20")
		)
		("@s9s_mb_2u_lib.s9s_mb_2u(sch_1):page595_i19@pure_quanta.q_res(chips)"
			("LOCATION" "PR250")
		)
		("@s9s_mb_2u_lib.s9s_mb_2u(sch_1):page595_i55@pure_quanta.q_res(chips)"
			("LOCATION" "PR1728")
		)
		("@s9s_mb_2u_lib.s9s_mb_2u(sch_1):page593_i151@pure_quanta.q_cap(chips)"
			("LOCATION" "PC440")
		)
		("@s9s_mb_2u_lib.s9s_mb_2u(sch_1):page593_i164@pure_quanta.q_cap(chips)"
			("LOCATION" "PC441")
		)
		("@s9s_mb_2u_lib.s9s_mb_2u(sch_1):page593_i111@pure_quanta.q_cap(chips)"
			("LOCATION" "PC442_P1_1")
		)
		("@s9s_mb_2u_lib.s9s_mb_2u(sch_1):page593_i171@pure_quanta.q_cap(chips)"
			("LOCATION" "PC443_P1_2")
		)
		("@s9s_mb_2u_lib.s9s_mb_2u(sch_1):page593_i112@pure_quanta.q_cap(chips)"
			("LOCATION" "PC444_P1_1")
		)
		("@s9s_mb_2u_lib.s9s_mb_2u(sch_1):page593_i170@pure_quanta.q_cap(chips)"
			("LOCATION" "PC445_P1_2")
		)
		("@s9s_mb_2u_lib.s9s_mb_2u(sch_1):page593_i225@pure_quanta.q_cap(chips)"
			("LOCATION" "PC446")
		)
		("@s9s_mb_2u_lib.s9s_mb_2u(sch_1):page593_i226@pure_quanta.q_cap(chips)"
			("LOCATION" "PC447")
		)
		("@s9s_mb_2u_lib.s9s_mb_2u(sch_1):page593_i113@pure_quanta.q_cap(chips)"
			("LOCATION" "PC448_P1_1")
		)
		("@s9s_mb_2u_lib.s9s_mb_2u(sch_1):page593_i172@pure_quanta.q_cap(chips)"
			("LOCATION" "PC449_P1_2")
		)
		("@s9s_mb_2u_lib.s9s_mb_2u(sch_1):page593_i115@pure_quanta.q_cap(chips)"
			("LOCATION" "PC450_P1_1")
		)
		("@s9s_mb_2u_lib.s9s_mb_2u(sch_1):page593_i173@pure_quanta.q_cap(chips)"
			("LOCATION" "PC451_P1_2")
		)
		("@s9s_mb_2u_lib.s9s_mb_2u(sch_1):page593_i105@pure_quanta.q_cap(chips)"
			("LOCATION" "PC452_P1_1")
		)
		("@s9s_mb_2u_lib.s9s_mb_2u(sch_1):page593_i125@pure_quanta.q_cap(chips)"
			("LOCATION" "PC455_P1_1")
		)
		("@s9s_mb_2u_lib.s9s_mb_2u(sch_1):page593_i177@pure_quanta.q_cap(chips)"
			("LOCATION" "PC456_P1_2")
		)
		("@s9s_mb_2u_lib.s9s_mb_2u(sch_1):page593_i126@pure_quanta.q_cap(chips)"
			("LOCATION" "PC457_P1_1")
		)
		("@s9s_mb_2u_lib.s9s_mb_2u(sch_1):page593_i178@pure_quanta.q_cap(chips)"
			("LOCATION" "PC458_P1_2")
		)
		("@s9s_mb_2u_lib.s9s_mb_2u(sch_1):page593_i142@pure_quanta.q_capp(chips)"
			("LOCATION" "PC460")
		)
		("@s9s_mb_2u_lib.s9s_mb_2u(sch_1):page593_i143@pure_quanta.q_capp(chips)"
			("LOCATION" "PC461")
		)
		("@s9s_mb_2u_lib.s9s_mb_2u(sch_1):page593_i209@pure_quanta.q_capp(chips)"
			("LOCATION" "PC1588")
		)
		("@s9s_mb_2u_lib.s9s_mb_2u(sch_1):page593_i210@pure_quanta.q_capp(chips)"
			("LOCATION" "PC1593")
		)
		("@s9s_mb_2u_lib.s9s_mb_2u(sch_1):page593_i206@pure_quanta.q_capp(chips)"
			("LOCATION" "PC1594")
		)
		("@s9s_mb_2u_lib.s9s_mb_2u(sch_1):page593_i207@pure_quanta.q_capp(chips)"
			("LOCATION" "PC1595")
		)
		("@s9s_mb_2u_lib.s9s_mb_2u(sch_1):page593_i205@pure_quanta.q_capp(chips)"
			("LOCATION" "PC1596")
		)
		("@s9s_mb_2u_lib.s9s_mb_2u(sch_1):page593_i150@pure_quanta.q_inductor(chips)"
			("LOCATION" "PL21")
		)
		("@s9s_mb_2u_lib.s9s_mb_2u(sch_1):page593_i182@pure_quanta.q_inductor(chips)"
			("LOCATION" "PL22")
		)
		("@s9s_mb_2u_lib.s9s_mb_2u(sch_1):page593_i141@pure_quanta.q_inductor(chips)"
			("LOCATION" "PL23")
		)
		("@s9s_mb_2u_lib.s9s_mb_2u(sch_1):page593_i154@pure_quanta.q_res(chips)"
			("LOCATION" "PR254")
		)
		("@s9s_mb_2u_lib.s9s_mb_2u(sch_1):page593_i165@pure_quanta.q_res(chips)"
			("LOCATION" "PR255")
		)
		("@s9s_mb_2u_lib.s9s_mb_2u(sch_1):page593_i228@pure_quanta.q_res(chips)"
			("LOCATION" "PR1726")
		)
		("@s9s_mb_2u_lib.s9s_mb_2u(sch_1):page593_i230@pure_quanta.q_res(chips)"
			("LOCATION" "PR1727")
		)
		("@s9s_mb_2u_lib.s9s_mb_2u(sch_1):page591_i318@pure_quanta.q_cap(chips)"
			("LOCATION" "PC467")
		)
		("@s9s_mb_2u_lib.s9s_mb_2u(sch_1):page591_i218@pure_quanta.q_cap(chips)"
			("LOCATION" "PC470")
		)
		("@s9s_mb_2u_lib.s9s_mb_2u(sch_1):page591_i219@pure_quanta.q_cap(chips)"
			("LOCATION" "PC471")
		)
		("@s9s_mb_2u_lib.s9s_mb_2u(sch_1):page591_i302@pure_quanta.q_cap(chips)"
			("LOCATION" "PC472")
		)
		("@s9s_mb_2u_lib.s9s_mb_2u(sch_1):page591_i307@pure_quanta.q_cap(chips)"
			("LOCATION" "PC473")
		)
		("@s9s_mb_2u_lib.s9s_mb_2u(sch_1):page591_i313@pure_quanta.q_cap(chips)"
			("LOCATION" "PC474")
		)
		("@s9s_mb_2u_lib.s9s_mb_2u(sch_1):page591_i333@pure_quanta.q_cap(chips)"
			("LOCATION" "PC476")
		)
		("@s9s_mb_2u_lib.s9s_mb_2u(sch_1):page591_i334@pure_quanta.q_cap(chips)"
			("LOCATION" "PC478")
		)
		("@s9s_mb_2u_lib.s9s_mb_2u(sch_1):page591_i339@pure_quanta.q_cap(chips)"
			("LOCATION" "PC1193")
		)
		("@s9s_mb_2u_lib.s9s_mb_2u(sch_1):page591_i253@pure_quanta.q_short(chips)"
			("LOCATION" "PJ50")
		)
		("@s9s_mb_2u_lib.s9s_mb_2u(sch_1):page591_i262@pure_quanta.q_short(chips)"
			("LOCATION" "PJ51")
		)
		("@s9s_mb_2u_lib.s9s_mb_2u(sch_1):page591_i322@pure_quanta.q_res(chips)"
			("LOCATION" "PR258")
		)
		("@s9s_mb_2u_lib.s9s_mb_2u(sch_1):page591_i320@pure_quanta.q_res(chips)"
			("LOCATION" "PR260")
		)
		("@s9s_mb_2u_lib.s9s_mb_2u(sch_1):page591_i314@pure_quanta.q_res(chips)"
			("LOCATION" "PR261")
		)
		("@s9s_mb_2u_lib.s9s_mb_2u(sch_1):page591_i216@pure_quanta.q_res(chips)"
			("LOCATION" "PR262")
		)
		("@s9s_mb_2u_lib.s9s_mb_2u(sch_1):page591_i215@pure_quanta.q_res(chips)"
			("LOCATION" "PR263")
		)
		("@s9s_mb_2u_lib.s9s_mb_2u(sch_1):page591_i214@pure_quanta.q_res(chips)"
			("LOCATION" "PR264")
		)
		("@s9s_mb_2u_lib.s9s_mb_2u(sch_1):page591_i222@pure_quanta.q_res(chips)"
			("LOCATION" "PR265")
		)
		("@s9s_mb_2u_lib.s9s_mb_2u(sch_1):page591_i223@pure_quanta.q_res(chips)"
			("LOCATION" "PR266")
		)
		("@s9s_mb_2u_lib.s9s_mb_2u(sch_1):page591_i213@pure_quanta.q_res(chips)"
			("LOCATION" "PR267")
		)
		("@s9s_mb_2u_lib.s9s_mb_2u(sch_1):page591_i226@pure_quanta.q_res(chips)"
			("LOCATION" "PR268")
		)
		("@s9s_mb_2u_lib.s9s_mb_2u(sch_1):page591_i227@pure_quanta.q_res(chips)"
			("LOCATION" "PR269")
		)
		("@s9s_mb_2u_lib.s9s_mb_2u(sch_1):page591_i306@pure_quanta.q_res(chips)"
			("LOCATION" "PR270")
		)
		("@s9s_mb_2u_lib.s9s_mb_2u(sch_1):page591_i304@pure_quanta.q_res(chips)"
			("LOCATION" "PR271")
		)
		("@s9s_mb_2u_lib.s9s_mb_2u(sch_1):page591_i301@pure_quanta.q_res(chips)"
			("LOCATION" "PR272")
		)
		("@s9s_mb_2u_lib.s9s_mb_2u(sch_1):page591_i250@pure_quanta.q_res(chips)"
			("LOCATION" "PR273")
		)
		("@s9s_mb_2u_lib.s9s_mb_2u(sch_1):page591_i259@pure_quanta.q_res(chips)"
			("LOCATION" "PR274")
		)
		("@s9s_mb_2u_lib.s9s_mb_2u(sch_1):page591_i317@pure_quanta.q_res(chips)"
			("LOCATION" "PR275")
		)
		("@s9s_mb_2u_lib.s9s_mb_2u(sch_1):page591_i316@pure_quanta.q_res(chips)"
			("LOCATION" "PR276")
		)
		("@s9s_mb_2u_lib.s9s_mb_2u(sch_1):page591_i335@pure_quanta.q_res(chips)"
			("LOCATION" "PR283")
		)
		("@s9s_mb_2u_lib.s9s_mb_2u(sch_1):page591_i386@pure_quanta.q_res(chips)"
			("LOCATION" "PR284")
		)
		("@s9s_mb_2u_lib.s9s_mb_2u(sch_1):page591_i256@pure_quanta.q_res(chips)"
			("LOCATION" "PR566")
		)
		("@s9s_mb_2u_lib.s9s_mb_2u(sch_1):page591_i265@pure_quanta.q_res(chips)"
			("LOCATION" "PR567")
		)
		("@s9s_mb_2u_lib.s9s_mb_2u(sch_1):page591_i252@pure_quanta.q_res(chips)"
			("LOCATION" "PR568")
		)
		("@s9s_mb_2u_lib.s9s_mb_2u(sch_1):page591_i261@pure_quanta.q_res(chips)"
			("LOCATION" "PR569")
		)
		("@s9s_mb_2u_lib.s9s_mb_2u(sch_1):page591_i297@pure_quanta.q_res(chips)"
			("LOCATION" "PR570")
		)
		("@s9s_mb_2u_lib.s9s_mb_2u(sch_1):page591_i298@pure_quanta.q_res(chips)"
			("LOCATION" "PR571")
		)
		("@s9s_mb_2u_lib.s9s_mb_2u(sch_1):page591_i409@pure_quanta.q_res(chips)"
			("LOCATION" "R1768")
		)
		("@s9s_mb_2u_lib.s9s_mb_2u(sch_1):page591_i410@pure_quanta.q_res(chips)"
			("LOCATION" "R1769")
		)
		("@s9s_mb_2u_lib.s9s_mb_2u(sch_1):page589_i9@pure_quanta.q_cap(chips)"
			("LOCATION" "PC479")
		)
		("@s9s_mb_2u_lib.s9s_mb_2u(sch_1):page589_i21@pure_quanta.q_cap(chips)"
			("LOCATION" "PC480")
		)
		("@s9s_mb_2u_lib.s9s_mb_2u(sch_1):page589_i11@pure_quanta.q_cap(chips)"
			("LOCATION" "PC481_P1_8")
		)
		("@s9s_mb_2u_lib.s9s_mb_2u(sch_1):page589_i23@pure_quanta.q_cap(chips)"
			("LOCATION" "PC482_P1_7")
		)
		("@s9s_mb_2u_lib.s9s_mb_2u(sch_1):page589_i29@pure_quanta.q_cap(chips)"
			("LOCATION" "PC483_P1_8")
		)
		("@s9s_mb_2u_lib.s9s_mb_2u(sch_1):page589_i44@pure_quanta.q_cap(chips)"
			("LOCATION" "PC484_P1_7")
		)
		("@s9s_mb_2u_lib.s9s_mb_2u(sch_1):page589_i30@pure_quanta.q_cap(chips)"
			("LOCATION" "PC485_P1_8")
		)
		("@s9s_mb_2u_lib.s9s_mb_2u(sch_1):page589_i46@pure_quanta.q_cap(chips)"
			("LOCATION" "PC486_P1_7")
		)
		("@s9s_mb_2u_lib.s9s_mb_2u(sch_1):page589_i79@pure_quanta.q_cap(chips)"
			("LOCATION" "PC487")
		)
		("@s9s_mb_2u_lib.s9s_mb_2u(sch_1):page589_i80@pure_quanta.q_cap(chips)"
			("LOCATION" "PC488")
		)
		("@s9s_mb_2u_lib.s9s_mb_2u(sch_1):page589_i33@pure_quanta.q_cap(chips)"
			("LOCATION" "PC489_P1_8")
		)
		("@s9s_mb_2u_lib.s9s_mb_2u(sch_1):page589_i49@pure_quanta.q_cap(chips)"
			("LOCATION" "PC490_P1_7")
		)
		("@s9s_mb_2u_lib.s9s_mb_2u(sch_1):page589_i34@pure_quanta.q_cap(chips)"
			("LOCATION" "PC491_P1_8")
		)
		("@s9s_mb_2u_lib.s9s_mb_2u(sch_1):page589_i50@pure_quanta.q_cap(chips)"
			("LOCATION" "PC492_P1_7")
		)
		("@s9s_mb_2u_lib.s9s_mb_2u(sch_1):page589_i35@pure_quanta.q_cap(chips)"
			("LOCATION" "PC493_P1_8")
		)
		("@s9s_mb_2u_lib.s9s_mb_2u(sch_1):page589_i51@pure_quanta.q_cap(chips)"
			("LOCATION" "PC494_P1_7")
		)
		("@s9s_mb_2u_lib.s9s_mb_2u(sch_1):page589_i37@pure_quanta.q_cap(chips)"
			("LOCATION" "PC495_P1_8")
		)
		("@s9s_mb_2u_lib.s9s_mb_2u(sch_1):page589_i52@pure_quanta.q_cap(chips)"
			("LOCATION" "PC496_P1_7")
		)
		("@s9s_mb_2u_lib.s9s_mb_2u(sch_1):page589_i39@pure_quanta.q_cap(chips)"
			("LOCATION" "PC497_P1_8")
		)
		("@s9s_mb_2u_lib.s9s_mb_2u(sch_1):page589_i53@pure_quanta.q_cap(chips)"
			("LOCATION" "PC498_P1_7")
		)
		("@s9s_mb_2u_lib.s9s_mb_2u(sch_1):page589_i41@pure_quanta.q_cap(chips)"
			("LOCATION" "PC499_P1_8")
		)
		("@s9s_mb_2u_lib.s9s_mb_2u(sch_1):page589_i55@pure_quanta.q_cap(chips)"
			("LOCATION" "PC500_P1_7")
		)
		("@s9s_mb_2u_lib.s9s_mb_2u(sch_1):page589_i32@pure_quanta.q_inductor(chips)"
			("LOCATION" "PL24")
		)
		("@s9s_mb_2u_lib.s9s_mb_2u(sch_1):page589_i48@pure_quanta.q_inductor(chips)"
			("LOCATION" "PL25")
		)
		("@s9s_mb_2u_lib.s9s_mb_2u(sch_1):page589_i2@pure_quanta.q_res(chips)"
			("LOCATION" "PR285")
		)
		("@s9s_mb_2u_lib.s9s_mb_2u(sch_1):page589_i16@pure_quanta.q_res(chips)"
			("LOCATION" "PR286")
		)
		("@s9s_mb_2u_lib.s9s_mb_2u(sch_1):page589_i10@pure_quanta.q_res(chips)"
			("LOCATION" "PR287")
		)
		("@s9s_mb_2u_lib.s9s_mb_2u(sch_1):page589_i22@pure_quanta.q_res(chips)"
			("LOCATION" "PR288")
		)
		("@s9s_mb_2u_lib.s9s_mb_2u(sch_1):page588_i18@pure_quanta.q_cap(chips)"
			("LOCATION" "PC501")
		)
		("@s9s_mb_2u_lib.s9s_mb_2u(sch_1):page588_i31@pure_quanta.q_cap(chips)"
			("LOCATION" "PC502")
		)
		("@s9s_mb_2u_lib.s9s_mb_2u(sch_1):page588_i26@pure_quanta.q_cap(chips)"
			("LOCATION" "PC503_P1_6")
		)
		("@s9s_mb_2u_lib.s9s_mb_2u(sch_1):page588_i35@pure_quanta.q_cap(chips)"
			("LOCATION" "PC504_P1_5")
		)
		("@s9s_mb_2u_lib.s9s_mb_2u(sch_1):page588_i37@pure_quanta.q_cap(chips)"
			("LOCATION" "PC505_P1_6")
		)
		("@s9s_mb_2u_lib.s9s_mb_2u(sch_1):page588_i43@pure_quanta.q_cap(chips)"
			("LOCATION" "PC506_P1_5")
		)
		("@s9s_mb_2u_lib.s9s_mb_2u(sch_1):page588_i38@pure_quanta.q_cap(chips)"
			("LOCATION" "PC507_P1_6")
		)
		("@s9s_mb_2u_lib.s9s_mb_2u(sch_1):page588_i44@pure_quanta.q_cap(chips)"
			("LOCATION" "PC508_P1_5")
		)
		("@s9s_mb_2u_lib.s9s_mb_2u(sch_1):page588_i79@pure_quanta.q_cap(chips)"
			("LOCATION" "PC509")
		)
		("@s9s_mb_2u_lib.s9s_mb_2u(sch_1):page588_i80@pure_quanta.q_cap(chips)"
			("LOCATION" "PC510")
		)
		("@s9s_mb_2u_lib.s9s_mb_2u(sch_1):page588_i39@pure_quanta.q_cap(chips)"
			("LOCATION" "PC511_P1_6")
		)
		("@s9s_mb_2u_lib.s9s_mb_2u(sch_1):page588_i45@pure_quanta.q_cap(chips)"
			("LOCATION" "PC512_P1_5")
		)
		("@s9s_mb_2u_lib.s9s_mb_2u(sch_1):page588_i46@pure_quanta.q_cap(chips)"
			("LOCATION" "PC513_P1_6")
		)
		("@s9s_mb_2u_lib.s9s_mb_2u(sch_1):page588_i51@pure_quanta.q_cap(chips)"
			("LOCATION" "PC514_P1_5")
		)
		("@s9s_mb_2u_lib.s9s_mb_2u(sch_1):page588_i47@pure_quanta.q_cap(chips)"
			("LOCATION" "PC515_P1_6")
		)
		("@s9s_mb_2u_lib.s9s_mb_2u(sch_1):page588_i52@pure_quanta.q_cap(chips)"
			("LOCATION" "PC516_P1_5")
		)
		("@s9s_mb_2u_lib.s9s_mb_2u(sch_1):page588_i14@pure_quanta.q_cap(chips)"
			("LOCATION" "PC519_P1_6")
		)
		("@s9s_mb_2u_lib.s9s_mb_2u(sch_1):page588_i55@pure_quanta.q_cap(chips)"
			("LOCATION" "PC520_P1_5")
		)
		("@s9s_mb_2u_lib.s9s_mb_2u(sch_1):page588_i15@pure_quanta.q_cap(chips)"
			("LOCATION" "PC521_P1_6")
		)
		("@s9s_mb_2u_lib.s9s_mb_2u(sch_1):page588_i56@pure_quanta.q_cap(chips)"
			("LOCATION" "PC522_P1_5")
		)
		("@s9s_mb_2u_lib.s9s_mb_2u(sch_1):page588_i12@pure_quanta.q_inductor(chips)"
			("LOCATION" "PL26")
		)
		("@s9s_mb_2u_lib.s9s_mb_2u(sch_1):page588_i40@pure_quanta.q_inductor(chips)"
			("LOCATION" "PL27")
		)
		("@s9s_mb_2u_lib.s9s_mb_2u(sch_1):page588_i2@pure_quanta.q_res(chips)"
			("LOCATION" "PR291")
		)
		("@s9s_mb_2u_lib.s9s_mb_2u(sch_1):page588_i22@pure_quanta.q_res(chips)"
			("LOCATION" "PR292")
		)
		("@s9s_mb_2u_lib.s9s_mb_2u(sch_1):page588_i19@pure_quanta.q_res(chips)"
			("LOCATION" "PR293")
		)
		("@s9s_mb_2u_lib.s9s_mb_2u(sch_1):page588_i32@pure_quanta.q_res(chips)"
			("LOCATION" "PR294")
		)
		("@s9s_mb_2u_lib.s9s_mb_2u(sch_1):page587_i8@pure_quanta.q_cap(chips)"
			("LOCATION" "PC523")
		)
		("@s9s_mb_2u_lib.s9s_mb_2u(sch_1):page587_i18@pure_quanta.q_cap(chips)"
			("LOCATION" "PC524")
		)
		("@s9s_mb_2u_lib.s9s_mb_2u(sch_1):page587_i24@pure_quanta.q_cap(chips)"
			("LOCATION" "PC525_P1_4")
		)
		("@s9s_mb_2u_lib.s9s_mb_2u(sch_1):page587_i40@pure_quanta.q_cap(chips)"
			("LOCATION" "PC526_P1_3")
		)
		("@s9s_mb_2u_lib.s9s_mb_2u(sch_1):page587_i27@pure_quanta.q_cap(chips)"
			("LOCATION" "PC527_P1_4")
		)
		("@s9s_mb_2u_lib.s9s_mb_2u(sch_1):page587_i43@pure_quanta.q_cap(chips)"
			("LOCATION" "PC528_P1_3")
		)
		("@s9s_mb_2u_lib.s9s_mb_2u(sch_1):page587_i32@pure_quanta.q_cap(chips)"
			("LOCATION" "PC529_P1_4")
		)
		("@s9s_mb_2u_lib.s9s_mb_2u(sch_1):page587_i44@pure_quanta.q_cap(chips)"
			("LOCATION" "PC530_P1_3")
		)
		("@s9s_mb_2u_lib.s9s_mb_2u(sch_1):page587_i92@pure_quanta.q_cap(chips)"
			("LOCATION" "PC531")
		)
		("@s9s_mb_2u_lib.s9s_mb_2u(sch_1):page587_i93@pure_quanta.q_cap(chips)"
			("LOCATION" "PC532")
		)
		("@s9s_mb_2u_lib.s9s_mb_2u(sch_1):page587_i33@pure_quanta.q_cap(chips)"
			("LOCATION" "PC533_P1_4")
		)
		("@s9s_mb_2u_lib.s9s_mb_2u(sch_1):page587_i45@pure_quanta.q_cap(chips)"
			("LOCATION" "PC534_P1_3")
		)
		("@s9s_mb_2u_lib.s9s_mb_2u(sch_1):page587_i34@pure_quanta.q_cap(chips)"
			("LOCATION" "PC535_P1_4")
		)
		("@s9s_mb_2u_lib.s9s_mb_2u(sch_1):page587_i47@pure_quanta.q_cap(chips)"
			("LOCATION" "PC536_P1_3")
		)
		("@s9s_mb_2u_lib.s9s_mb_2u(sch_1):page587_i35@pure_quanta.q_cap(chips)"
			("LOCATION" "PC537_P1_4")
		)
		("@s9s_mb_2u_lib.s9s_mb_2u(sch_1):page587_i48@pure_quanta.q_cap(chips)"
			("LOCATION" "PC538_P1_3")
		)
		("@s9s_mb_2u_lib.s9s_mb_2u(sch_1):page587_i51@pure_quanta.q_cap(chips)"
			("LOCATION" "PC541_P1_4")
		)
		("@s9s_mb_2u_lib.s9s_mb_2u(sch_1):page587_i57@pure_quanta.q_cap(chips)"
			("LOCATION" "PC542_P1_3")
		)
		("@s9s_mb_2u_lib.s9s_mb_2u(sch_1):page587_i52@pure_quanta.q_cap(chips)"
			("LOCATION" "PC543_P1_4")
		)
		("@s9s_mb_2u_lib.s9s_mb_2u(sch_1):page587_i58@pure_quanta.q_cap(chips)"
			("LOCATION" "PC544_P1_3")
		)
		("@s9s_mb_2u_lib.s9s_mb_2u(sch_1):page587_i30@pure_quanta.q_inductor(chips)"
			("LOCATION" "PL28")
		)
		("@s9s_mb_2u_lib.s9s_mb_2u(sch_1):page587_i42@pure_quanta.q_inductor(chips)"
			("LOCATION" "PL29")
		)
		("@s9s_mb_2u_lib.s9s_mb_2u(sch_1):page587_i2@pure_quanta.q_res(chips)"
			("LOCATION" "PR297")
		)
		("@s9s_mb_2u_lib.s9s_mb_2u(sch_1):page587_i12@pure_quanta.q_res(chips)"
			("LOCATION" "PR298")
		)
		("@s9s_mb_2u_lib.s9s_mb_2u(sch_1):page587_i9@pure_quanta.q_res(chips)"
			("LOCATION" "PR299")
		)
		("@s9s_mb_2u_lib.s9s_mb_2u(sch_1):page587_i19@pure_quanta.q_res(chips)"
			("LOCATION" "PR300")
		)
		("@s9s_mb_2u_lib.s9s_mb_2u(sch_1):page433_i150@pure_quanta.q_cap(chips)"
			("LOCATION" "PC545")
		)
		("@s9s_mb_2u_lib.s9s_mb_2u(sch_1):page433_i151@pure_quanta.q_cap(chips)"
			("LOCATION" "PC546")
		)
		("@s9s_mb_2u_lib.s9s_mb_2u(sch_1):page433_i20@pure_quanta.q_cap(chips)"
			("LOCATION" "PC547")
		)
		("@s9s_mb_2u_lib.s9s_mb_2u(sch_1):page433_i38@pure_quanta.q_cap(chips)"
			("LOCATION" "PC548")
		)
		("@s9s_mb_2u_lib.s9s_mb_2u(sch_1):page433_i128@pure_quanta.q_cap(chips)"
			("LOCATION" "PC550")
		)
		("@s9s_mb_2u_lib.s9s_mb_2u(sch_1):page433_i130@pure_quanta.q_cap(chips)"
			("LOCATION" "PC551")
		)
		("@s9s_mb_2u_lib.s9s_mb_2u(sch_1):page433_i94@pure_quanta.q_cap(chips)"
			("LOCATION" "PC552")
		)
		("@s9s_mb_2u_lib.s9s_mb_2u(sch_1):page433_i96@pure_quanta.q_cap(chips)"
			("LOCATION" "PC555")
		)
		("@s9s_mb_2u_lib.s9s_mb_2u(sch_1):page433_i115@pure_quanta.q_cap(chips)"
			("LOCATION" "PC1194")
		)
		("@s9s_mb_2u_lib.s9s_mb_2u(sch_1):page433_i33@pure_quanta.q_short(chips)"
			("LOCATION" "PJ52")
		)
		("@s9s_mb_2u_lib.s9s_mb_2u(sch_1):page433_i154@pure_quanta.q_res(chips)"
			("LOCATION" "PR303")
		)
		("@s9s_mb_2u_lib.s9s_mb_2u(sch_1):page433_i153@pure_quanta.q_res(chips)"
			("LOCATION" "PR304")
		)
		("@s9s_mb_2u_lib.s9s_mb_2u(sch_1):page433_i1@pure_quanta.q_res(chips)"
			("LOCATION" "PR305")
		)
		("@s9s_mb_2u_lib.s9s_mb_2u(sch_1):page433_i25@pure_quanta.q_res(chips)"
			("LOCATION" "PR306")
		)
		("@s9s_mb_2u_lib.s9s_mb_2u(sch_1):page433_i126@pure_quanta.q_res(chips)"
			("LOCATION" "PR307")
		)
		("@s9s_mb_2u_lib.s9s_mb_2u(sch_1):page433_i123@pure_quanta.q_res(chips)"
			("LOCATION" "PR308")
		)
		("@s9s_mb_2u_lib.s9s_mb_2u(sch_1):page433_i122@pure_quanta.q_res(chips)"
			("LOCATION" "PR309")
		)
		("@s9s_mb_2u_lib.s9s_mb_2u(sch_1):page433_i52@pure_quanta.q_res(chips)"
			("LOCATION" "PR310")
		)
		("@s9s_mb_2u_lib.s9s_mb_2u(sch_1):page433_i120@pure_quanta.q_res(chips)"
			("LOCATION" "PR311")
		)
		("@s9s_mb_2u_lib.s9s_mb_2u(sch_1):page433_i121@pure_quanta.q_res(chips)"
			("LOCATION" "PR312")
		)
		("@s9s_mb_2u_lib.s9s_mb_2u(sch_1):page433_i37@pure_quanta.q_res(chips)"
			("LOCATION" "PR313")
		)
		("@s9s_mb_2u_lib.s9s_mb_2u(sch_1):page433_i132@pure_quanta.q_res(chips)"
			("LOCATION" "PR314")
		)
		("@s9s_mb_2u_lib.s9s_mb_2u(sch_1):page433_i133@pure_quanta.q_res(chips)"
			("LOCATION" "PR315")
		)
		("@s9s_mb_2u_lib.s9s_mb_2u(sch_1):page433_i34@pure_quanta.q_res(chips)"
			("LOCATION" "PR316")
		)
		("@s9s_mb_2u_lib.s9s_mb_2u(sch_1):page433_i134@pure_quanta.q_res(chips)"
			("LOCATION" "PR317")
		)
		("@s9s_mb_2u_lib.s9s_mb_2u(sch_1):page433_i35@pure_quanta.q_res(chips)"
			("LOCATION" "PR319")
		)
		("@s9s_mb_2u_lib.s9s_mb_2u(sch_1):page433_i171@pure_quanta.q_res(chips)"
			("LOCATION" "PR321")
		)
		("@s9s_mb_2u_lib.s9s_mb_2u(sch_1):page433_i100@pure_quanta.q_res(chips)"
			("LOCATION" "PR323")
		)
		("@s9s_mb_2u_lib.s9s_mb_2u(sch_1):page433_i82@pure_quanta.q_res(chips)"
			("LOCATION" "PR324")
		)
		("@s9s_mb_2u_lib.s9s_mb_2u(sch_1):page433_i136@pure_quanta.q_res(chips)"
			("LOCATION" "PR574")
		)
		("@s9s_mb_2u_lib.s9s_mb_2u(sch_1):page433_i143@pure_quanta.q_res(chips)"
			("LOCATION" "PR575")
		)
		("@s9s_mb_2u_lib.s9s_mb_2u(sch_1):page433_i141@pure_quanta.q_res(chips)"
			("LOCATION" "PR576")
		)
		("@s9s_mb_2u_lib.s9s_mb_2u(sch_1):page433_i147@pure_quanta.q_res(chips)"
			("LOCATION" "PR577")
		)
		("@s9s_mb_2u_lib.s9s_mb_2u(sch_1):page433_i138@pure_quanta.q_res(chips)"
			("LOCATION" "PR578")
		)
		("@s9s_mb_2u_lib.s9s_mb_2u(sch_1):page446_i192@pure_quanta.q_cap(chips)"
			("LOCATION" "PC591")
		)
		("@s9s_mb_2u_lib.s9s_mb_2u(sch_1):page446_i138@pure_quanta.q_cap(chips)"
			("LOCATION" "PC592")
		)
		("@s9s_mb_2u_lib.s9s_mb_2u(sch_1):page446_i142@pure_quanta.q_cap(chips)"
			("LOCATION" "PC593")
		)
		("@s9s_mb_2u_lib.s9s_mb_2u(sch_1):page446_i189@pure_quanta.q_cap(chips)"
			("LOCATION" "PC595")
		)
		("@s9s_mb_2u_lib.s9s_mb_2u(sch_1):page446_i174@pure_quanta.q_cap(chips)"
			("LOCATION" "PC596")
		)
		("@s9s_mb_2u_lib.s9s_mb_2u(sch_1):page446_i175@pure_quanta.q_cap(chips)"
			("LOCATION" "PC599")
		)
		("@s9s_mb_2u_lib.s9s_mb_2u(sch_1):page446_i173@pure_quanta.q_cap(chips)"
			("LOCATION" "PC1195")
		)
		("@s9s_mb_2u_lib.s9s_mb_2u(sch_1):page446_i129@pure_quanta.q_short(chips)"
			("LOCATION" "PJ53")
		)
		("@s9s_mb_2u_lib.s9s_mb_2u(sch_1):page446_i198@pure_quanta.q_res(chips)"
			("LOCATION" "PR331")
		)
		("@s9s_mb_2u_lib.s9s_mb_2u(sch_1):page446_i194@pure_quanta.q_res(chips)"
			("LOCATION" "PR333")
		)
		("@s9s_mb_2u_lib.s9s_mb_2u(sch_1):page446_i195@pure_quanta.q_res(chips)"
			("LOCATION" "PR334")
		)
		("@s9s_mb_2u_lib.s9s_mb_2u(sch_1):page446_i140@pure_quanta.q_res(chips)"
			("LOCATION" "PR335")
		)
		("@s9s_mb_2u_lib.s9s_mb_2u(sch_1):page446_i141@pure_quanta.q_res(chips)"
			("LOCATION" "PR336")
		)
		("@s9s_mb_2u_lib.s9s_mb_2u(sch_1):page446_i133@pure_quanta.q_res(chips)"
			("LOCATION" "PR337")
		)
		("@s9s_mb_2u_lib.s9s_mb_2u(sch_1):page446_i134@pure_quanta.q_res(chips)"
			("LOCATION" "PR338")
		)
		("@s9s_mb_2u_lib.s9s_mb_2u(sch_1):page446_i131@pure_quanta.q_res(chips)"
			("LOCATION" "PR339")
		)
		("@s9s_mb_2u_lib.s9s_mb_2u(sch_1):page446_i132@pure_quanta.q_res(chips)"
			("LOCATION" "PR340")
		)
		("@s9s_mb_2u_lib.s9s_mb_2u(sch_1):page446_i137@pure_quanta.q_res(chips)"
			("LOCATION" "PR341")
		)
		("@s9s_mb_2u_lib.s9s_mb_2u(sch_1):page446_i136@pure_quanta.q_res(chips)"
			("LOCATION" "PR342")
		)
		("@s9s_mb_2u_lib.s9s_mb_2u(sch_1):page446_i188@pure_quanta.q_res(chips)"
			("LOCATION" "PR343")
		)
		("@s9s_mb_2u_lib.s9s_mb_2u(sch_1):page446_i120@pure_quanta.q_res(chips)"
			("LOCATION" "PR344")
		)
		("@s9s_mb_2u_lib.s9s_mb_2u(sch_1):page446_i135@pure_quanta.q_res(chips)"
			("LOCATION" "PR345")
		)
		("@s9s_mb_2u_lib.s9s_mb_2u(sch_1):page446_i122@pure_quanta.q_res(chips)"
			("LOCATION" "PR346")
		)
		("@s9s_mb_2u_lib.s9s_mb_2u(sch_1):page446_i191@pure_quanta.q_res(chips)"
			("LOCATION" "PR347")
		)
		("@s9s_mb_2u_lib.s9s_mb_2u(sch_1):page446_i184@pure_quanta.q_res(chips)"
			("LOCATION" "PR351")
		)
		("@s9s_mb_2u_lib.s9s_mb_2u(sch_1):page446_i167@pure_quanta.q_res(chips)"
			("LOCATION" "PR352")
		)
		("@s9s_mb_2u_lib.s9s_mb_2u(sch_1):page446_i117@pure_quanta.q_res(chips)"
			("LOCATION" "PR586")
		)
		("@s9s_mb_2u_lib.s9s_mb_2u(sch_1):page446_i128@pure_quanta.q_res(chips)"
			("LOCATION" "PR587")
		)
		("@s9s_mb_2u_lib.s9s_mb_2u(sch_1):page446_i215@pure_quanta.q_res(chips)"
			("LOCATION" "PR1308")
		)
		("@s9s_mb_2u_lib.s9s_mb_2u(sch_1):page446_i221@pure_quanta.q_res(chips)"
			("LOCATION" "R1767")
		)
		("@s9s_mb_2u_lib.s9s_mb_2u(sch_1):page446_i222@pure_quanta.q_res(chips)"
			("LOCATION" "R1772")
		)
		("@s9s_mb_2u_lib.s9s_mb_2u(sch_1):page447_i18@pure_quanta.q_cap(chips)"
			("LOCATION" "PC600")
		)
		("@s9s_mb_2u_lib.s9s_mb_2u(sch_1):page447_i7@pure_quanta.q_cap(chips)"
			("LOCATION" "PC601")
		)
		("@s9s_mb_2u_lib.s9s_mb_2u(sch_1):page447_i36@pure_quanta.q_cap(chips)"
			("LOCATION" "PC602_P0_1")
		)
		("@s9s_mb_2u_lib.s9s_mb_2u(sch_1):page447_i25@pure_quanta.q_cap(chips)"
			("LOCATION" "PC603_P0_2")
		)
		("@s9s_mb_2u_lib.s9s_mb_2u(sch_1):page447_i37@pure_quanta.q_cap(chips)"
			("LOCATION" "PC604_P0_1")
		)
		("@s9s_mb_2u_lib.s9s_mb_2u(sch_1):page447_i26@pure_quanta.q_cap(chips)"
			("LOCATION" "PC605_P0_2")
		)
		("@s9s_mb_2u_lib.s9s_mb_2u(sch_1):page447_i102@pure_quanta.q_cap(chips)"
			("LOCATION" "PC606")
		)
		("@s9s_mb_2u_lib.s9s_mb_2u(sch_1):page447_i101@pure_quanta.q_cap(chips)"
			("LOCATION" "PC607")
		)
		("@s9s_mb_2u_lib.s9s_mb_2u(sch_1):page447_i38@pure_quanta.q_cap(chips)"
			("LOCATION" "PC608_P0_1")
		)
		("@s9s_mb_2u_lib.s9s_mb_2u(sch_1):page447_i29@pure_quanta.q_cap(chips)"
			("LOCATION" "PC609_P0_2")
		)
		("@s9s_mb_2u_lib.s9s_mb_2u(sch_1):page447_i39@pure_quanta.q_cap(chips)"
			("LOCATION" "PC610_P0_1")
		)
		("@s9s_mb_2u_lib.s9s_mb_2u(sch_1):page447_i30@pure_quanta.q_cap(chips)"
			("LOCATION" "PC611_P0_2")
		)
		("@s9s_mb_2u_lib.s9s_mb_2u(sch_1):page447_i35@pure_quanta.q_cap(chips)"
			("LOCATION" "PC612_P0_1")
		)
		("@s9s_mb_2u_lib.s9s_mb_2u(sch_1):page447_i103@pure_quanta.q_cap(chips)"
			("LOCATION" "PC613_P0_2")
		)
		("@s9s_mb_2u_lib.s9s_mb_2u(sch_1):page447_i50@pure_quanta.q_cap(chips)"
			("LOCATION" "PC615_P0_1")
		)
		("@s9s_mb_2u_lib.s9s_mb_2u(sch_1):page447_i43@pure_quanta.q_cap(chips)"
			("LOCATION" "PC616_P0_2")
		)
		("@s9s_mb_2u_lib.s9s_mb_2u(sch_1):page447_i51@pure_quanta.q_cap(chips)"
			("LOCATION" "PC617_P0_1")
		)
		("@s9s_mb_2u_lib.s9s_mb_2u(sch_1):page447_i44@pure_quanta.q_cap(chips)"
			("LOCATION" "PC618_P0_2")
		)
		("@s9s_mb_2u_lib.s9s_mb_2u(sch_1):page447_i47@pure_quanta.q_capp(chips)"
			("LOCATION" "PC619")
		)
		("@s9s_mb_2u_lib.s9s_mb_2u(sch_1):page447_i48@pure_quanta.q_capp(chips)"
			("LOCATION" "PC620")
		)
		("@s9s_mb_2u_lib.s9s_mb_2u(sch_1):page447_i54@pure_quanta.q_capp(chips)"
			("LOCATION" "PC621")
		)
		("@s9s_mb_2u_lib.s9s_mb_2u(sch_1):page447_i61@pure_quanta.q_capp(chips)"
			("LOCATION" "PC622")
		)
		("@s9s_mb_2u_lib.s9s_mb_2u(sch_1):page447_i56@pure_quanta.q_capp(chips)"
			("LOCATION" "PC623")
		)
		("@s9s_mb_2u_lib.s9s_mb_2u(sch_1):page447_i65@pure_quanta.q_cap(chips)"
			("LOCATION" "PC1211_P0_1")
		)
		("@s9s_mb_2u_lib.s9s_mb_2u(sch_1):page447_i67@pure_quanta.q_cap(chips)"
			("LOCATION" "PC1212_P0_2")
		)
		("@s9s_mb_2u_lib.s9s_mb_2u(sch_1):page447_i90@pure_quanta.q_capp(chips)"
			("LOCATION" "PC2645")
		)
		("@s9s_mb_2u_lib.s9s_mb_2u(sch_1):page447_i88@pure_quanta.q_inductor(chips)"
			("LOCATION" "PL33")
		)
		("@s9s_mb_2u_lib.s9s_mb_2u(sch_1):page447_i89@pure_quanta.q_inductor(chips)"
			("LOCATION" "PL34")
		)
		("@s9s_mb_2u_lib.s9s_mb_2u(sch_1):page447_i59@pure_quanta.q_inductor(chips)"
			("LOCATION" "PL44")
		)
		("@s9s_mb_2u_lib.s9s_mb_2u(sch_1):page447_i70@pure_quanta.q_res(chips)"
			("LOCATION" "PR353")
		)
		("@s9s_mb_2u_lib.s9s_mb_2u(sch_1):page447_i12@pure_quanta.q_res(chips)"
			("LOCATION" "PR354")
		)
		("@s9s_mb_2u_lib.s9s_mb_2u(sch_1):page447_i19@pure_quanta.q_res(chips)"
			("LOCATION" "PR355")
		)
		("@s9s_mb_2u_lib.s9s_mb_2u(sch_1):page447_i9@pure_quanta.q_res(chips)"
			("LOCATION" "PR356")
		)
		("@s9s_mb_2u_lib.s9s_mb_2u(sch_1):page453_i134@pure_quanta.q_cap(chips)"
			("LOCATION" "PC633")
		)
		("@s9s_mb_2u_lib.s9s_mb_2u(sch_1):page453_i123@pure_quanta.q_cap(chips)"
			("LOCATION" "PC634")
		)
		("@s9s_mb_2u_lib.s9s_mb_2u(sch_1):page453_i122@pure_quanta.q_cap(chips)"
			("LOCATION" "PC635")
		)
		("@s9s_mb_2u_lib.s9s_mb_2u(sch_1):page453_i167@pure_quanta.q_cap(chips)"
			("LOCATION" "PC636")
		)
		("@s9s_mb_2u_lib.s9s_mb_2u(sch_1):page453_i120@pure_quanta.q_cap(chips)"
			("LOCATION" "PC637")
		)
		("@s9s_mb_2u_lib.s9s_mb_2u(sch_1):page453_i119@pure_quanta.q_cap(chips)"
			("LOCATION" "PC638")
		)
		("@s9s_mb_2u_lib.s9s_mb_2u(sch_1):page453_i128@pure_quanta.q_cap(chips)"
			("LOCATION" "PC639")
		)
		("@s9s_mb_2u_lib.s9s_mb_2u(sch_1):page453_i126@pure_quanta.q_cap(chips)"
			("LOCATION" "PC641")
		)
		("@s9s_mb_2u_lib.s9s_mb_2u(sch_1):page453_i125@pure_quanta.q_cap(chips)"
			("LOCATION" "PC642")
		)
		("@s9s_mb_2u_lib.s9s_mb_2u(sch_1):page453_i145@pure_quanta.q_capp(chips)"
			("LOCATION" "PC1644")
		)
		("@s9s_mb_2u_lib.s9s_mb_2u(sch_1):page453_i157@pure_quanta.q_capp(chips)"
			("LOCATION" "PC1645")
		)
		("@s9s_mb_2u_lib.s9s_mb_2u(sch_1):page453_i159@pure_quanta.q_capp(chips)"
			("LOCATION" "PC1910")
		)
		("@s9s_mb_2u_lib.s9s_mb_2u(sch_1):page453_i129@pure_quanta.q_inductor(chips)"
			("LOCATION" "PL35")
		)
		("@s9s_mb_2u_lib.s9s_mb_2u(sch_1):page453_i132@pure_quanta.q_res(chips)"
			("LOCATION" "PR380")
		)
		("@s9s_mb_2u_lib.s9s_mb_2u(sch_1):page453_i169@pure_quanta.q_res(chips)"
			("LOCATION" "PR2718")
		)
		("@s9s_mb_2u_lib.s9s_mb_2u(sch_1):page448_i21@pure_quanta.q_cap(chips)"
			("LOCATION" "PC1171")
		)
		("@s9s_mb_2u_lib.s9s_mb_2u(sch_1):page448_i9@pure_quanta.q_cap(chips)"
			("LOCATION" "PC1172")
		)
		("@s9s_mb_2u_lib.s9s_mb_2u(sch_1):page448_i50@pure_quanta.q_cap(chips)"
			("LOCATION" "PC1173_P0_3")
		)
		("@s9s_mb_2u_lib.s9s_mb_2u(sch_1):page448_i32@pure_quanta.q_cap(chips)"
			("LOCATION" "PC1174_P0_4")
		)
		("@s9s_mb_2u_lib.s9s_mb_2u(sch_1):page448_i51@pure_quanta.q_cap(chips)"
			("LOCATION" "PC1175_P0_3")
		)
		("@s9s_mb_2u_lib.s9s_mb_2u(sch_1):page448_i33@pure_quanta.q_cap(chips)"
			("LOCATION" "PC1176_P0_4")
		)
		("@s9s_mb_2u_lib.s9s_mb_2u(sch_1):page448_i111@pure_quanta.q_cap(chips)"
			("LOCATION" "PC1177")
		)
		("@s9s_mb_2u_lib.s9s_mb_2u(sch_1):page448_i112@pure_quanta.q_cap(chips)"
			("LOCATION" "PC1178")
		)
		("@s9s_mb_2u_lib.s9s_mb_2u(sch_1):page448_i52@pure_quanta.q_cap(chips)"
			("LOCATION" "PC1179_P0_3")
		)
		("@s9s_mb_2u_lib.s9s_mb_2u(sch_1):page448_i34@pure_quanta.q_cap(chips)"
			("LOCATION" "PC1180_P0_4")
		)
		("@s9s_mb_2u_lib.s9s_mb_2u(sch_1):page448_i53@pure_quanta.q_cap(chips)"
			("LOCATION" "PC1181_P0_3")
		)
		("@s9s_mb_2u_lib.s9s_mb_2u(sch_1):page448_i39@pure_quanta.q_cap(chips)"
			("LOCATION" "PC1182_P0_4")
		)
		("@s9s_mb_2u_lib.s9s_mb_2u(sch_1):page448_i94@pure_quanta.q_capp(chips)"
			("LOCATION" "PC1183")
		)
		("@s9s_mb_2u_lib.s9s_mb_2u(sch_1):page448_i47@pure_quanta.q_cap(chips)"
			("LOCATION" "PC1183_P0_3")
		)
		("@s9s_mb_2u_lib.s9s_mb_2u(sch_1):page448_i113@pure_quanta.q_cap(chips)"
			("LOCATION" "PC1183_P0_4")
		)
		("@s9s_mb_2u_lib.s9s_mb_2u(sch_1):page448_i95@pure_quanta.q_capp(chips)"
			("LOCATION" "PC1185")
		)
		("@s9s_mb_2u_lib.s9s_mb_2u(sch_1):page448_i48@pure_quanta.q_cap(chips)"
			("LOCATION" "PC1185_P0_3")
		)
		("@s9s_mb_2u_lib.s9s_mb_2u(sch_1):page448_i96@pure_quanta.q_capp(chips)"
			("LOCATION" "PC1186")
		)
		("@s9s_mb_2u_lib.s9s_mb_2u(sch_1):page448_i43@pure_quanta.q_cap(chips)"
			("LOCATION" "PC1186_P0_4")
		)
		("@s9s_mb_2u_lib.s9s_mb_2u(sch_1):page448_i97@pure_quanta.q_capp(chips)"
			("LOCATION" "PC1187")
		)
		("@s9s_mb_2u_lib.s9s_mb_2u(sch_1):page448_i49@pure_quanta.q_cap(chips)"
			("LOCATION" "PC1187_P0_3")
		)
		("@s9s_mb_2u_lib.s9s_mb_2u(sch_1):page448_i44@pure_quanta.q_cap(chips)"
			("LOCATION" "PC1188_P0_4")
		)
		("@s9s_mb_2u_lib.s9s_mb_2u(sch_1):page448_i66@pure_quanta.q_capp(chips)"
			("LOCATION" "PC1189")
		)
		("@s9s_mb_2u_lib.s9s_mb_2u(sch_1):page448_i26@pure_quanta.q_cap(chips)"
			("LOCATION" "PC1213_P0_3")
		)
		("@s9s_mb_2u_lib.s9s_mb_2u(sch_1):page448_i13@pure_quanta.q_cap(chips)"
			("LOCATION" "PC1214_P0_4")
		)
		("@s9s_mb_2u_lib.s9s_mb_2u(sch_1):page448_i99@pure_quanta.q_capp(chips)"
			("LOCATION" "PC2170")
		)
		("@s9s_mb_2u_lib.s9s_mb_2u(sch_1):page448_i91@pure_quanta.q_inductor(chips)"
			("LOCATION" "PL2")
		)
		("@s9s_mb_2u_lib.s9s_mb_2u(sch_1):page448_i67@pure_quanta.q_inductor(chips)"
			("LOCATION" "PL101")
		)
		("@s9s_mb_2u_lib.s9s_mb_2u(sch_1):page448_i98@pure_quanta.q_inductor(chips)"
			("LOCATION" "PL210")
		)
		("@s9s_mb_2u_lib.s9s_mb_2u(sch_1):page448_i1@pure_quanta.q_res(chips)"
			("LOCATION" "PR1297")
		)
		("@s9s_mb_2u_lib.s9s_mb_2u(sch_1):page448_i15@pure_quanta.q_res(chips)"
			("LOCATION" "PR1298")
		)
		("@s9s_mb_2u_lib.s9s_mb_2u(sch_1):page448_i24@pure_quanta.q_res(chips)"
			("LOCATION" "PR1299")
		)
		("@s9s_mb_2u_lib.s9s_mb_2u(sch_1):page448_i10@pure_quanta.q_res(chips)"
			("LOCATION" "PR1300")
		)
		("@s9s_mb_2u_lib.s9s_mb_2u(sch_1):page579_i7@pure_quanta.q_cap(chips)"
			("LOCATION" "PC1232")
		)
		("@s9s_mb_2u_lib.s9s_mb_2u(sch_1):page579_i8@pure_quanta.q_cap(chips)"
			("LOCATION" "PC1233")
		)
		("@s9s_mb_2u_lib.s9s_mb_2u(sch_1):page579_i12@pure_quanta.q_cap(chips)"
			("LOCATION" "PC1234")
		)
		("@s9s_mb_2u_lib.s9s_mb_2u(sch_1):page579_i15@pure_quanta.q_cap(chips)"
			("LOCATION" "PC1235")
		)
		("@s9s_mb_2u_lib.s9s_mb_2u(sch_1):page579_i17@pure_quanta.q_cap(chips)"
			("LOCATION" "PC1236")
		)
		("@s9s_mb_2u_lib.s9s_mb_2u(sch_1):page579_i20@pure_quanta.q_cap(chips)"
			("LOCATION" "PC1237")
		)
		("@s9s_mb_2u_lib.s9s_mb_2u(sch_1):page579_i21@pure_quanta.q_cap(chips)"
			("LOCATION" "PC1238")
		)
		("@s9s_mb_2u_lib.s9s_mb_2u(sch_1):page579_i25@pure_quanta.q_cap(chips)"
			("LOCATION" "PC1239")
		)
		("@s9s_mb_2u_lib.s9s_mb_2u(sch_1):page579_i26@pure_quanta.q_cap(chips)"
			("LOCATION" "PC1240")
		)
		("@s9s_mb_2u_lib.s9s_mb_2u(sch_1):page579_i28@pure_quanta.q_cap(chips)"
			("LOCATION" "PC1241")
		)
		("@s9s_mb_2u_lib.s9s_mb_2u(sch_1):page579_i2@pure_quanta.q_cap(chips)"
			("LOCATION" "PC1642")
		)
		("@s9s_mb_2u_lib.s9s_mb_2u(sch_1):page579_i23@pure_quanta.q_cap(chips)"
			("LOCATION" "PC2287")
		)
		("@s9s_mb_2u_lib.s9s_mb_2u(sch_1):page579_i30@pure_quanta.q_inductor(chips)"
			("LOCATION" "PL16")
		)
		("@s9s_mb_2u_lib.s9s_mb_2u(sch_1):page579_i19@pure_quanta.q_inductor(chips)"
			("LOCATION" "PL170")
		)
		("@s9s_mb_2u_lib.s9s_mb_2u(sch_1):page579_i35@pure_quanta.q_res(chips)"
			("LOCATION" "PR411")
		)
		("@s9s_mb_2u_lib.s9s_mb_2u(sch_1):page579_i34@pure_quanta.q_res(chips)"
			("LOCATION" "PR412")
		)
		("@s9s_mb_2u_lib.s9s_mb_2u(sch_1):page579_i16@pure_quanta.q_res(chips)"
			("LOCATION" "PR1302")
		)
		("@s9s_mb_2u_lib.s9s_mb_2u(sch_1):page579_i4@pure_quanta.q_res(chips)"
			("LOCATION" "PR1329")
		)
		("@s9s_mb_2u_lib.s9s_mb_2u(sch_1):page579_i10@pure_quanta.q_res(chips)"
			("LOCATION" "PR1330")
		)
		("@s9s_mb_2u_lib.s9s_mb_2u(sch_1):page579_i18@pure_quanta.q_res(chips)"
			("LOCATION" "PR1651")
		)
		("@s9s_mb_2u_lib.s9s_mb_2u(sch_1):page579_i46@pure_quanta.q_res(chips)"
			("LOCATION" "PR1942")
		)
		("@s9s_mb_2u_lib.s9s_mb_2u(sch_1):page579_i45@pure_quanta.q_res(chips)"
			("LOCATION" "PR1943")
		)
		("@s9s_mb_2u_lib.s9s_mb_2u(sch_1):page579_i13@pure_quanta.nb695gdz(chips)"
			("LOCATION" "PU74")
		)
		("@s9s_mb_2u_lib.s9s_mb_2u(sch_1):page579_i37@pure_quanta.q_res(chips)"
			("LOCATION" "R1850")
		)
		("@s9s_mb_2u_lib.s9s_mb_2u(sch_1):page580_i29@pure_quanta.q_cap(chips)"
			("LOCATION" "PC1323")
		)
		("@s9s_mb_2u_lib.s9s_mb_2u(sch_1):page580_i13@pure_quanta.q_cap(chips)"
			("LOCATION" "PC1324")
		)
		("@s9s_mb_2u_lib.s9s_mb_2u(sch_1):page580_i7@pure_quanta.q_cap(chips)"
			("LOCATION" "PC1325")
		)
		("@s9s_mb_2u_lib.s9s_mb_2u(sch_1):page580_i5@pure_quanta.q_cap(chips)"
			("LOCATION" "PC1326")
		)
		("@s9s_mb_2u_lib.s9s_mb_2u(sch_1):page580_i4@pure_quanta.q_cap(chips)"
			("LOCATION" "PC1327")
		)
		("@s9s_mb_2u_lib.s9s_mb_2u(sch_1):page580_i2@pure_quanta.q_cap(chips)"
			("LOCATION" "PC1328")
		)
		("@s9s_mb_2u_lib.s9s_mb_2u(sch_1):page580_i17@pure_quanta.q_cap(chips)"
			("LOCATION" "PC1329")
		)
		("@s9s_mb_2u_lib.s9s_mb_2u(sch_1):page580_i16@pure_quanta.q_cap(chips)"
			("LOCATION" "PC1330")
		)
		("@s9s_mb_2u_lib.s9s_mb_2u(sch_1):page580_i15@pure_quanta.q_cap(chips)"
			("LOCATION" "PC1331")
		)
		("@s9s_mb_2u_lib.s9s_mb_2u(sch_1):page580_i31@pure_quanta.q_cap(chips)"
			("LOCATION" "PC1332")
		)
		("@s9s_mb_2u_lib.s9s_mb_2u(sch_1):page580_i33@pure_quanta.q_cap(chips)"
			("LOCATION" "PC1333")
		)
		("@s9s_mb_2u_lib.s9s_mb_2u(sch_1):page580_i18@pure_quanta.q_inductor(chips)"
			("LOCATION" "PL115")
		)
		("@s9s_mb_2u_lib.s9s_mb_2u(sch_1):page580_i10@pure_quanta.q_inductor(chips)"
			("LOCATION" "PL116")
		)
		("@s9s_mb_2u_lib.s9s_mb_2u(sch_1):page580_i12@pure_quanta.q_res(chips)"
			("LOCATION" "PR923")
		)
		("@s9s_mb_2u_lib.s9s_mb_2u(sch_1):page580_i27@pure_quanta.q_res(chips)"
			("LOCATION" "PR924")
		)
		("@s9s_mb_2u_lib.s9s_mb_2u(sch_1):page580_i23@pure_quanta.q_res(chips)"
			("LOCATION" "PR925")
		)
		("@s9s_mb_2u_lib.s9s_mb_2u(sch_1):page580_i30@pure_quanta.q_res(chips)"
			("LOCATION" "PR926")
		)
		("@s9s_mb_2u_lib.s9s_mb_2u(sch_1):page580_i22@pure_quanta.nb695gdz(chips)"
			("LOCATION" "PU98")
		)
		("@s9s_mb_2u_lib.s9s_mb_2u(sch_1):page641_i29@pure_quanta.q_cap(chips)"
			("LOCATION" "PC2367")
		)
		("@s9s_mb_2u_lib.s9s_mb_2u(sch_1):page641_i30@pure_quanta.q_cap(chips)"
			("LOCATION" "PC2368")
		)
		("@s9s_mb_2u_lib.s9s_mb_2u(sch_1):page641_i25@pure_quanta.q_cap(chips)"
			("LOCATION" "PC2369_P0_5")
		)
		("@s9s_mb_2u_lib.s9s_mb_2u(sch_1):page641_i3@pure_quanta.q_cap(chips)"
			("LOCATION" "PC2370_P0_5")
		)
		("@s9s_mb_2u_lib.s9s_mb_2u(sch_1):page641_i4@pure_quanta.q_cap(chips)"
			("LOCATION" "PC2371_P0_5")
		)
		("@s9s_mb_2u_lib.s9s_mb_2u(sch_1):page641_i5@pure_quanta.q_cap(chips)"
			("LOCATION" "PC2372_P0_5")
		)
		("@s9s_mb_2u_lib.s9s_mb_2u(sch_1):page641_i22@pure_quanta.q_cap(chips)"
			("LOCATION" "PC2373_P0_5")
		)
		("@s9s_mb_2u_lib.s9s_mb_2u(sch_1):page641_i21@pure_quanta.q_cap(chips)"
			("LOCATION" "PC2374")
		)
		("@s9s_mb_2u_lib.s9s_mb_2u(sch_1):page641_i16@pure_quanta.q_cap(chips)"
			("LOCATION" "PC2375_P0_5")
		)
		("@s9s_mb_2u_lib.s9s_mb_2u(sch_1):page641_i15@pure_quanta.q_cap(chips)"
			("LOCATION" "PC2376_P0_5")
		)
		("@s9s_mb_2u_lib.s9s_mb_2u(sch_1):page641_i10@pure_quanta.q_capp(chips)"
			("LOCATION" "PC2377")
		)
		("@s9s_mb_2u_lib.s9s_mb_2u(sch_1):page641_i8@pure_quanta.q_capp(chips)"
			("LOCATION" "PC2378")
		)
		("@s9s_mb_2u_lib.s9s_mb_2u(sch_1):page641_i19@pure_quanta.q_inductor(chips)"
			("LOCATION" "PL57")
		)
		("@s9s_mb_2u_lib.s9s_mb_2u(sch_1):page641_i36@pure_quanta.q_res(chips)"
			("LOCATION" "PR1887")
		)
		("@s9s_mb_2u_lib.s9s_mb_2u(sch_1):page641_i28@pure_quanta.q_res(chips)"
			("LOCATION" "PR1888")
		)
		("@s9s_mb_2u_lib.s9s_mb_2u(sch_1):page641_i20@pure_quanta.q_res(chips)"
			("LOCATION" "PR1890")
		)
		("@s9s_mb_2u_lib.s9s_mb_2u(sch_1):page483_i57@pure_quanta.mosfet_nch_dual(chips)"
			("LOCATION" "Q3")
		)
		("@s9s_mb_2u_lib.s9s_mb_2u(sch_1):page483_i163@pure_quanta.mosfet_nch_dual(chips)"
			("LOCATION" "Q3")
		)
		("@s9s_mb_2u_lib.s9s_mb_2u(sch_1):page483_i70@pure_quanta.mosfet_nch_dual(chips)"
			("LOCATION" "Q4")
		)
		("@s9s_mb_2u_lib.s9s_mb_2u(sch_1):page483_i166@pure_quanta.mosfet_nch_dual(chips)"
			("LOCATION" "Q4")
		)
		("@s9s_mb_2u_lib.s9s_mb_2u(sch_1):page483_i130@pure_quanta.mosfet_nch_dual(chips)"
			("LOCATION" "Q5")
		)
		("@s9s_mb_2u_lib.s9s_mb_2u(sch_1):page483_i165@pure_quanta.mosfet_nch_dual(chips)"
			("LOCATION" "Q5")
		)
		("@s9s_mb_2u_lib.s9s_mb_2u(sch_1):page483_i142@pure_quanta.mosfet_nch_dual(chips)"
			("LOCATION" "Q6")
		)
		("@s9s_mb_2u_lib.s9s_mb_2u(sch_1):page483_i164@pure_quanta.mosfet_nch_dual(chips)"
			("LOCATION" "Q6")
		)
		("@s9s_mb_2u_lib.s9s_mb_2u(sch_1):page483_i58@pure_quanta.q_res(chips)"
			("LOCATION" "R229")
		)
		("@s9s_mb_2u_lib.s9s_mb_2u(sch_1):page483_i81@pure_quanta.q_res(chips)"
			("LOCATION" "R230")
		)
		("@s9s_mb_2u_lib.s9s_mb_2u(sch_1):page483_i132@pure_quanta.q_res(chips)"
			("LOCATION" "R231")
		)
		("@s9s_mb_2u_lib.s9s_mb_2u(sch_1):page483_i153@pure_quanta.q_res(chips)"
			("LOCATION" "R232")
		)
		("@s9s_mb_2u_lib.s9s_mb_2u(sch_1):page483_i62@pure_quanta.q_res(chips)"
			("LOCATION" "R233")
		)
		("@s9s_mb_2u_lib.s9s_mb_2u(sch_1):page483_i79@pure_quanta.q_res(chips)"
			("LOCATION" "R234")
		)
		("@s9s_mb_2u_lib.s9s_mb_2u(sch_1):page483_i128@pure_quanta.q_res(chips)"
			("LOCATION" "R235")
		)
		("@s9s_mb_2u_lib.s9s_mb_2u(sch_1):page483_i150@pure_quanta.q_res(chips)"
			("LOCATION" "R236")
		)
		("@s9s_mb_2u_lib.s9s_mb_2u(sch_1):page483_i69@pure_quanta.q_res(chips)"
			("LOCATION" "R237")
		)
		("@s9s_mb_2u_lib.s9s_mb_2u(sch_1):page483_i80@pure_quanta.q_res(chips)"
			("LOCATION" "R238")
		)
		("@s9s_mb_2u_lib.s9s_mb_2u(sch_1):page483_i129@pure_quanta.q_res(chips)"
			("LOCATION" "R239")
		)
		("@s9s_mb_2u_lib.s9s_mb_2u(sch_1):page483_i151@pure_quanta.q_res(chips)"
			("LOCATION" "R240")
		)
		("@s9s_mb_2u_lib.s9s_mb_2u(sch_1):page483_i167@pure_quanta.q_res(chips)"
			("LOCATION" "R241")
		)
		("@s9s_mb_2u_lib.s9s_mb_2u(sch_1):page483_i169@pure_quanta.q_res(chips)"
			("LOCATION" "R242")
		)
		("@s9s_mb_2u_lib.s9s_mb_2u(sch_1):page483_i171@pure_quanta.q_res(chips)"
			("LOCATION" "R243")
		)
		("@s9s_mb_2u_lib.s9s_mb_2u(sch_1):page483_i173@pure_quanta.q_res(chips)"
			("LOCATION" "R244")
		)
		("@s9s_mb_2u_lib.s9s_mb_2u(sch_1):page483_i67@pure_quanta.q_res(chips)"
			("LOCATION" "R245")
		)
		("@s9s_mb_2u_lib.s9s_mb_2u(sch_1):page483_i73@pure_quanta.q_res(chips)"
			("LOCATION" "R246")
		)
		("@s9s_mb_2u_lib.s9s_mb_2u(sch_1):page483_i116@pure_quanta.q_res(chips)"
			("LOCATION" "R247")
		)
		("@s9s_mb_2u_lib.s9s_mb_2u(sch_1):page483_i146@pure_quanta.q_res(chips)"
			("LOCATION" "R248")
		)
		("@s9s_mb_2u_lib.s9s_mb_2u(sch_1):page464_i33@pure_quanta.mosfet_n_123(chips)"
			("LOCATION" "Q7")
		)
		("@s9s_mb_2u_lib.s9s_mb_2u(sch_1):page464_i31@pure_quanta.mosfet_nch_dual(chips)"
			("LOCATION" "Q8")
		)
		("@s9s_mb_2u_lib.s9s_mb_2u(sch_1):page464_i32@pure_quanta.mosfet_nch_dual(chips)"
			("LOCATION" "Q8")
		)
		("@s9s_mb_2u_lib.s9s_mb_2u(sch_1):page464_i11@pure_quanta.q_res(chips)"
			("LOCATION" "R1246")
		)
		("@s9s_mb_2u_lib.s9s_mb_2u(sch_1):page464_i14@pure_quanta.q_res(chips)"
			("LOCATION" "R1247")
		)
		("@s9s_mb_2u_lib.s9s_mb_2u(sch_1):page464_i3@pure_quanta.q_res(chips)"
			("LOCATION" "R1248")
		)
		("@s9s_mb_2u_lib.s9s_mb_2u(sch_1):page464_i2@pure_quanta.q_res(chips)"
			("LOCATION" "R1249")
		)
		("@s9s_mb_2u_lib.s9s_mb_2u(sch_1):page464_i24@pure_quanta.q_res(chips)"
			("LOCATION" "R1250")
		)
		("@s9s_mb_2u_lib.s9s_mb_2u(sch_1):page464_i21@pure_quanta.q_res(chips)"
			("LOCATION" "R1251")
		)
		("@s9s_mb_2u_lib.s9s_mb_2u(sch_1):page464_i29@pure_quanta.q_res(chips)"
			("LOCATION" "R1263")
		)
		("@s9s_mb_2u_lib.s9s_mb_2u(sch_1):page464_i27@pure_quanta.q_res(chips)"
			("LOCATION" "R1264")
		)
		("@s9s_mb_2u_lib.s9s_mb_2u(sch_1):page464_i25@pure_quanta.q_res(chips)"
			("LOCATION" "R1265")
		)
		("@s9s_mb_2u_lib.s9s_mb_2u(sch_1):page464_i23@pure_quanta.q_res(chips)"
			("LOCATION" "R1266")
		)
		("@s9s_mb_2u_lib.s9s_mb_2u(sch_1):page464_i35@pure_quanta.q_res(chips)"
			("LOCATION" "R1820")
		)
		("@s9s_mb_2u_lib.s9s_mb_2u(sch_1):page13_i18@pure_quanta.q_res(chips)"
			("LOCATION" "R1")
		)
		("@s9s_mb_2u_lib.s9s_mb_2u(sch_1):page13_i16@pure_quanta.q_res(chips)"
			("LOCATION" "R2")
		)
		("@s9s_mb_2u_lib.s9s_mb_2u(sch_1):page13_i21@pure_quanta.q_res(chips)"
			("LOCATION" "R3")
		)
		("@s9s_mb_2u_lib.s9s_mb_2u(sch_1):page13_i29@pure_quanta.q_res(chips)"
			("LOCATION" "R4")
		)
		("@s9s_mb_2u_lib.s9s_mb_2u(sch_1):page13_i24@pure_quanta.q_res(chips)"
			("LOCATION" "R5")
		)
		("@s9s_mb_2u_lib.s9s_mb_2u(sch_1):page13_i25@pure_quanta.q_res(chips)"
			("LOCATION" "R6")
		)
		("@s9s_mb_2u_lib.s9s_mb_2u(sch_1):page13_i57@pure_quanta.socket4677_azifs035p001c01(chips)"
			("LOCATION" "U2")
		)
		("@s9s_mb_2u_lib.s9s_mb_2u(sch_1):page14_i66@pure_quanta.q_res(chips)"
			("LOCATION" "R7")
		)
		("@s9s_mb_2u_lib.s9s_mb_2u(sch_1):page14_i78@pure_quanta.q_res(chips)"
			("LOCATION" "R10")
		)
		("@s9s_mb_2u_lib.s9s_mb_2u(sch_1):page14_i79@pure_quanta.q_res(chips)"
			("LOCATION" "R11")
		)
		("@s9s_mb_2u_lib.s9s_mb_2u(sch_1):page14_i59@pure_quanta.q_res(chips)"
			("LOCATION" "R12")
		)
		("@s9s_mb_2u_lib.s9s_mb_2u(sch_1):page14_i60@pure_quanta.q_res(chips)"
			("LOCATION" "R13")
		)
		("@s9s_mb_2u_lib.s9s_mb_2u(sch_1):page14_i61@pure_quanta.q_res(chips)"
			("LOCATION" "R14")
		)
		("@s9s_mb_2u_lib.s9s_mb_2u(sch_1):page14_i62@pure_quanta.q_res(chips)"
			("LOCATION" "R15")
		)
		("@s9s_mb_2u_lib.s9s_mb_2u(sch_1):page14_i63@pure_quanta.q_res(chips)"
			("LOCATION" "R16")
		)
		("@s9s_mb_2u_lib.s9s_mb_2u(sch_1):page14_i64@pure_quanta.q_res(chips)"
			("LOCATION" "R17")
		)
		("@s9s_mb_2u_lib.s9s_mb_2u(sch_1):page14_i83@pure_quanta.q_res(chips)"
			("LOCATION" "R317")
		)
		("@s9s_mb_2u_lib.s9s_mb_2u(sch_1):page14_i90@pure_quanta.q_res(chips)"
			("LOCATION" "R322")
		)
		("@s9s_mb_2u_lib.s9s_mb_2u(sch_1):page14_i93@pure_quanta.q_res(chips)"
			("LOCATION" "R328")
		)
		("@s9s_mb_2u_lib.s9s_mb_2u(sch_1):page14_i94@pure_quanta.q_res(chips)"
			("LOCATION" "R548")
		)
		("@s9s_mb_2u_lib.s9s_mb_2u(sch_1):page14_i98@pure_quanta.q_res(chips)"
			("LOCATION" "R555")
		)
		("@s9s_mb_2u_lib.s9s_mb_2u(sch_1):page14_i100@pure_quanta.q_res(chips)"
			("LOCATION" "R556")
		)
		("@s9s_mb_2u_lib.s9s_mb_2u(sch_1):page14_i109@pure_quanta.q_res(chips)"
			("LOCATION" "R1932")
		)
		("@s9s_mb_2u_lib.s9s_mb_2u(sch_1):page14_i110@pure_quanta.q_res(chips)"
			("LOCATION" "R1933")
		)
		("@s9s_mb_2u_lib.s9s_mb_2u(sch_1):page14_i1@pure_quanta.socket4677_azifs035p001c01(chips)"
			("LOCATION" "U2")
		)
		("@s9s_mb_2u_lib.s9s_mb_2u(sch_1):page463_i59@pure_quanta.q_res(chips)"
			("LOCATION" "R8")
		)
		("@s9s_mb_2u_lib.s9s_mb_2u(sch_1):page463_i60@pure_quanta.q_res(chips)"
			("LOCATION" "R71")
		)
		("@s9s_mb_2u_lib.s9s_mb_2u(sch_1):page463_i69@pure_quanta.q_res(chips)"
			("LOCATION" "R401")
		)
		("@s9s_mb_2u_lib.s9s_mb_2u(sch_1):page463_i66@pure_quanta.q_res(chips)"
			("LOCATION" "R456")
		)
		("@s9s_mb_2u_lib.s9s_mb_2u(sch_1):page463_i23@pure_quanta.q_res(chips)"
			("LOCATION" "R1253")
		)
		("@s9s_mb_2u_lib.s9s_mb_2u(sch_1):page463_i24@pure_quanta.q_res(chips)"
			("LOCATION" "R1254")
		)
		("@s9s_mb_2u_lib.s9s_mb_2u(sch_1):page463_i26@pure_quanta.q_res(chips)"
			("LOCATION" "R1255")
		)
		("@s9s_mb_2u_lib.s9s_mb_2u(sch_1):page463_i1@pure_quanta.q_res(chips)"
			("LOCATION" "R1256")
		)
		("@s9s_mb_2u_lib.s9s_mb_2u(sch_1):page463_i4@pure_quanta.q_res(chips)"
			("LOCATION" "R1257")
		)
		("@s9s_mb_2u_lib.s9s_mb_2u(sch_1):page463_i6@pure_quanta.q_res(chips)"
			("LOCATION" "R1258")
		)
		("@s9s_mb_2u_lib.s9s_mb_2u(sch_1):page463_i8@pure_quanta.q_res(chips)"
			("LOCATION" "R1259")
		)
		("@s9s_mb_2u_lib.s9s_mb_2u(sch_1):page463_i17@pure_quanta.q_res(chips)"
			("LOCATION" "R1260")
		)
		("@s9s_mb_2u_lib.s9s_mb_2u(sch_1):page463_i18@pure_quanta.q_res(chips)"
			("LOCATION" "R1261")
		)
		("@s9s_mb_2u_lib.s9s_mb_2u(sch_1):page463_i11@pure_quanta.q_res(chips)"
			("LOCATION" "R1262")
		)
		("@s9s_mb_2u_lib.s9s_mb_2u(sch_1):page463_i40@pure_quanta.q_res(chips)"
			("LOCATION" "R1344")
		)
		("@s9s_mb_2u_lib.s9s_mb_2u(sch_1):page463_i41@pure_quanta.q_res(chips)"
			("LOCATION" "R1449")
		)
		("@s9s_mb_2u_lib.s9s_mb_2u(sch_1):page463_i42@pure_quanta.q_res(chips)"
			("LOCATION" "R1450")
		)
		("@s9s_mb_2u_lib.s9s_mb_2u(sch_1):page463_i50@pure_quanta.q_res(chips)"
			("LOCATION" "R1458")
		)
		("@s9s_mb_2u_lib.s9s_mb_2u(sch_1):page463_i51@pure_quanta.q_res(chips)"
			("LOCATION" "R1459")
		)
		("@s9s_mb_2u_lib.s9s_mb_2u(sch_1):page463_i62@pure_quanta.q_res(chips)"
			("LOCATION" "R1554")
		)
		("@s9s_mb_2u_lib.s9s_mb_2u(sch_1):page339_i57@pure_quanta.q_res(chips)"
			("LOCATION" "R9")
		)
		("@s9s_mb_2u_lib.s9s_mb_2u(sch_1):page339_i12@pure_quanta.q_res(chips)"
			("LOCATION" "R67")
		)
		("@s9s_mb_2u_lib.s9s_mb_2u(sch_1):page339_i13@pure_quanta.q_res(chips)"
			("LOCATION" "R68")
		)
		("@s9s_mb_2u_lib.s9s_mb_2u(sch_1):page339_i16@pure_quanta.q_res(chips)"
			("LOCATION" "R69")
		)
		("@s9s_mb_2u_lib.s9s_mb_2u(sch_1):page339_i17@pure_quanta.q_res(chips)"
			("LOCATION" "R70")
		)
		("@s9s_mb_2u_lib.s9s_mb_2u(sch_1):page339_i59@pure_quanta.q_res(chips)"
			("LOCATION" "R316")
		)
		("@s9s_mb_2u_lib.s9s_mb_2u(sch_1):page339_i26@pure_quanta.q_res(chips)"
			("LOCATION" "R1218")
		)
		("@s9s_mb_2u_lib.s9s_mb_2u(sch_1):page339_i27@pure_quanta.q_res(chips)"
			("LOCATION" "R1219")
		)
		("@s9s_mb_2u_lib.s9s_mb_2u(sch_1):page339_i49@pure_quanta.q_res(chips)"
			("LOCATION" "R1223")
		)
		("@s9s_mb_2u_lib.s9s_mb_2u(sch_1):page339_i50@pure_quanta.q_res(chips)"
			("LOCATION" "R1224")
		)
		("@s9s_mb_2u_lib.s9s_mb_2u(sch_1):page339_i51@pure_quanta.q_res(chips)"
			("LOCATION" "R1225")
		)
		("@s9s_mb_2u_lib.s9s_mb_2u(sch_1):page339_i52@pure_quanta.q_res(chips)"
			("LOCATION" "R1226")
		)
		("@s9s_mb_2u_lib.s9s_mb_2u(sch_1):page339_i56@pure_quanta.q_res(chips)"
			("LOCATION" "R1227")
		)
		("@s9s_mb_2u_lib.s9s_mb_2u(sch_1):page16_i35@pure_quanta.q_res(chips)"
			("LOCATION" "R18")
		)
		("@s9s_mb_2u_lib.s9s_mb_2u(sch_1):page16_i36@pure_quanta.q_res(chips)"
			("LOCATION" "R19")
		)
		("@s9s_mb_2u_lib.s9s_mb_2u(sch_1):page16_i31@pure_quanta.q_res(chips)"
			("LOCATION" "R20")
		)
		("@s9s_mb_2u_lib.s9s_mb_2u(sch_1):page16_i32@pure_quanta.q_res(chips)"
			("LOCATION" "R21")
		)
		("@s9s_mb_2u_lib.s9s_mb_2u(sch_1):page16_i19@pure_quanta.q_res(chips)"
			("LOCATION" "R22")
		)
		("@s9s_mb_2u_lib.s9s_mb_2u(sch_1):page16_i20@pure_quanta.q_res(chips)"
			("LOCATION" "R23")
		)
		("@s9s_mb_2u_lib.s9s_mb_2u(sch_1):page16_i25@pure_quanta.q_res(chips)"
			("LOCATION" "R24")
		)
		("@s9s_mb_2u_lib.s9s_mb_2u(sch_1):page16_i26@pure_quanta.q_res(chips)"
			("LOCATION" "R25")
		)
		("@s9s_mb_2u_lib.s9s_mb_2u(sch_1):page16_i1@pure_quanta.socket4677_azifs035p001c01(chips)"
			("LOCATION" "U2")
		)
		("@s9s_mb_2u_lib.s9s_mb_2u(sch_1):page343_i34@pure_quanta.q_res(chips)"
			("LOCATION" "R49")
		)
		("@s9s_mb_2u_lib.s9s_mb_2u(sch_1):page343_i35@pure_quanta.q_res(chips)"
			("LOCATION" "R50")
		)
		("@s9s_mb_2u_lib.s9s_mb_2u(sch_1):page343_i24@pure_quanta.q_res(chips)"
			("LOCATION" "R51")
		)
		("@s9s_mb_2u_lib.s9s_mb_2u(sch_1):page343_i25@pure_quanta.q_res(chips)"
			("LOCATION" "R52")
		)
		("@s9s_mb_2u_lib.s9s_mb_2u(sch_1):page343_i23@pure_quanta.q_res(chips)"
			("LOCATION" "R53")
		)
		("@s9s_mb_2u_lib.s9s_mb_2u(sch_1):page343_i22@pure_quanta.q_res(chips)"
			("LOCATION" "R54")
		)
		("@s9s_mb_2u_lib.s9s_mb_2u(sch_1):page343_i16@pure_quanta.socket4677_azifs035p001c01(chips)"
			("LOCATION" "U1")
		)
		("@s9s_mb_2u_lib.s9s_mb_2u(sch_1):page341_i54@pure_quanta.q_res(chips)"
			("LOCATION" "R55")
		)
		("@s9s_mb_2u_lib.s9s_mb_2u(sch_1):page341_i55@pure_quanta.q_res(chips)"
			("LOCATION" "R56")
		)
		("@s9s_mb_2u_lib.s9s_mb_2u(sch_1):page341_i56@pure_quanta.q_res(chips)"
			("LOCATION" "R57")
		)
		("@s9s_mb_2u_lib.s9s_mb_2u(sch_1):page341_i51@pure_quanta.q_res(chips)"
			("LOCATION" "R58")
		)
		("@s9s_mb_2u_lib.s9s_mb_2u(sch_1):page341_i52@pure_quanta.q_res(chips)"
			("LOCATION" "R59")
		)
		("@s9s_mb_2u_lib.s9s_mb_2u(sch_1):page341_i53@pure_quanta.q_res(chips)"
			("LOCATION" "R60")
		)
		("@s9s_mb_2u_lib.s9s_mb_2u(sch_1):page341_i63@pure_quanta.q_res(chips)"
			("LOCATION" "R516")
		)
		("@s9s_mb_2u_lib.s9s_mb_2u(sch_1):page341_i74@pure_quanta.q_res(chips)"
			("LOCATION" "R557")
		)
		("@s9s_mb_2u_lib.s9s_mb_2u(sch_1):page341_i73@pure_quanta.q_res(chips)"
			("LOCATION" "R558")
		)
		("@s9s_mb_2u_lib.s9s_mb_2u(sch_1):page341_i69@pure_quanta.q_res(chips)"
			("LOCATION" "R559")
		)
		("@s9s_mb_2u_lib.s9s_mb_2u(sch_1):page341_i70@pure_quanta.q_res(chips)"
			("LOCATION" "R560")
		)
		("@s9s_mb_2u_lib.s9s_mb_2u(sch_1):page341_i81@pure_quanta.q_res(chips)"
			("LOCATION" "R1934")
		)
		("@s9s_mb_2u_lib.s9s_mb_2u(sch_1):page341_i82@pure_quanta.q_res(chips)"
			("LOCATION" "R1935")
		)
		("@s9s_mb_2u_lib.s9s_mb_2u(sch_1):page341_i29@pure_quanta.socket4677_azifs035p001c01(chips)"
			("LOCATION" "U1")
		)
		("@s9s_mb_2u_lib.s9s_mb_2u(sch_1):page340_i16@pure_quanta.q_res(chips)"
			("LOCATION" "R61")
		)
		("@s9s_mb_2u_lib.s9s_mb_2u(sch_1):page340_i11@pure_quanta.q_res(chips)"
			("LOCATION" "R62")
		)
		("@s9s_mb_2u_lib.s9s_mb_2u(sch_1):page340_i10@pure_quanta.q_res(chips)"
			("LOCATION" "R63")
		)
		("@s9s_mb_2u_lib.s9s_mb_2u(sch_1):page340_i9@pure_quanta.q_res(chips)"
			("LOCATION" "R64")
		)
		("@s9s_mb_2u_lib.s9s_mb_2u(sch_1):page340_i8@pure_quanta.q_res(chips)"
			("LOCATION" "R65")
		)
		("@s9s_mb_2u_lib.s9s_mb_2u(sch_1):page340_i7@pure_quanta.q_res(chips)"
			("LOCATION" "R66")
		)
		("@s9s_mb_2u_lib.s9s_mb_2u(sch_1):page340_i55@pure_quanta.q_res(chips)"
			("LOCATION" "R1270")
		)
		("@s9s_mb_2u_lib.s9s_mb_2u(sch_1):page340_i51@pure_quanta.socket4677_azifs035p001c01(chips)"
			("LOCATION" "U1")
		)
		("@s9s_mb_2u_lib.s9s_mb_2u(sch_1):page488_i135@pure_quanta.q_res(chips)"
			("LOCATION" "R90")
		)
		("@s9s_mb_2u_lib.s9s_mb_2u(sch_1):page488_i136@pure_quanta.q_res(chips)"
			("LOCATION" "R91")
		)
		("@s9s_mb_2u_lib.s9s_mb_2u(sch_1):page488_i140@pure_quanta.q_res(chips)"
			("LOCATION" "R92")
		)
		("@s9s_mb_2u_lib.s9s_mb_2u(sch_1):page488_i141@pure_quanta.q_res(chips)"
			("LOCATION" "R93")
		)
		("@s9s_mb_2u_lib.s9s_mb_2u(sch_1):page488_i25@pure_quanta.q_res(chips)"
			("LOCATION" "R94")
		)
		("@s9s_mb_2u_lib.s9s_mb_2u(sch_1):page488_i23@pure_quanta.q_res(chips)"
			("LOCATION" "R95")
		)
		("@s9s_mb_2u_lib.s9s_mb_2u(sch_1):page488_i22@pure_quanta.q_res(chips)"
			("LOCATION" "R96")
		)
		("@s9s_mb_2u_lib.s9s_mb_2u(sch_1):page488_i114@pure_quanta.q_res(chips)"
			("LOCATION" "R97")
		)
		("@s9s_mb_2u_lib.s9s_mb_2u(sch_1):page488_i77@pure_quanta.q_res(chips)"
			("LOCATION" "R98")
		)
		("@s9s_mb_2u_lib.s9s_mb_2u(sch_1):page488_i79@pure_quanta.q_res(chips)"
			("LOCATION" "R99")
		)
		("@s9s_mb_2u_lib.s9s_mb_2u(sch_1):page488_i84@pure_quanta.q_res(chips)"
			("LOCATION" "R100")
		)
		("@s9s_mb_2u_lib.s9s_mb_2u(sch_1):page488_i85@pure_quanta.q_res(chips)"
			("LOCATION" "R101")
		)
		("@s9s_mb_2u_lib.s9s_mb_2u(sch_1):page488_i106@pure_quanta.q_res(chips)"
			("LOCATION" "R102")
		)
		("@s9s_mb_2u_lib.s9s_mb_2u(sch_1):page488_i107@pure_quanta.q_res(chips)"
			("LOCATION" "R103")
		)
		("@s9s_mb_2u_lib.s9s_mb_2u(sch_1):page488_i108@pure_quanta.q_res(chips)"
			("LOCATION" "R104")
		)
		("@s9s_mb_2u_lib.s9s_mb_2u(sch_1):page488_i109@pure_quanta.q_res(chips)"
			("LOCATION" "R105")
		)
		("@s9s_mb_2u_lib.s9s_mb_2u(sch_1):page488_i91@pure_quanta.q_res(chips)"
			("LOCATION" "R114")
		)
		("@s9s_mb_2u_lib.s9s_mb_2u(sch_1):page488_i92@pure_quanta.q_res(chips)"
			("LOCATION" "R115")
		)
		("@s9s_mb_2u_lib.s9s_mb_2u(sch_1):page488_i93@pure_quanta.q_res(chips)"
			("LOCATION" "R116")
		)
		("@s9s_mb_2u_lib.s9s_mb_2u(sch_1):page488_i96@pure_quanta.q_res(chips)"
			("LOCATION" "R117")
		)
		("@s9s_mb_2u_lib.s9s_mb_2u(sch_1):page488_i97@pure_quanta.q_res(chips)"
			("LOCATION" "R118")
		)
		("@s9s_mb_2u_lib.s9s_mb_2u(sch_1):page488_i98@pure_quanta.q_res(chips)"
			("LOCATION" "R119")
		)
		("@s9s_mb_2u_lib.s9s_mb_2u(sch_1):page563_i43@pure_quanta.q_res(chips)"
			("LOCATION" "R107")
		)
		("@s9s_mb_2u_lib.s9s_mb_2u(sch_1):page563_i42@pure_quanta.q_res(chips)"
			("LOCATION" "R108")
		)
		("@s9s_mb_2u_lib.s9s_mb_2u(sch_1):page563_i36@pure_quanta.q_res(chips)"
			("LOCATION" "R577")
		)
		("@s9s_mb_2u_lib.s9s_mb_2u(sch_1):page563_i37@pure_quanta.q_res(chips)"
			("LOCATION" "R578")
		)
		("@s9s_mb_2u_lib.s9s_mb_2u(sch_1):page563_i38@pure_quanta.q_res(chips)"
			("LOCATION" "R579")
		)
		("@s9s_mb_2u_lib.s9s_mb_2u(sch_1):page563_i39@pure_quanta.q_res(chips)"
			("LOCATION" "R580")
		)
		("@s9s_mb_2u_lib.s9s_mb_2u(sch_1):page563_i44@pure_quanta.q_res(chips)"
			("LOCATION" "R581")
		)
		("@s9s_mb_2u_lib.s9s_mb_2u(sch_1):page563_i45@pure_quanta.q_res(chips)"
			("LOCATION" "R582")
		)
		("@s9s_mb_2u_lib.s9s_mb_2u(sch_1):page563_i135@pure_quanta.q_res(chips)"
			("LOCATION" "R583")
		)
		("@s9s_mb_2u_lib.s9s_mb_2u(sch_1):page563_i134@pure_quanta.q_res(chips)"
			("LOCATION" "R584")
		)
		("@s9s_mb_2u_lib.s9s_mb_2u(sch_1):page563_i109@pure_quanta.q_res(chips)"
			("LOCATION" "R585")
		)
		("@s9s_mb_2u_lib.s9s_mb_2u(sch_1):page563_i106@pure_quanta.q_res(chips)"
			("LOCATION" "R586")
		)
		("@s9s_mb_2u_lib.s9s_mb_2u(sch_1):page563_i58@pure_quanta.q_res(chips)"
			("LOCATION" "R593")
		)
		("@s9s_mb_2u_lib.s9s_mb_2u(sch_1):page563_i59@pure_quanta.q_res(chips)"
			("LOCATION" "R594")
		)
		("@s9s_mb_2u_lib.s9s_mb_2u(sch_1):page563_i60@pure_quanta.q_res(chips)"
			("LOCATION" "R595")
		)
		("@s9s_mb_2u_lib.s9s_mb_2u(sch_1):page563_i61@pure_quanta.q_res(chips)"
			("LOCATION" "R596")
		)
		("@s9s_mb_2u_lib.s9s_mb_2u(sch_1):page563_i62@pure_quanta.q_res(chips)"
			("LOCATION" "R597")
		)
		("@s9s_mb_2u_lib.s9s_mb_2u(sch_1):page563_i63@pure_quanta.q_res(chips)"
			("LOCATION" "R598")
		)
		("@s9s_mb_2u_lib.s9s_mb_2u(sch_1):page563_i64@pure_quanta.q_res(chips)"
			("LOCATION" "R599")
		)
		("@s9s_mb_2u_lib.s9s_mb_2u(sch_1):page563_i65@pure_quanta.q_res(chips)"
			("LOCATION" "R600")
		)
		("@s9s_mb_2u_lib.s9s_mb_2u(sch_1):page563_i2@pure_quanta.q_res(chips)"
			("LOCATION" "R1319")
		)
		("@s9s_mb_2u_lib.s9s_mb_2u(sch_1):page563_i3@pure_quanta.q_res(chips)"
			("LOCATION" "R1321")
		)
		("@s9s_mb_2u_lib.s9s_mb_2u(sch_1):page563_i4@pure_quanta.q_res(chips)"
			("LOCATION" "R1384")
		)
		("@s9s_mb_2u_lib.s9s_mb_2u(sch_1):page563_i5@pure_quanta.q_res(chips)"
			("LOCATION" "R1385")
		)
		("@s9s_mb_2u_lib.s9s_mb_2u(sch_1):page563_i6@pure_quanta.q_res(chips)"
			("LOCATION" "R1386")
		)
		("@s9s_mb_2u_lib.s9s_mb_2u(sch_1):page563_i7@pure_quanta.q_res(chips)"
			("LOCATION" "R1387")
		)
		("@s9s_mb_2u_lib.s9s_mb_2u(sch_1):page563_i40@pure_quanta.q_res(chips)"
			("LOCATION" "R1525")
		)
		("@s9s_mb_2u_lib.s9s_mb_2u(sch_1):page563_i41@pure_quanta.q_res(chips)"
			("LOCATION" "R1526")
		)
		("@s9s_mb_2u_lib.s9s_mb_2u(sch_1):page563_i89@pure_quanta.q_res(chips)"
			("LOCATION" "R1661")
		)
		("@s9s_mb_2u_lib.s9s_mb_2u(sch_1):page563_i90@pure_quanta.q_res(chips)"
			("LOCATION" "R1662")
		)
		("@s9s_mb_2u_lib.s9s_mb_2u(sch_1):page563_i143@pure_quanta.q_res(chips)"
			("LOCATION" "R1663")
		)
		("@s9s_mb_2u_lib.s9s_mb_2u(sch_1):page563_i142@pure_quanta.q_res(chips)"
			("LOCATION" "R1664")
		)
		("@s9s_mb_2u_lib.s9s_mb_2u(sch_1):page563_i121@pure_quanta.q_res(chips)"
			("LOCATION" "R1665")
		)
		("@s9s_mb_2u_lib.s9s_mb_2u(sch_1):page563_i120@pure_quanta.q_res(chips)"
			("LOCATION" "R1666")
		)
		("@s9s_mb_2u_lib.s9s_mb_2u(sch_1):page563_i151@pure_quanta.q_res(chips)"
			("LOCATION" "R1668")
		)
		("@s9s_mb_2u_lib.s9s_mb_2u(sch_1):page563_i150@pure_quanta.q_res(chips)"
			("LOCATION" "R1669")
		)
		("@s9s_mb_2u_lib.s9s_mb_2u(sch_1):page563_i136@pure_quanta.q_res(chips)"
			("LOCATION" "R1670")
		)
		("@s9s_mb_2u_lib.s9s_mb_2u(sch_1):page563_i139@pure_quanta.q_res(chips)"
			("LOCATION" "R1730")
		)
		("@s9s_mb_2u_lib.s9s_mb_2u(sch_1):page563_i125@pure_quanta.q_res(chips)"
			("LOCATION" "R1731")
		)
		("@s9s_mb_2u_lib.s9s_mb_2u(sch_1):page563_i124@pure_quanta.q_res(chips)"
			("LOCATION" "R1732")
		)
		("@s9s_mb_2u_lib.s9s_mb_2u(sch_1):page563_i131@pure_quanta.q_res(chips)"
			("LOCATION" "R1733")
		)
		("@s9s_mb_2u_lib.s9s_mb_2u(sch_1):page563_i130@pure_quanta.q_res(chips)"
			("LOCATION" "R1734")
		)
		("@s9s_mb_2u_lib.s9s_mb_2u(sch_1):page563_i160@pure_quanta.q_res(chips)"
			("LOCATION" "R1761")
		)
		("@s9s_mb_2u_lib.s9s_mb_2u(sch_1):page563_i161@pure_quanta.q_res(chips)"
			("LOCATION" "R1762")
		)
		("@s9s_mb_2u_lib.s9s_mb_2u(sch_1):page550_i44@pure_quanta.q_res(chips)"
			("LOCATION" "R109")
		)
		("@s9s_mb_2u_lib.s9s_mb_2u(sch_1):page550_i17@pure_quanta.q_res(chips)"
			("LOCATION" "R110")
		)
		("@s9s_mb_2u_lib.s9s_mb_2u(sch_1):page550_i24@pure_quanta.q_res(chips)"
			("LOCATION" "R111")
		)
		("@s9s_mb_2u_lib.s9s_mb_2u(sch_1):page550_i27@pure_quanta.q_res(chips)"
			("LOCATION" "R113")
		)
		("@s9s_mb_2u_lib.s9s_mb_2u(sch_1):page550_i91@pure_quanta.q_res(chips)"
			("LOCATION" "R269")
		)
		("@s9s_mb_2u_lib.s9s_mb_2u(sch_1):page550_i7@pure_quanta.q_res(chips)"
			("LOCATION" "R1205")
		)
		("@s9s_mb_2u_lib.s9s_mb_2u(sch_1):page550_i10@pure_quanta.q_res(chips)"
			("LOCATION" "R1206")
		)
		("@s9s_mb_2u_lib.s9s_mb_2u(sch_1):page550_i15@pure_quanta.q_res(chips)"
			("LOCATION" "R1207")
		)
		("@s9s_mb_2u_lib.s9s_mb_2u(sch_1):page550_i47@pure_quanta.q_res(chips)"
			("LOCATION" "R1318")
		)
		("@s9s_mb_2u_lib.s9s_mb_2u(sch_1):page550_i51@pure_quanta.q_res(chips)"
			("LOCATION" "R1468")
		)
		("@s9s_mb_2u_lib.s9s_mb_2u(sch_1):page550_i55@pure_quanta.q_res(chips)"
			("LOCATION" "R1469")
		)
		("@s9s_mb_2u_lib.s9s_mb_2u(sch_1):page550_i56@pure_quanta.q_res(chips)"
			("LOCATION" "R1470")
		)
		("@s9s_mb_2u_lib.s9s_mb_2u(sch_1):page550_i63@pure_quanta.q_res(chips)"
			("LOCATION" "R1512")
		)
		("@s9s_mb_2u_lib.s9s_mb_2u(sch_1):page550_i64@pure_quanta.q_res(chips)"
			("LOCATION" "R1513")
		)
		("@s9s_mb_2u_lib.s9s_mb_2u(sch_1):page550_i65@pure_quanta.q_res(chips)"
			("LOCATION" "R1514")
		)
		("@s9s_mb_2u_lib.s9s_mb_2u(sch_1):page550_i74@pure_quanta.q_res(chips)"
			("LOCATION" "R1515")
		)
		("@s9s_mb_2u_lib.s9s_mb_2u(sch_1):page550_i76@pure_quanta.q_res(chips)"
			("LOCATION" "R1516")
		)
		("@s9s_mb_2u_lib.s9s_mb_2u(sch_1):page550_i70@pure_quanta.q_res(chips)"
			("LOCATION" "R1518")
		)
		("@s9s_mb_2u_lib.s9s_mb_2u(sch_1):page550_i71@pure_quanta.q_res(chips)"
			("LOCATION" "R1519")
		)
		("@s9s_mb_2u_lib.s9s_mb_2u(sch_1):page550_i81@pure_quanta.q_res(chips)"
			("LOCATION" "R1520")
		)
		("@s9s_mb_2u_lib.s9s_mb_2u(sch_1):page550_i78@pure_quanta.q_res(chips)"
			("LOCATION" "R1521")
		)
		("@s9s_mb_2u_lib.s9s_mb_2u(sch_1):page550_i92@pure_quanta.q_res(chips)"
			("LOCATION" "R1541")
		)
		("@s9s_mb_2u_lib.s9s_mb_2u(sch_1):page550_i94@pure_quanta.q_res(chips)"
			("LOCATION" "R1744")
		)
		("@s9s_mb_2u_lib.s9s_mb_2u(sch_1):page550_i86@pure_quanta.q_res(chips)"
			("LOCATION" "R1995")
		)
		("@s9s_mb_2u_lib.s9s_mb_2u(sch_1):page550_i87@pure_quanta.q_res(chips)"
			("LOCATION" "R1996")
		)
		("@s9s_mb_2u_lib.s9s_mb_2u(sch_1):page550_i19@pure_quanta.mosfet_n(chips)"
			("LOCATION" "U70")
		)
		("@s9s_mb_2u_lib.s9s_mb_2u(sch_1):page528_i16@pure_quanta.q_res(chips)"
			("LOCATION" "R143")
		)
		("@s9s_mb_2u_lib.s9s_mb_2u(sch_1):page528_i2@pure_quanta.q_res(chips)"
			("LOCATION" "R144")
		)
		("@s9s_mb_2u_lib.s9s_mb_2u(sch_1):page528_i11@pure_quanta.q_res(chips)"
			("LOCATION" "R145")
		)
		("@s9s_mb_2u_lib.s9s_mb_2u(sch_1):page528_i6@pure_quanta.q_res(chips)"
			("LOCATION" "R146")
		)
		("@s9s_mb_2u_lib.s9s_mb_2u(sch_1):page528_i18@pure_quanta.q_res(chips)"
			("LOCATION" "R147")
		)
		("@s9s_mb_2u_lib.s9s_mb_2u(sch_1):page528_i4@pure_quanta.q_res(chips)"
			("LOCATION" "R148")
		)
		("@s9s_mb_2u_lib.s9s_mb_2u(sch_1):page528_i9@pure_quanta.q_res(chips)"
			("LOCATION" "R149")
		)
		("@s9s_mb_2u_lib.s9s_mb_2u(sch_1):page528_i15@pure_quanta.q_res(chips)"
			("LOCATION" "R1297")
		)
		("@s9s_mb_2u_lib.s9s_mb_2u(sch_1):page482_i27@pure_quanta.q_res(chips)"
			("LOCATION" "R249")
		)
		("@s9s_mb_2u_lib.s9s_mb_2u(sch_1):page482_i29@pure_quanta.q_res(chips)"
			("LOCATION" "R250")
		)
		("@s9s_mb_2u_lib.s9s_mb_2u(sch_1):page482_i28@pure_quanta.q_res(chips)"
			("LOCATION" "R251")
		)
		("@s9s_mb_2u_lib.s9s_mb_2u(sch_1):page482_i30@pure_quanta.q_res(chips)"
			("LOCATION" "R252")
		)
		("@s9s_mb_2u_lib.s9s_mb_2u(sch_1):page482_i31@pure_quanta.q_res(chips)"
			("LOCATION" "R253")
		)
		("@s9s_mb_2u_lib.s9s_mb_2u(sch_1):page482_i32@pure_quanta.q_res(chips)"
			("LOCATION" "R254")
		)
		("@s9s_mb_2u_lib.s9s_mb_2u(sch_1):page482_i42@pure_quanta.q_res(chips)"
			("LOCATION" "R255")
		)
		("@s9s_mb_2u_lib.s9s_mb_2u(sch_1):page482_i48@pure_quanta.q_res(chips)"
			("LOCATION" "R256")
		)
		("@s9s_mb_2u_lib.s9s_mb_2u(sch_1):page482_i43@pure_quanta.q_res(chips)"
			("LOCATION" "R257")
		)
		("@s9s_mb_2u_lib.s9s_mb_2u(sch_1):page482_i44@pure_quanta.q_res(chips)"
			("LOCATION" "R258")
		)
		("@s9s_mb_2u_lib.s9s_mb_2u(sch_1):page482_i45@pure_quanta.q_res(chips)"
			("LOCATION" "R259")
		)
		("@s9s_mb_2u_lib.s9s_mb_2u(sch_1):page482_i46@pure_quanta.q_res(chips)"
			("LOCATION" "R260")
		)
		("@s9s_mb_2u_lib.s9s_mb_2u(sch_1):page482_i51@pure_quanta.q_res(chips)"
			("LOCATION" "R517")
		)
		("@s9s_mb_2u_lib.s9s_mb_2u(sch_1):page482_i54@pure_quanta.q_res(chips)"
			("LOCATION" "R695")
		)
		("@s9s_mb_2u_lib.s9s_mb_2u(sch_1):page482_i61@pure_quanta.q_res(chips)"
			("LOCATION" "R1391")
		)
		("@s9s_mb_2u_lib.s9s_mb_2u(sch_1):page482_i62@pure_quanta.q_res(chips)"
			("LOCATION" "R1392")
		)
		("@s9s_mb_2u_lib.s9s_mb_2u(sch_1):page482_i66@pure_quanta.q_res(chips)"
			("LOCATION" "R1393")
		)
		("@s9s_mb_2u_lib.s9s_mb_2u(sch_1):page482_i67@pure_quanta.q_res(chips)"
			("LOCATION" "R1394")
		)
		("@s9s_mb_2u_lib.s9s_mb_2u(sch_1):page481_i101@pure_quanta.q_res(chips)"
			("LOCATION" "R261")
		)
		("@s9s_mb_2u_lib.s9s_mb_2u(sch_1):page481_i100@pure_quanta.q_res(chips)"
			("LOCATION" "R262")
		)
		("@s9s_mb_2u_lib.s9s_mb_2u(sch_1):page481_i125@pure_quanta.q_res(chips)"
			("LOCATION" "R263")
		)
		("@s9s_mb_2u_lib.s9s_mb_2u(sch_1):page481_i98@pure_quanta.q_res(chips)"
			("LOCATION" "R264")
		)
		("@s9s_mb_2u_lib.s9s_mb_2u(sch_1):page481_i97@pure_quanta.q_res(chips)"
			("LOCATION" "R265")
		)
		("@s9s_mb_2u_lib.s9s_mb_2u(sch_1):page481_i96@pure_quanta.q_res(chips)"
			("LOCATION" "R266")
		)
		("@s9s_mb_2u_lib.s9s_mb_2u(sch_1):page481_i95@pure_quanta.q_res(chips)"
			("LOCATION" "R267")
		)
		("@s9s_mb_2u_lib.s9s_mb_2u(sch_1):page481_i94@pure_quanta.q_res(chips)"
			("LOCATION" "R268")
		)
		("@s9s_mb_2u_lib.s9s_mb_2u(sch_1):page481_i93@pure_quanta.q_res(chips)"
			("LOCATION" "R270")
		)
		("@s9s_mb_2u_lib.s9s_mb_2u(sch_1):page481_i92@pure_quanta.q_res(chips)"
			("LOCATION" "R271")
		)
		("@s9s_mb_2u_lib.s9s_mb_2u(sch_1):page481_i90@pure_quanta.q_res(chips)"
			("LOCATION" "R272")
		)
		("@s9s_mb_2u_lib.s9s_mb_2u(sch_1):page481_i89@pure_quanta.q_res(chips)"
			("LOCATION" "R273")
		)
		("@s9s_mb_2u_lib.s9s_mb_2u(sch_1):page481_i88@pure_quanta.q_res(chips)"
			("LOCATION" "R274")
		)
		("@s9s_mb_2u_lib.s9s_mb_2u(sch_1):page481_i68@pure_quanta.q_res(chips)"
			("LOCATION" "R275")
		)
		("@s9s_mb_2u_lib.s9s_mb_2u(sch_1):page481_i66@pure_quanta.q_res(chips)"
			("LOCATION" "R276")
		)
		("@s9s_mb_2u_lib.s9s_mb_2u(sch_1):page481_i62@pure_quanta.q_res(chips)"
			("LOCATION" "R277")
		)
		("@s9s_mb_2u_lib.s9s_mb_2u(sch_1):page481_i61@pure_quanta.q_res(chips)"
			("LOCATION" "R278")
		)
		("@s9s_mb_2u_lib.s9s_mb_2u(sch_1):page481_i54@pure_quanta.q_res(chips)"
			("LOCATION" "R279")
		)
		("@s9s_mb_2u_lib.s9s_mb_2u(sch_1):page481_i57@pure_quanta.q_res(chips)"
			("LOCATION" "R280")
		)
		("@s9s_mb_2u_lib.s9s_mb_2u(sch_1):page481_i58@pure_quanta.q_res(chips)"
			("LOCATION" "R281")
		)
		("@s9s_mb_2u_lib.s9s_mb_2u(sch_1):page481_i53@pure_quanta.q_res(chips)"
			("LOCATION" "R282")
		)
		("@s9s_mb_2u_lib.s9s_mb_2u(sch_1):page481_i147@pure_quanta.q_res(chips)"
			("LOCATION" "R283")
		)
		("@s9s_mb_2u_lib.s9s_mb_2u(sch_1):page481_i148@pure_quanta.q_res(chips)"
			("LOCATION" "R284")
		)
		("@s9s_mb_2u_lib.s9s_mb_2u(sch_1):page481_i150@pure_quanta.q_res(chips)"
			("LOCATION" "R285")
		)
		("@s9s_mb_2u_lib.s9s_mb_2u(sch_1):page481_i151@pure_quanta.q_res(chips)"
			("LOCATION" "R286")
		)
		("@s9s_mb_2u_lib.s9s_mb_2u(sch_1):page481_i152@pure_quanta.q_res(chips)"
			("LOCATION" "R287")
		)
		("@s9s_mb_2u_lib.s9s_mb_2u(sch_1):page481_i119@pure_quanta.q_res(chips)"
			("LOCATION" "R288")
		)
		("@s9s_mb_2u_lib.s9s_mb_2u(sch_1):page481_i118@pure_quanta.q_res(chips)"
			("LOCATION" "R289")
		)
		("@s9s_mb_2u_lib.s9s_mb_2u(sch_1):page481_i135@pure_quanta.q_res(chips)"
			("LOCATION" "R290")
		)
		("@s9s_mb_2u_lib.s9s_mb_2u(sch_1):page481_i116@pure_quanta.q_res(chips)"
			("LOCATION" "R291")
		)
		("@s9s_mb_2u_lib.s9s_mb_2u(sch_1):page481_i69@pure_quanta.q_res(chips)"
			("LOCATION" "R292")
		)
		("@s9s_mb_2u_lib.s9s_mb_2u(sch_1):page481_i70@pure_quanta.q_res(chips)"
			("LOCATION" "R293")
		)
		("@s9s_mb_2u_lib.s9s_mb_2u(sch_1):page481_i71@pure_quanta.q_res(chips)"
			("LOCATION" "R294")
		)
		("@s9s_mb_2u_lib.s9s_mb_2u(sch_1):page481_i72@pure_quanta.q_res(chips)"
			("LOCATION" "R295")
		)
		("@s9s_mb_2u_lib.s9s_mb_2u(sch_1):page481_i139@pure_quanta.q_res(chips)"
			("LOCATION" "R1008")
		)
		("@s9s_mb_2u_lib.s9s_mb_2u(sch_1):page481_i136@pure_quanta.q_res(chips)"
			("LOCATION" "R1009")
		)
		("@s9s_mb_2u_lib.s9s_mb_2u(sch_1):page481_i165@pure_quanta.q_res(chips)"
			("LOCATION" "R1228")
		)
		("@s9s_mb_2u_lib.s9s_mb_2u(sch_1):page481_i169@pure_quanta.q_res(chips)"
			("LOCATION" "R1229")
		)
		("@s9s_mb_2u_lib.s9s_mb_2u(sch_1):page481_i170@pure_quanta.q_res(chips)"
			("LOCATION" "R1230")
		)
		("@s9s_mb_2u_lib.s9s_mb_2u(sch_1):page481_i154@pure_quanta.q_res(chips)"
			("LOCATION" "R1231")
		)
		("@s9s_mb_2u_lib.s9s_mb_2u(sch_1):page481_i156@pure_quanta.q_res(chips)"
			("LOCATION" "R1232")
		)
		("@s9s_mb_2u_lib.s9s_mb_2u(sch_1):page481_i158@pure_quanta.q_res(chips)"
			("LOCATION" "R1233")
		)
		("@s9s_mb_2u_lib.s9s_mb_2u(sch_1):page481_i172@pure_quanta.q_res(chips)"
			("LOCATION" "R1234")
		)
		("@s9s_mb_2u_lib.s9s_mb_2u(sch_1):page481_i176@pure_quanta.q_res(chips)"
			("LOCATION" "R1235")
		)
		("@s9s_mb_2u_lib.s9s_mb_2u(sch_1):page481_i177@pure_quanta.q_res(chips)"
			("LOCATION" "R1236")
		)
		("@s9s_mb_2u_lib.s9s_mb_2u(sch_1):page481_i160@pure_quanta.q_res(chips)"
			("LOCATION" "R1237")
		)
		("@s9s_mb_2u_lib.s9s_mb_2u(sch_1):page481_i161@pure_quanta.q_res(chips)"
			("LOCATION" "R1238")
		)
		("@s9s_mb_2u_lib.s9s_mb_2u(sch_1):page481_i163@pure_quanta.q_res(chips)"
			("LOCATION" "R1239")
		)
		("@s9s_mb_2u_lib.s9s_mb_2u(sch_1):page529_i11@pure_quanta.q_res(chips)"
			("LOCATION" "R367")
		)
		("@s9s_mb_2u_lib.s9s_mb_2u(sch_1):page529_i16@pure_quanta.q_res(chips)"
			("LOCATION" "R369")
		)
		("@s9s_mb_2u_lib.s9s_mb_2u(sch_1):page529_i45@pure_quanta.q_res(chips)"
			("LOCATION" "R371")
		)
		("@s9s_mb_2u_lib.s9s_mb_2u(sch_1):page529_i46@pure_quanta.q_res(chips)"
			("LOCATION" "R372")
		)
		("@s9s_mb_2u_lib.s9s_mb_2u(sch_1):page529_i53@pure_quanta.q_res(chips)"
			("LOCATION" "R373")
		)
		("@s9s_mb_2u_lib.s9s_mb_2u(sch_1):page529_i60@pure_quanta.q_res(chips)"
			("LOCATION" "R374")
		)
		("@s9s_mb_2u_lib.s9s_mb_2u(sch_1):page529_i61@pure_quanta.q_res(chips)"
			("LOCATION" "R375")
		)
		("@s9s_mb_2u_lib.s9s_mb_2u(sch_1):page529_i57@pure_quanta.q_res(chips)"
			("LOCATION" "R376")
		)
		("@s9s_mb_2u_lib.s9s_mb_2u(sch_1):page529_i50@pure_quanta.q_res(chips)"
			("LOCATION" "R377")
		)
		("@s9s_mb_2u_lib.s9s_mb_2u(sch_1):page529_i77@pure_quanta.q_res(chips)"
			("LOCATION" "R378")
		)
		("@s9s_mb_2u_lib.s9s_mb_2u(sch_1):page529_i76@pure_quanta.q_res(chips)"
			("LOCATION" "R379")
		)
		("@s9s_mb_2u_lib.s9s_mb_2u(sch_1):page529_i78@pure_quanta.q_res(chips)"
			("LOCATION" "R380")
		)
		("@s9s_mb_2u_lib.s9s_mb_2u(sch_1):page529_i81@pure_quanta.q_res(chips)"
			("LOCATION" "R381")
		)
		("@s9s_mb_2u_lib.s9s_mb_2u(sch_1):page529_i68@pure_quanta.q_res(chips)"
			("LOCATION" "R502")
		)
		("@s9s_mb_2u_lib.s9s_mb_2u(sch_1):page529_i89@pure_quanta.q_res(chips)"
			("LOCATION" "R1809")
		)
		("@s9s_mb_2u_lib.s9s_mb_2u(sch_1):page529_i88@pure_quanta.q_res(chips)"
			("LOCATION" "R1810")
		)
		("@s9s_mb_2u_lib.s9s_mb_2u(sch_1):page619_i32@pure_quanta.q_res(chips)"
			("LOCATION" "R382")
		)
		("@s9s_mb_2u_lib.s9s_mb_2u(sch_1):page619_i63@pure_quanta.q_res(chips)"
			("LOCATION" "R1220")
		)
		("@s9s_mb_2u_lib.s9s_mb_2u(sch_1):page619_i64@pure_quanta.q_res(chips)"
			("LOCATION" "R1221")
		)
		("@s9s_mb_2u_lib.s9s_mb_2u(sch_1):page619_i57@pure_quanta.q_res(chips)"
			("LOCATION" "R1222")
		)
		("@s9s_mb_2u_lib.s9s_mb_2u(sch_1):page619_i22@pure_quanta.q_res(chips)"
			("LOCATION" "R1298")
		)
		("@s9s_mb_2u_lib.s9s_mb_2u(sch_1):page619_i21@pure_quanta.q_res(chips)"
			("LOCATION" "R1299")
		)
		("@s9s_mb_2u_lib.s9s_mb_2u(sch_1):page619_i31@pure_quanta.q_res(chips)"
			("LOCATION" "R1311")
		)
		("@s9s_mb_2u_lib.s9s_mb_2u(sch_1):page619_i35@pure_quanta.q_res(chips)"
			("LOCATION" "R1315")
		)
		("@s9s_mb_2u_lib.s9s_mb_2u(sch_1):page619_i36@pure_quanta.q_res(chips)"
			("LOCATION" "R1457")
		)
		("@s9s_mb_2u_lib.s9s_mb_2u(sch_1):page619_i44@pure_quanta.q_res(chips)"
			("LOCATION" "R1475")
		)
		("@s9s_mb_2u_lib.s9s_mb_2u(sch_1):page619_i43@pure_quanta.q_res(chips)"
			("LOCATION" "R1476")
		)
		("@s9s_mb_2u_lib.s9s_mb_2u(sch_1):page619_i47@pure_quanta.q_res(chips)"
			("LOCATION" "R1477")
		)
		("@s9s_mb_2u_lib.s9s_mb_2u(sch_1):page619_i50@pure_quanta.q_res(chips)"
			("LOCATION" "R1478")
		)
		("@s9s_mb_2u_lib.s9s_mb_2u(sch_1):page619_i71@pure_quanta.q_res(chips)"
			("LOCATION" "R1496")
		)
		("@s9s_mb_2u_lib.s9s_mb_2u(sch_1):page619_i70@pure_quanta.q_res(chips)"
			("LOCATION" "R1497")
		)
		("@s9s_mb_2u_lib.s9s_mb_2u(sch_1):page619_i76@pure_quanta.q_res(chips)"
			("LOCATION" "R1498")
		)
		("@s9s_mb_2u_lib.s9s_mb_2u(sch_1):page619_i77@pure_quanta.q_res(chips)"
			("LOCATION" "R1499")
		)
		("@s9s_mb_2u_lib.s9s_mb_2u(sch_1):page516_i10@pure_quanta.q_res(chips)"
			("LOCATION" "R496")
		)
		("@s9s_mb_2u_lib.s9s_mb_2u(sch_1):page516_i11@pure_quanta.emmitsburg_rev0p9(chips)"
			("LOCATION" "U4")
		)
		("@s9s_mb_2u_lib.s9s_mb_2u(sch_1):page523_i2@pure_quanta.q_res(chips)"
			("LOCATION" "R497")
		)
		("@s9s_mb_2u_lib.s9s_mb_2u(sch_1):page523_i4@pure_quanta.emmitsburg_rev0p9(chips)"
			("LOCATION" "U4")
		)
		("@s9s_mb_2u_lib.s9s_mb_2u(sch_1):page472_i64@pure_quanta.q_res(chips)"
			("LOCATION" "R499")
		)
		("@s9s_mb_2u_lib.s9s_mb_2u(sch_1):page472_i63@pure_quanta.q_res(chips)"
			("LOCATION" "R500")
		)
		("@s9s_mb_2u_lib.s9s_mb_2u(sch_1):page472_i65@pure_quanta.q_res(chips)"
			("LOCATION" "R501")
		)
		("@s9s_mb_2u_lib.s9s_mb_2u(sch_1):page472_i62@pure_quanta.q_res(chips)"
			("LOCATION" "R915")
		)
		("@s9s_mb_2u_lib.s9s_mb_2u(sch_1):page472_i61@pure_quanta.q_res(chips)"
			("LOCATION" "R916")
		)
		("@s9s_mb_2u_lib.s9s_mb_2u(sch_1):page472_i60@pure_quanta.q_res(chips)"
			("LOCATION" "R917")
		)
		("@s9s_mb_2u_lib.s9s_mb_2u(sch_1):page472_i59@pure_quanta.q_res(chips)"
			("LOCATION" "R918")
		)
		("@s9s_mb_2u_lib.s9s_mb_2u(sch_1):page472_i66@pure_quanta.q_res(chips)"
			("LOCATION" "R1395")
		)
		("@s9s_mb_2u_lib.s9s_mb_2u(sch_1):page535_i28@pure_quanta.q_res(chips)"
			("LOCATION" "R520")
		)
		("@s9s_mb_2u_lib.s9s_mb_2u(sch_1):page535_i123@pure_quanta.q_res(chips)"
			("LOCATION" "R521")
		)
		("@s9s_mb_2u_lib.s9s_mb_2u(sch_1):page535_i129@pure_quanta.q_res(chips)"
			("LOCATION" "R522")
		)
		("@s9s_mb_2u_lib.s9s_mb_2u(sch_1):page535_i128@pure_quanta.q_res(chips)"
			("LOCATION" "R523")
		)
		("@s9s_mb_2u_lib.s9s_mb_2u(sch_1):page535_i136@pure_quanta.q_res(chips)"
			("LOCATION" "R524")
		)
		("@s9s_mb_2u_lib.s9s_mb_2u(sch_1):page535_i135@pure_quanta.q_res(chips)"
			("LOCATION" "R525")
		)
		("@s9s_mb_2u_lib.s9s_mb_2u(sch_1):page535_i137@pure_quanta.q_res(chips)"
			("LOCATION" "R526")
		)
		("@s9s_mb_2u_lib.s9s_mb_2u(sch_1):page535_i138@pure_quanta.q_res(chips)"
			("LOCATION" "R527")
		)
		("@s9s_mb_2u_lib.s9s_mb_2u(sch_1):page535_i217@pure_quanta.q_res(chips)"
			("LOCATION" "R549")
		)
		("@s9s_mb_2u_lib.s9s_mb_2u(sch_1):page535_i218@pure_quanta.q_res(chips)"
			("LOCATION" "R550")
		)
		("@s9s_mb_2u_lib.s9s_mb_2u(sch_1):page535_i220@pure_quanta.q_res(chips)"
			("LOCATION" "R551")
		)
		("@s9s_mb_2u_lib.s9s_mb_2u(sch_1):page535_i219@pure_quanta.q_res(chips)"
			("LOCATION" "R552")
		)
		("@s9s_mb_2u_lib.s9s_mb_2u(sch_1):page535_i169@pure_quanta.q_res(chips)"
			("LOCATION" "R563")
		)
		("@s9s_mb_2u_lib.s9s_mb_2u(sch_1):page535_i170@pure_quanta.q_res(chips)"
			("LOCATION" "R564")
		)
		("@s9s_mb_2u_lib.s9s_mb_2u(sch_1):page535_i167@pure_quanta.q_res(chips)"
			("LOCATION" "R565")
		)
		("@s9s_mb_2u_lib.s9s_mb_2u(sch_1):page535_i168@pure_quanta.q_res(chips)"
			("LOCATION" "R566")
		)
		("@s9s_mb_2u_lib.s9s_mb_2u(sch_1):page535_i166@pure_quanta.q_res(chips)"
			("LOCATION" "R1273")
		)
		("@s9s_mb_2u_lib.s9s_mb_2u(sch_1):page535_i165@pure_quanta.q_res(chips)"
			("LOCATION" "R1274")
		)
		("@s9s_mb_2u_lib.s9s_mb_2u(sch_1):page535_i164@pure_quanta.q_res(chips)"
			("LOCATION" "R1275")
		)
		("@s9s_mb_2u_lib.s9s_mb_2u(sch_1):page535_i163@pure_quanta.q_res(chips)"
			("LOCATION" "R1276")
		)
		("@s9s_mb_2u_lib.s9s_mb_2u(sch_1):page535_i186@pure_quanta.q_res(chips)"
			("LOCATION" "R1277")
		)
		("@s9s_mb_2u_lib.s9s_mb_2u(sch_1):page535_i185@pure_quanta.q_res(chips)"
			("LOCATION" "R1278")
		)
		("@s9s_mb_2u_lib.s9s_mb_2u(sch_1):page535_i190@pure_quanta.q_res(chips)"
			("LOCATION" "R1279")
		)
		("@s9s_mb_2u_lib.s9s_mb_2u(sch_1):page535_i187@pure_quanta.q_res(chips)"
			("LOCATION" "R1280")
		)
		("@s9s_mb_2u_lib.s9s_mb_2u(sch_1):page535_i198@pure_quanta.q_res(chips)"
			("LOCATION" "R1281")
		)
		("@s9s_mb_2u_lib.s9s_mb_2u(sch_1):page535_i199@pure_quanta.q_res(chips)"
			("LOCATION" "R1282")
		)
		("@s9s_mb_2u_lib.s9s_mb_2u(sch_1):page535_i200@pure_quanta.q_res(chips)"
			("LOCATION" "R1283")
		)
		("@s9s_mb_2u_lib.s9s_mb_2u(sch_1):page535_i193@pure_quanta.q_res(chips)"
			("LOCATION" "R1284")
		)
		("@s9s_mb_2u_lib.s9s_mb_2u(sch_1):page533_i124@pure_quanta.q_res(chips)"
			("LOCATION" "R528")
		)
		("@s9s_mb_2u_lib.s9s_mb_2u(sch_1):page533_i125@pure_quanta.q_res(chips)"
			("LOCATION" "R529")
		)
		("@s9s_mb_2u_lib.s9s_mb_2u(sch_1):page533_i126@pure_quanta.q_res(chips)"
			("LOCATION" "R530")
		)
		("@s9s_mb_2u_lib.s9s_mb_2u(sch_1):page533_i127@pure_quanta.q_res(chips)"
			("LOCATION" "R531")
		)
		("@s9s_mb_2u_lib.s9s_mb_2u(sch_1):page533_i116@pure_quanta.q_res(chips)"
			("LOCATION" "R532")
		)
		("@s9s_mb_2u_lib.s9s_mb_2u(sch_1):page533_i115@pure_quanta.q_res(chips)"
			("LOCATION" "R533")
		)
		("@s9s_mb_2u_lib.s9s_mb_2u(sch_1):page533_i114@pure_quanta.q_res(chips)"
			("LOCATION" "R534")
		)
		("@s9s_mb_2u_lib.s9s_mb_2u(sch_1):page533_i113@pure_quanta.q_res(chips)"
			("LOCATION" "R535")
		)
		("@s9s_mb_2u_lib.s9s_mb_2u(sch_1):page533_i109@pure_quanta.q_res(chips)"
			("LOCATION" "R553")
		)
		("@s9s_mb_2u_lib.s9s_mb_2u(sch_1):page533_i110@pure_quanta.q_res(chips)"
			("LOCATION" "R554")
		)
		("@s9s_mb_2u_lib.s9s_mb_2u(sch_1):page533_i152@pure_quanta.q_res(chips)"
			("LOCATION" "R1285")
		)
		("@s9s_mb_2u_lib.s9s_mb_2u(sch_1):page533_i151@pure_quanta.q_res(chips)"
			("LOCATION" "R1286")
		)
		("@s9s_mb_2u_lib.s9s_mb_2u(sch_1):page533_i150@pure_quanta.q_res(chips)"
			("LOCATION" "R1287")
		)
		("@s9s_mb_2u_lib.s9s_mb_2u(sch_1):page533_i149@pure_quanta.q_res(chips)"
			("LOCATION" "R1288")
		)
		("@s9s_mb_2u_lib.s9s_mb_2u(sch_1):page533_i173@pure_quanta.q_res(chips)"
			("LOCATION" "R1357")
		)
		("@s9s_mb_2u_lib.s9s_mb_2u(sch_1):page533_i174@pure_quanta.q_res(chips)"
			("LOCATION" "R1358")
		)
		("@s9s_mb_2u_lib.s9s_mb_2u(sch_1):page533_i175@pure_quanta.q_res(chips)"
			("LOCATION" "R1359")
		)
		("@s9s_mb_2u_lib.s9s_mb_2u(sch_1):page533_i167@pure_quanta.q_res(chips)"
			("LOCATION" "R1360")
		)
		("@s9s_mb_2u_lib.s9s_mb_2u(sch_1):page533_i160@pure_quanta.q_res(chips)"
			("LOCATION" "R1361")
		)
		("@s9s_mb_2u_lib.s9s_mb_2u(sch_1):page533_i159@pure_quanta.q_res(chips)"
			("LOCATION" "R1362")
		)
		("@s9s_mb_2u_lib.s9s_mb_2u(sch_1):page533_i164@pure_quanta.q_res(chips)"
			("LOCATION" "R1363")
		)
		("@s9s_mb_2u_lib.s9s_mb_2u(sch_1):page533_i161@pure_quanta.q_res(chips)"
			("LOCATION" "R1364")
		)
		("@s9s_mb_2u_lib.s9s_mb_2u(sch_1):page466_i21@pure_quanta.q_res(chips)"
			("LOCATION" "R607")
		)
		("@s9s_mb_2u_lib.s9s_mb_2u(sch_1):page466_i36@pure_quanta.q_res(chips)"
			("LOCATION" "R608")
		)
		("@s9s_mb_2u_lib.s9s_mb_2u(sch_1):page466_i39@pure_quanta.q_res(chips)"
			("LOCATION" "R609")
		)
		("@s9s_mb_2u_lib.s9s_mb_2u(sch_1):page466_i40@pure_quanta.q_res(chips)"
			("LOCATION" "R610")
		)
		("@s9s_mb_2u_lib.s9s_mb_2u(sch_1):page466_i43@pure_quanta.q_res(chips)"
			("LOCATION" "R611")
		)
		("@s9s_mb_2u_lib.s9s_mb_2u(sch_1):page466_i44@pure_quanta.q_res(chips)"
			("LOCATION" "R612")
		)
		("@s9s_mb_2u_lib.s9s_mb_2u(sch_1):page466_i18@pure_quanta.q_res(chips)"
			("LOCATION" "R613")
		)
		("@s9s_mb_2u_lib.s9s_mb_2u(sch_1):page466_i23@pure_quanta.q_res(chips)"
			("LOCATION" "R614")
		)
		("@s9s_mb_2u_lib.s9s_mb_2u(sch_1):page466_i51@pure_quanta.q_res(chips)"
			("LOCATION" "R615")
		)
		("@s9s_mb_2u_lib.s9s_mb_2u(sch_1):page466_i54@pure_quanta.q_res(chips)"
			("LOCATION" "R617")
		)
		("@s9s_mb_2u_lib.s9s_mb_2u(sch_1):page466_i53@pure_quanta.q_res(chips)"
			("LOCATION" "R618")
		)
		("@s9s_mb_2u_lib.s9s_mb_2u(sch_1):page466_i48@pure_quanta.q_res(chips)"
			("LOCATION" "R619")
		)
		("@s9s_mb_2u_lib.s9s_mb_2u(sch_1):page466_i55@pure_quanta.q_res(chips)"
			("LOCATION" "R621")
		)
		("@s9s_mb_2u_lib.s9s_mb_2u(sch_1):page466_i56@pure_quanta.q_res(chips)"
			("LOCATION" "R622")
		)
		("@s9s_mb_2u_lib.s9s_mb_2u(sch_1):page466_i13@pure_quanta.q_res(chips)"
			("LOCATION" "R623")
		)
		("@s9s_mb_2u_lib.s9s_mb_2u(sch_1):page466_i14@pure_quanta.q_res(chips)"
			("LOCATION" "R624")
		)
		("@s9s_mb_2u_lib.s9s_mb_2u(sch_1):page530_i32@pure_quanta.q_res(chips)"
			("LOCATION" "R698")
		)
		("@s9s_mb_2u_lib.s9s_mb_2u(sch_1):page530_i5@pure_quanta.q_res(chips)"
			("LOCATION" "R1300")
		)
		("@s9s_mb_2u_lib.s9s_mb_2u(sch_1):page530_i13@pure_quanta.q_res(chips)"
			("LOCATION" "R1306")
		)
		("@s9s_mb_2u_lib.s9s_mb_2u(sch_1):page530_i3@pure_quanta.q_res(chips)"
			("LOCATION" "R1307")
		)
		("@s9s_mb_2u_lib.s9s_mb_2u(sch_1):page530_i10@pure_quanta.q_res(chips)"
			("LOCATION" "R1309")
		)
		("@s9s_mb_2u_lib.s9s_mb_2u(sch_1):page530_i20@pure_quanta.q_res(chips)"
			("LOCATION" "R1310")
		)
		("@s9s_mb_2u_lib.s9s_mb_2u(sch_1):page530_i21@pure_quanta.q_res(chips)"
			("LOCATION" "R1313")
		)
		("@s9s_mb_2u_lib.s9s_mb_2u(sch_1):page530_i27@pure_quanta.q_res(chips)"
			("LOCATION" "R1455")
		)
		("@s9s_mb_2u_lib.s9s_mb_2u(sch_1):page530_i28@pure_quanta.q_res(chips)"
			("LOCATION" "R1456")
		)
		("@s9s_mb_2u_lib.s9s_mb_2u(sch_1):page530_i34@pure_quanta.q_res(chips)"
			("LOCATION" "R1817")
		)
		("@s9s_mb_2u_lib.s9s_mb_2u(sch_1):page476_i34@pure_quanta.q_res(chips)"
			("LOCATION" "R877")
		)
		("@s9s_mb_2u_lib.s9s_mb_2u(sch_1):page476_i59@pure_quanta.q_res(chips)"
			("LOCATION" "R878")
		)
		("@s9s_mb_2u_lib.s9s_mb_2u(sch_1):page476_i63@pure_quanta.q_res(chips)"
			("LOCATION" "R879")
		)
		("@s9s_mb_2u_lib.s9s_mb_2u(sch_1):page476_i61@pure_quanta.q_res(chips)"
			("LOCATION" "R880")
		)
		("@s9s_mb_2u_lib.s9s_mb_2u(sch_1):page476_i71@pure_quanta.q_res(chips)"
			("LOCATION" "R881")
		)
		("@s9s_mb_2u_lib.s9s_mb_2u(sch_1):page476_i72@pure_quanta.q_res(chips)"
			("LOCATION" "R882")
		)
		("@s9s_mb_2u_lib.s9s_mb_2u(sch_1):page476_i73@pure_quanta.q_res(chips)"
			("LOCATION" "R883")
		)
		("@s9s_mb_2u_lib.s9s_mb_2u(sch_1):page476_i74@pure_quanta.q_res(chips)"
			("LOCATION" "R884")
		)
		("@s9s_mb_2u_lib.s9s_mb_2u(sch_1):page476_i81@pure_quanta.q_res(chips)"
			("LOCATION" "R885")
		)
		("@s9s_mb_2u_lib.s9s_mb_2u(sch_1):page476_i82@pure_quanta.q_res(chips)"
			("LOCATION" "R886")
		)
		("@s9s_mb_2u_lib.s9s_mb_2u(sch_1):page476_i83@pure_quanta.q_res(chips)"
			("LOCATION" "R887")
		)
		("@s9s_mb_2u_lib.s9s_mb_2u(sch_1):page476_i84@pure_quanta.q_res(chips)"
			("LOCATION" "R888")
		)
		("@s9s_mb_2u_lib.s9s_mb_2u(sch_1):page476_i86@pure_quanta.q_res(chips)"
			("LOCATION" "R889")
		)
		("@s9s_mb_2u_lib.s9s_mb_2u(sch_1):page476_i85@pure_quanta.q_res(chips)"
			("LOCATION" "R890")
		)
		("@s9s_mb_2u_lib.s9s_mb_2u(sch_1):page476_i87@pure_quanta.q_res(chips)"
			("LOCATION" "R891")
		)
		("@s9s_mb_2u_lib.s9s_mb_2u(sch_1):page476_i76@pure_quanta.q_res(chips)"
			("LOCATION" "R892")
		)
		("@s9s_mb_2u_lib.s9s_mb_2u(sch_1):page476_i104@pure_quanta.q_res(chips)"
			("LOCATION" "R893")
		)
		("@s9s_mb_2u_lib.s9s_mb_2u(sch_1):page476_i105@pure_quanta.q_res(chips)"
			("LOCATION" "R894")
		)
		("@s9s_mb_2u_lib.s9s_mb_2u(sch_1):page476_i106@pure_quanta.q_res(chips)"
			("LOCATION" "R895")
		)
		("@s9s_mb_2u_lib.s9s_mb_2u(sch_1):page476_i107@pure_quanta.q_res(chips)"
			("LOCATION" "R896")
		)
		("@s9s_mb_2u_lib.s9s_mb_2u(sch_1):page476_i109@pure_quanta.q_res(chips)"
			("LOCATION" "R897")
		)
		("@s9s_mb_2u_lib.s9s_mb_2u(sch_1):page476_i108@pure_quanta.q_res(chips)"
			("LOCATION" "R898")
		)
		("@s9s_mb_2u_lib.s9s_mb_2u(sch_1):page476_i110@pure_quanta.q_res(chips)"
			("LOCATION" "R899")
		)
		("@s9s_mb_2u_lib.s9s_mb_2u(sch_1):page476_i111@pure_quanta.q_res(chips)"
			("LOCATION" "R900")
		)
		("@s9s_mb_2u_lib.s9s_mb_2u(sch_1):page476_i112@pure_quanta.q_res(chips)"
			("LOCATION" "R901")
		)
		("@s9s_mb_2u_lib.s9s_mb_2u(sch_1):page476_i113@pure_quanta.q_res(chips)"
			("LOCATION" "R902")
		)
		("@s9s_mb_2u_lib.s9s_mb_2u(sch_1):page476_i114@pure_quanta.q_res(chips)"
			("LOCATION" "R903")
		)
		("@s9s_mb_2u_lib.s9s_mb_2u(sch_1):page476_i115@pure_quanta.q_res(chips)"
			("LOCATION" "R904")
		)
		("@s9s_mb_2u_lib.s9s_mb_2u(sch_1):page476_i116@pure_quanta.q_res(chips)"
			("LOCATION" "R905")
		)
		("@s9s_mb_2u_lib.s9s_mb_2u(sch_1):page476_i117@pure_quanta.q_res(chips)"
			("LOCATION" "R906")
		)
		("@s9s_mb_2u_lib.s9s_mb_2u(sch_1):page476_i118@pure_quanta.q_res(chips)"
			("LOCATION" "R907")
		)
		("@s9s_mb_2u_lib.s9s_mb_2u(sch_1):page476_i119@pure_quanta.q_res(chips)"
			("LOCATION" "R908")
		)
		("@s9s_mb_2u_lib.s9s_mb_2u(sch_1):page476_i145@pure_quanta.q_res(chips)"
			("LOCATION" "R940")
		)
		("@s9s_mb_2u_lib.s9s_mb_2u(sch_1):page476_i146@pure_quanta.q_res(chips)"
			("LOCATION" "R941")
		)
		("@s9s_mb_2u_lib.s9s_mb_2u(sch_1):page476_i147@pure_quanta.q_res(chips)"
			("LOCATION" "R942")
		)
		("@s9s_mb_2u_lib.s9s_mb_2u(sch_1):page476_i148@pure_quanta.q_res(chips)"
			("LOCATION" "R943")
		)
		("@s9s_mb_2u_lib.s9s_mb_2u(sch_1):page476_i153@pure_quanta.q_res(chips)"
			("LOCATION" "R944")
		)
		("@s9s_mb_2u_lib.s9s_mb_2u(sch_1):page476_i154@pure_quanta.q_res(chips)"
			("LOCATION" "R945")
		)
		("@s9s_mb_2u_lib.s9s_mb_2u(sch_1):page476_i156@pure_quanta.q_res(chips)"
			("LOCATION" "R946")
		)
		("@s9s_mb_2u_lib.s9s_mb_2u(sch_1):page476_i157@pure_quanta.q_res(chips)"
			("LOCATION" "R947")
		)
		("@s9s_mb_2u_lib.s9s_mb_2u(sch_1):page549_i9@pure_quanta.q_res(chips)"
			("LOCATION" "R981")
		)
		("@s9s_mb_2u_lib.s9s_mb_2u(sch_1):page549_i10@pure_quanta.q_res(chips)"
			("LOCATION" "R982")
		)
		("@s9s_mb_2u_lib.s9s_mb_2u(sch_1):page549_i13@pure_quanta.q_res(chips)"
			("LOCATION" "R983")
		)
		("@s9s_mb_2u_lib.s9s_mb_2u(sch_1):page549_i15@pure_quanta.q_res(chips)"
			("LOCATION" "R984")
		)
		("@s9s_mb_2u_lib.s9s_mb_2u(sch_1):page549_i21@pure_quanta.q_res(chips)"
			("LOCATION" "R985")
		)
		("@s9s_mb_2u_lib.s9s_mb_2u(sch_1):page549_i25@pure_quanta.q_res(chips)"
			("LOCATION" "R986")
		)
		("@s9s_mb_2u_lib.s9s_mb_2u(sch_1):page549_i24@pure_quanta.q_res(chips)"
			("LOCATION" "R987")
		)
		("@s9s_mb_2u_lib.s9s_mb_2u(sch_1):page549_i23@pure_quanta.q_res(chips)"
			("LOCATION" "R988")
		)
		("@s9s_mb_2u_lib.s9s_mb_2u(sch_1):page549_i74@pure_quanta.q_res(chips)"
			("LOCATION" "R1101")
		)
		("@s9s_mb_2u_lib.s9s_mb_2u(sch_1):page549_i44@pure_quanta.q_res(chips)"
			("LOCATION" "R1423")
		)
		("@s9s_mb_2u_lib.s9s_mb_2u(sch_1):page549_i48@pure_quanta.q_res(chips)"
			("LOCATION" "R1442")
		)
		("@s9s_mb_2u_lib.s9s_mb_2u(sch_1):page549_i49@pure_quanta.q_res(chips)"
			("LOCATION" "R1443")
		)
		("@s9s_mb_2u_lib.s9s_mb_2u(sch_1):page549_i54@pure_quanta.q_res(chips)"
			("LOCATION" "R1444")
		)
		("@s9s_mb_2u_lib.s9s_mb_2u(sch_1):page549_i61@pure_quanta.q_res(chips)"
			("LOCATION" "R1446")
		)
		("@s9s_mb_2u_lib.s9s_mb_2u(sch_1):page549_i68@pure_quanta.q_res(chips)"
			("LOCATION" "R1447")
		)
		("@s9s_mb_2u_lib.s9s_mb_2u(sch_1):page549_i62@pure_quanta.q_res(chips)"
			("LOCATION" "R1448")
		)
		("@s9s_mb_2u_lib.s9s_mb_2u(sch_1):page549_i81@pure_quanta.q_res(chips)"
			("LOCATION" "R1751")
		)
		("@s9s_mb_2u_lib.s9s_mb_2u(sch_1):page549_i82@pure_quanta.q_res(chips)"
			("LOCATION" "R1752")
		)
		("@s9s_mb_2u_lib.s9s_mb_2u(sch_1):page549_i84@pure_quanta.q_res(chips)"
			("LOCATION" "R1753")
		)
		("@s9s_mb_2u_lib.s9s_mb_2u(sch_1):page549_i88@pure_quanta.q_res(chips)"
			("LOCATION" "R1754")
		)
		("@s9s_mb_2u_lib.s9s_mb_2u(sch_1):page549_i96@pure_quanta.q_res(chips)"
			("LOCATION" "R1755")
		)
		("@s9s_mb_2u_lib.s9s_mb_2u(sch_1):page549_i98@pure_quanta.q_res(chips)"
			("LOCATION" "R1756")
		)
		("@s9s_mb_2u_lib.s9s_mb_2u(sch_1):page549_i99@pure_quanta.q_res(chips)"
			("LOCATION" "R1757")
		)
		("@s9s_mb_2u_lib.s9s_mb_2u(sch_1):page549_i91@pure_quanta.q_res(chips)"
			("LOCATION" "R1758")
		)
		("@s9s_mb_2u_lib.s9s_mb_2u(sch_1):page549_i110@pure_quanta.q_res(chips)"
			("LOCATION" "R1811")
		)
		("@s9s_mb_2u_lib.s9s_mb_2u(sch_1):page549_i111@pure_quanta.q_res(chips)"
			("LOCATION" "R1812")
		)
		("@s9s_mb_2u_lib.s9s_mb_2u(sch_1):page549_i115@pure_quanta.q_res(chips)"
			("LOCATION" "R1842")
		)
		("@s9s_mb_2u_lib.s9s_mb_2u(sch_1):page549_i122@pure_quanta.q_res(chips)"
			("LOCATION" "R1843")
		)
		("@s9s_mb_2u_lib.s9s_mb_2u(sch_1):page549_i123@pure_quanta.q_res(chips)"
			("LOCATION" "R1844")
		)
		("@s9s_mb_2u_lib.s9s_mb_2u(sch_1):page549_i127@pure_quanta.q_res(chips)"
			("LOCATION" "R1919")
		)
		("@s9s_mb_2u_lib.s9s_mb_2u(sch_1):page537_i22@pure_quanta.q_res(chips)"
			("LOCATION" "R1010")
		)
		("@s9s_mb_2u_lib.s9s_mb_2u(sch_1):page537_i29@pure_quanta.q_res(chips)"
			("LOCATION" "R1011")
		)
		("@s9s_mb_2u_lib.s9s_mb_2u(sch_1):page537_i10@pure_quanta.q_res(chips)"
			("LOCATION" "R1012")
		)
		("@s9s_mb_2u_lib.s9s_mb_2u(sch_1):page537_i11@pure_quanta.q_res(chips)"
			("LOCATION" "R1013")
		)
		("@s9s_mb_2u_lib.s9s_mb_2u(sch_1):page537_i13@pure_quanta.q_res(chips)"
			("LOCATION" "R1014")
		)
		("@s9s_mb_2u_lib.s9s_mb_2u(sch_1):page537_i12@pure_quanta.q_res(chips)"
			("LOCATION" "R1015")
		)
		("@s9s_mb_2u_lib.s9s_mb_2u(sch_1):page537_i18@pure_quanta.q_res(chips)"
			("LOCATION" "R1016")
		)
		("@s9s_mb_2u_lib.s9s_mb_2u(sch_1):page537_i19@pure_quanta.q_res(chips)"
			("LOCATION" "R1017")
		)
		("@s9s_mb_2u_lib.s9s_mb_2u(sch_1):page537_i20@pure_quanta.q_res(chips)"
			("LOCATION" "R1018")
		)
		("@s9s_mb_2u_lib.s9s_mb_2u(sch_1):page537_i21@pure_quanta.q_res(chips)"
			("LOCATION" "R1019")
		)
		("@s9s_mb_2u_lib.s9s_mb_2u(sch_1):page537_i5@pure_quanta.q_res(chips)"
			("LOCATION" "R1020")
		)
		("@s9s_mb_2u_lib.s9s_mb_2u(sch_1):page537_i6@pure_quanta.q_res(chips)"
			("LOCATION" "R1021")
		)
		("@s9s_mb_2u_lib.s9s_mb_2u(sch_1):page537_i7@pure_quanta.q_res(chips)"
			("LOCATION" "R1022")
		)
		("@s9s_mb_2u_lib.s9s_mb_2u(sch_1):page537_i8@pure_quanta.q_res(chips)"
			("LOCATION" "R1023")
		)
		("@s9s_mb_2u_lib.s9s_mb_2u(sch_1):page479_i9@pure_quanta.q_res(chips)"
			("LOCATION" "R1240")
		)
		("@s9s_mb_2u_lib.s9s_mb_2u(sch_1):page479_i17@pure_quanta.q_res(chips)"
			("LOCATION" "R1241")
		)
		("@s9s_mb_2u_lib.s9s_mb_2u(sch_1):page479_i13@pure_quanta.q_res(chips)"
			("LOCATION" "R1242")
		)
		("@s9s_mb_2u_lib.s9s_mb_2u(sch_1):page479_i19@pure_quanta.q_res(chips)"
			("LOCATION" "R1243")
		)
		("@s9s_mb_2u_lib.s9s_mb_2u(sch_1):page479_i16@pure_quanta.q_res(chips)"
			("LOCATION" "R1244")
		)
		("@s9s_mb_2u_lib.s9s_mb_2u(sch_1):page479_i10@pure_quanta.q_res(chips)"
			("LOCATION" "R1245")
		)
		("@s9s_mb_2u_lib.s9s_mb_2u(sch_1):page541_i51@pure_quanta.q_res(chips)"
			("LOCATION" "R1465")
		)
		("@s9s_mb_2u_lib.s9s_mb_2u(sch_1):page541_i56@pure_quanta.q_res(chips)"
			("LOCATION" "R1467")
		)
		("@s9s_mb_2u_lib.s9s_mb_2u(sch_1):page541_i73@pure_quanta.q_res(chips)"
			("LOCATION" "R1547")
		)
		("@s9s_mb_2u_lib.s9s_mb_2u(sch_1):page541_i55@pure_quanta.q_res(chips)"
			("LOCATION" "R1551")
		)
		("@s9s_mb_2u_lib.s9s_mb_2u(sch_1):page541_i75@pure_quanta.q_res(chips)"
			("LOCATION" "R1556")
		)
		("@s9s_mb_2u_lib.s9s_mb_2u(sch_1):page541_i71@pure_quanta.q_res(chips)"
			("LOCATION" "R1606")
		)
		("@s9s_mb_2u_lib.s9s_mb_2u(sch_1):page541_i84@pure_quanta.q_res(chips)"
			("LOCATION" "R1853")
		)
		("@s9s_mb_2u_lib.s9s_mb_2u(sch_1):page541_i92@pure_quanta.q_res(chips)"
			("LOCATION" "R1931")
		)
		("@s9s_mb_2u_lib.s9s_mb_2u(sch_1):page541_i1@pure_quanta.\\10m25daf484c7g\\(chips)"
			("LOCATION" "U3")
		)
		("@s9s_mb_2u_lib.s9s_mb_2u(sch_1):page15_i35@pure_quanta.q_res(chips)"
			("LOCATION" "R1503")
		)
		("@s9s_mb_2u_lib.s9s_mb_2u(sch_1):page15_i1@pure_quanta.socket4677_azifs035p001c01(chips)"
			("LOCATION" "U2")
		)
		("@s9s_mb_2u_lib.s9s_mb_2u(sch_1):page543_i130@pure_quanta.q_res(chips)"
			("LOCATION" "R1681")
		)
		("@s9s_mb_2u_lib.s9s_mb_2u(sch_1):page543_i28@pure_quanta.\\10m25daf484c7g\\(chips)"
			("LOCATION" "U3")
		)
		("@s9s_mb_2u_lib.s9s_mb_2u(sch_1):page625_i1@pure_quanta.q_res_4p_12(chips)"
			("LOCATION" "R1837")
		)
		("@s9s_mb_2u_lib.s9s_mb_2u(sch_1):page625_i5@pure_quanta.q_res_4p_12(chips)"
			("LOCATION" "R1838")
		)
		("@s9s_mb_2u_lib.s9s_mb_2u(sch_1):page625_i17@pure_quanta.max9634teuk(chips)"
			("LOCATION" "U102")
		)
		("@s9s_mb_2u_lib.s9s_mb_2u(sch_1):page625_i12@pure_quanta.max9634teuk(chips)"
			("LOCATION" "U103")
		)
		("@s9s_mb_2u_lib.s9s_mb_2u(sch_1):page342_i5@pure_quanta.socket4677_azifs035p001c01(chips)"
			("LOCATION" "U1")
		)
		("@s9s_mb_2u_lib.s9s_mb_2u(sch_1):page344_i1@pure_quanta.socket4677_azifs035p001c01(chips)"
			("LOCATION" "U1")
		)
		("@s9s_mb_2u_lib.s9s_mb_2u(sch_1):page345_i2@pure_quanta.socket4677_azifs035p001c01(chips)"
			("LOCATION" "U1")
		)
		("@s9s_mb_2u_lib.s9s_mb_2u(sch_1):page346_i23@pure_quanta.socket4677_azifs035p001c01(chips)"
			("LOCATION" "U1")
		)
		("@s9s_mb_2u_lib.s9s_mb_2u(sch_1):page347_i2@pure_quanta.socket4677_azifs035p001c01(chips)"
			("LOCATION" "U1")
		)
		("@s9s_mb_2u_lib.s9s_mb_2u(sch_1):page348_i91@pure_quanta.socket4677_azifs035p001c01(chips)"
			("LOCATION" "U1")
		)
		("@s9s_mb_2u_lib.s9s_mb_2u(sch_1):page349_i91@pure_quanta.socket4677_azifs035p001c01(chips)"
			("LOCATION" "U1")
		)
		("@s9s_mb_2u_lib.s9s_mb_2u(sch_1):page350_i91@pure_quanta.socket4677_azifs035p001c01(chips)"
			("LOCATION" "U1")
		)
		("@s9s_mb_2u_lib.s9s_mb_2u(sch_1):page351_i7@pure_quanta.socket4677_azifs035p001c01(chips)"
			("LOCATION" "U1")
		)
		("@s9s_mb_2u_lib.s9s_mb_2u(sch_1):page352_i168@pure_quanta.socket4677_azifs035p001c01(chips)"
			("LOCATION" "U1")
		)
		("@s9s_mb_2u_lib.s9s_mb_2u(sch_1):page353_i168@pure_quanta.socket4677_azifs035p001c01(chips)"
			("LOCATION" "U1")
		)
		("@s9s_mb_2u_lib.s9s_mb_2u(sch_1):page354_i20@pure_quanta.socket4677_azifs035p001c01(chips)"
			("LOCATION" "U1")
		)
		("@s9s_mb_2u_lib.s9s_mb_2u(sch_1):page355_i20@pure_quanta.socket4677_azifs035p001c01(chips)"
			("LOCATION" "U1")
		)
		("@s9s_mb_2u_lib.s9s_mb_2u(sch_1):page356_i80@pure_quanta.socket4677_azifs035p001c01(chips)"
			("LOCATION" "U1")
		)
		("@s9s_mb_2u_lib.s9s_mb_2u(sch_1):page356_i69@pure_quanta.socket4677_azifs035p001c01(chips)"
			("LOCATION" "U1")
		)
		("@s9s_mb_2u_lib.s9s_mb_2u(sch_1):page357_i54@pure_quanta.socket4677_azifs035p001c01(chips)"
			("LOCATION" "U1")
		)
		("@s9s_mb_2u_lib.s9s_mb_2u(sch_1):page357_i12@pure_quanta.socket4677_azifs035p001c01(chips)"
			("LOCATION" "U1")
		)
		("@s9s_mb_2u_lib.s9s_mb_2u(sch_1):page358_i18@pure_quanta.socket4677_azifs035p001c01(chips)"
			("LOCATION" "U1")
		)
		("@s9s_mb_2u_lib.s9s_mb_2u(sch_1):page359_i51@pure_quanta.socket4677_azifs035p001c01(chips)"
			("LOCATION" "U1")
		)
		("@s9s_mb_2u_lib.s9s_mb_2u(sch_1):page64_i21@pure_quanta.socket4677_azifs035p001c01(chips)"
			("LOCATION" "U1")
		)
		("@s9s_mb_2u_lib.s9s_mb_2u(sch_1):page65_i16@pure_quanta.socket4677_azifs035p001c01(chips)"
			("LOCATION" "U1")
		)
		("@s9s_mb_2u_lib.s9s_mb_2u(sch_1):page66_i16@pure_quanta.socket4677_azifs035p001c01(chips)"
			("LOCATION" "U1")
		)
		("@s9s_mb_2u_lib.s9s_mb_2u(sch_1):page67_i1@pure_quanta.socket4677_azifs035p001c01(chips)"
			("LOCATION" "U1")
		)
		("@s9s_mb_2u_lib.s9s_mb_2u(sch_1):page67_i3@pure_quanta.socket4677_azifs035p001c01(chips)"
			("LOCATION" "U1")
		)
		("@s9s_mb_2u_lib.s9s_mb_2u(sch_1):page69_i1@pure_quanta.socket4677_azifs035p001c01(chips)"
			("LOCATION" "U1")
		)
		("@s9s_mb_2u_lib.s9s_mb_2u(sch_1):page360_i2@pure_quanta.socket4677_azifs035p001c01(chips)"
			("LOCATION" "U1")
		)
		("@s9s_mb_2u_lib.s9s_mb_2u(sch_1):page360_i5@pure_quanta.socket4677_azifs035p001c01(chips)"
			("LOCATION" "U1")
		)
		("@s9s_mb_2u_lib.s9s_mb_2u(sch_1):page360_i8@pure_quanta.socket4677_azifs035p001c01(chips)"
			("LOCATION" "U1")
		)
		("@s9s_mb_2u_lib.s9s_mb_2u(sch_1):page361_i2@pure_quanta.socket4677_azifs035p001c01(chips)"
			("LOCATION" "U1")
		)
		("@s9s_mb_2u_lib.s9s_mb_2u(sch_1):page361_i5@pure_quanta.socket4677_azifs035p001c01(chips)"
			("LOCATION" "U1")
		)
		("@s9s_mb_2u_lib.s9s_mb_2u(sch_1):page361_i8@pure_quanta.socket4677_azifs035p001c01(chips)"
			("LOCATION" "U1")
		)
		("@s9s_mb_2u_lib.s9s_mb_2u(sch_1):page362_i2@pure_quanta.socket4677_azifs035p001c01(chips)"
			("LOCATION" "U1")
		)
		("@s9s_mb_2u_lib.s9s_mb_2u(sch_1):page362_i5@pure_quanta.socket4677_azifs035p001c01(chips)"
			("LOCATION" "U1")
		)
		("@s9s_mb_2u_lib.s9s_mb_2u(sch_1):page362_i8@pure_quanta.socket4677_azifs035p001c01(chips)"
			("LOCATION" "U1")
		)
		("@s9s_mb_2u_lib.s9s_mb_2u(sch_1):page363_i2@pure_quanta.socket4677_azifs035p001c01(chips)"
			("LOCATION" "U1")
		)
		("@s9s_mb_2u_lib.s9s_mb_2u(sch_1):page363_i5@pure_quanta.socket4677_azifs035p001c01(chips)"
			("LOCATION" "U1")
		)
		("@s9s_mb_2u_lib.s9s_mb_2u(sch_1):page363_i8@pure_quanta.socket4677_azifs035p001c01(chips)"
			("LOCATION" "U1")
		)
		("@s9s_mb_2u_lib.s9s_mb_2u(sch_1):page17_i1@pure_quanta.socket4677_azifs035p001c01(chips)"
			("LOCATION" "U2")
		)
		("@s9s_mb_2u_lib.s9s_mb_2u(sch_1):page18_i1@pure_quanta.socket4677_azifs035p001c01(chips)"
			("LOCATION" "U2")
		)
		("@s9s_mb_2u_lib.s9s_mb_2u(sch_1):page329_i1@pure_quanta.socket4677_azifs035p001c01(chips)"
			("LOCATION" "U2")
		)
		("@s9s_mb_2u_lib.s9s_mb_2u(sch_1):page330_i1@pure_quanta.socket4677_azifs035p001c01(chips)"
			("LOCATION" "U2")
		)
		("@s9s_mb_2u_lib.s9s_mb_2u(sch_1):page331_i169@pure_quanta.socket4677_azifs035p001c01(chips)"
			("LOCATION" "U2")
		)
		("@s9s_mb_2u_lib.s9s_mb_2u(sch_1):page332_i169@pure_quanta.socket4677_azifs035p001c01(chips)"
			("LOCATION" "U2")
		)
		("@s9s_mb_2u_lib.s9s_mb_2u(sch_1):page333_i169@pure_quanta.socket4677_azifs035p001c01(chips)"
			("LOCATION" "U2")
		)
		("@s9s_mb_2u_lib.s9s_mb_2u(sch_1):page24_i169@pure_quanta.socket4677_azifs035p001c01(chips)"
			("LOCATION" "U2")
		)
		("@s9s_mb_2u_lib.s9s_mb_2u(sch_1):page334_i169@pure_quanta.socket4677_azifs035p001c01(chips)"
			("LOCATION" "U2")
		)
		("@s9s_mb_2u_lib.s9s_mb_2u(sch_1):page26_i169@pure_quanta.socket4677_azifs035p001c01(chips)"
			("LOCATION" "U2")
		)
		("@s9s_mb_2u_lib.s9s_mb_2u(sch_1):page27_i169@pure_quanta.socket4677_azifs035p001c01(chips)"
			("LOCATION" "U2")
		)
		("@s9s_mb_2u_lib.s9s_mb_2u(sch_1):page28_i169@pure_quanta.socket4677_azifs035p001c01(chips)"
			("LOCATION" "U2")
		)
		("@s9s_mb_2u_lib.s9s_mb_2u(sch_1):page29_i37@pure_quanta.socket4677_azifs035p001c01(chips)"
			("LOCATION" "U2")
		)
		("@s9s_mb_2u_lib.s9s_mb_2u(sch_1):page29_i176@pure_quanta.socket4677_azifs035p001c01(chips)"
			("LOCATION" "U2")
		)
		("@s9s_mb_2u_lib.s9s_mb_2u(sch_1):page30_i139@pure_quanta.socket4677_azifs035p001c01(chips)"
			("LOCATION" "U2")
		)
		("@s9s_mb_2u_lib.s9s_mb_2u(sch_1):page30_i140@pure_quanta.socket4677_azifs035p001c01(chips)"
			("LOCATION" "U2")
		)
		("@s9s_mb_2u_lib.s9s_mb_2u(sch_1):page31_i139@pure_quanta.socket4677_azifs035p001c01(chips)"
			("LOCATION" "U2")
		)
		("@s9s_mb_2u_lib.s9s_mb_2u(sch_1):page32_i70@pure_quanta.socket4677_azifs035p001c01(chips)"
			("LOCATION" "U2")
		)
		("@s9s_mb_2u_lib.s9s_mb_2u(sch_1):page33_i102@pure_quanta.socket4677_azifs035p001c01(chips)"
			("LOCATION" "U2")
		)
		("@s9s_mb_2u_lib.s9s_mb_2u(sch_1):page34_i102@pure_quanta.socket4677_azifs035p001c01(chips)"
			("LOCATION" "U2")
		)
		("@s9s_mb_2u_lib.s9s_mb_2u(sch_1):page35_i102@pure_quanta.socket4677_azifs035p001c01(chips)"
			("LOCATION" "U2")
		)
		("@s9s_mb_2u_lib.s9s_mb_2u(sch_1):page36_i1@pure_quanta.socket4677_azifs035p001c01(chips)"
			("LOCATION" "U2")
		)
		("@s9s_mb_2u_lib.s9s_mb_2u(sch_1):page36_i7@pure_quanta.socket4677_azifs035p001c01(chips)"
			("LOCATION" "U2")
		)
		("@s9s_mb_2u_lib.s9s_mb_2u(sch_1):page38_i4@pure_quanta.socket4677_azifs035p001c01(chips)"
			("LOCATION" "U2")
		)
		("@s9s_mb_2u_lib.s9s_mb_2u(sch_1):page335_i1@pure_quanta.socket4677_azifs035p001c01(chips)"
			("LOCATION" "U2")
		)
		("@s9s_mb_2u_lib.s9s_mb_2u(sch_1):page335_i9@pure_quanta.socket4677_azifs035p001c01(chips)"
			("LOCATION" "U2")
		)
		("@s9s_mb_2u_lib.s9s_mb_2u(sch_1):page335_i10@pure_quanta.socket4677_azifs035p001c01(chips)"
			("LOCATION" "U2")
		)
		("@s9s_mb_2u_lib.s9s_mb_2u(sch_1):page336_i10@pure_quanta.socket4677_azifs035p001c01(chips)"
			("LOCATION" "U2")
		)
		("@s9s_mb_2u_lib.s9s_mb_2u(sch_1):page336_i11@pure_quanta.socket4677_azifs035p001c01(chips)"
			("LOCATION" "U2")
		)
		("@s9s_mb_2u_lib.s9s_mb_2u(sch_1):page336_i12@pure_quanta.socket4677_azifs035p001c01(chips)"
			("LOCATION" "U2")
		)
		("@s9s_mb_2u_lib.s9s_mb_2u(sch_1):page337_i9@pure_quanta.socket4677_azifs035p001c01(chips)"
			("LOCATION" "U2")
		)
		("@s9s_mb_2u_lib.s9s_mb_2u(sch_1):page337_i10@pure_quanta.socket4677_azifs035p001c01(chips)"
			("LOCATION" "U2")
		)
		("@s9s_mb_2u_lib.s9s_mb_2u(sch_1):page337_i11@pure_quanta.socket4677_azifs035p001c01(chips)"
			("LOCATION" "U2")
		)
		("@s9s_mb_2u_lib.s9s_mb_2u(sch_1):page338_i10@pure_quanta.socket4677_azifs035p001c01(chips)"
			("LOCATION" "U2")
		)
		("@s9s_mb_2u_lib.s9s_mb_2u(sch_1):page338_i11@pure_quanta.socket4677_azifs035p001c01(chips)"
			("LOCATION" "U2")
		)
		("@s9s_mb_2u_lib.s9s_mb_2u(sch_1):page338_i12@pure_quanta.socket4677_azifs035p001c01(chips)"
			("LOCATION" "U2")
		)
		("@s9s_mb_2u_lib.s9s_mb_2u(sch_1):page520_i22@pure_quanta.emmitsburg_rev0p9(chips)"
			("LOCATION" "U4")
		)
		("@s9s_mb_2u_lib.s9s_mb_2u(sch_1):page522_i11@pure_quanta.emmitsburg_rev0p9(chips)"
			("LOCATION" "U4")
		)
		("@s9s_mb_2u_lib.s9s_mb_2u(sch_1):page524_i7@pure_quanta.emmitsburg_rev0p9(chips)"
			("LOCATION" "U4")
		)
		("@s9s_mb_2u_lib.s9s_mb_2u(sch_1):page524_i9@pure_quanta.emmitsburg_rev0p9(chips)"
			("LOCATION" "U4")
		)
	)
)
